G04 ================== begin FILE IDENTIFICATION RECORD ==================*
G04 Layout Name:  D:/<user>/Wistron_project/16342-2/gbr/16342-2.brd*
G04 Film Name:    TSILK*
G04 File Format:  Gerber RS274X*
G04 File Origin:  Cadence Allegro 16.5-S056*
G04 Origin Date:  Mon Aug 07 11:24:23 2017*
G04 *
G04 Layer:  VIA CLASS/FILMMASKTOP*
G04 Layer:  REF DES/ASSEMBLY_TOP*
G04 Layer:  PACKAGE GEOMETRY/SILKSCREEN_TOP*
G04 Layer:  DRAWING FORMAT/LAYER_PCB_STORY*
G04 Layer:  DRAWING FORMAT/LAYER_SILK_T*
G04 Layer:  BOARD GEOMETRY/SILKSCREEN_TOP*
G04 *
G04 Offset:    (0.00 0.00)*
G04 Mirror:    No*
G04 Mode:      Positive*
G04 Rotation:  0*
G04 FullContactRelief:  No*
G04 UndefLineWidth:     6.00*
G04 ================== end FILE IDENTIFICATION RECORD ====================*
%FSLAX35Y35*MOIN*%
%IR0*IPPOS*OFA0.00000B0.00000*MIA0B0*SFA1.00000B1.00000*%
%ADD10C,.01*%
%ADD11C,.02*%
%ADD12C,.012*%
%ADD13C,.013*%
%ADD14C,.015*%
%ADD15C,.016*%
%ADD16C,.018*%
%ADD17C,.019*%
%ADD18C,.002*%
%ADD19C,.006*%
%ADD20C,.008*%
G75*
%LPD*%
G75*
G36*
G01X130165Y459041D02*
Y496550D01*
X155565D01*
Y459041D01*
X130165D01*
G37*
G36*
G01X158044Y496300D02*
X127686D01*
Y459300D01*
X158044D01*
Y496300D01*
G37*
G36*
G01X115750Y510552D02*
Y515552D01*
X118250Y513052D01*
X115750Y510552D01*
G37*
G36*
G01X79564Y652000D02*
Y657000D01*
X74564Y652000D01*
X79564D01*
G37*
G36*
G01X148869Y701045D02*
Y705095D01*
X144819Y701045D01*
X148869D01*
G37*
G36*
G01X202651Y675636D02*
Y681584D01*
G03X204601Y684206I-850J2668D01*
G01X222801D01*
G03X224751Y681584I2800J46D01*
G01Y675636D01*
X202651D01*
G37*
G36*
G01X203500Y662750D02*
X201000Y660250D01*
X206000D01*
X203500Y662750D01*
G37*
G36*
G01X227100Y459041D02*
Y496550D01*
X252500D01*
Y459041D01*
X227100D01*
G37*
G36*
G01X254979Y496300D02*
X224621D01*
Y459300D01*
X254979D01*
Y496300D01*
G37*
G36*
G01X283200Y598200D02*
X272000D01*
Y580800D01*
X283200D01*
Y598200D01*
G37*
G36*
G01X279000Y625500D02*
X284000D01*
X281500Y623000D01*
X279000Y625500D01*
G37*
G36*
G01X353464Y124020D02*
X354864Y125420D01*
X352064D01*
X353464Y124020D01*
G37*
G36*
G01X340411Y215568D02*
Y204368D01*
X357811D01*
Y215568D01*
X340411D01*
G37*
G36*
G01X319993Y192728D02*
X321993Y190728D01*
Y194728D01*
X319993Y192728D01*
G37*
G36*
G01X301996Y379543D02*
Y191717D01*
X309816D01*
Y379543D01*
X301996D01*
G37*
G36*
G01X317524Y578783D02*
Y553143D01*
X302924D01*
Y578783D01*
X317524D01*
G37*
G36*
G01X349364Y623420D02*
X354364Y628420D01*
X349364D01*
Y623420D01*
G37*
G36*
G01X320150Y624750D02*
Y629750D01*
X315150Y624750D01*
X320150D01*
G37*
G36*
G01X309484Y696220D02*
Y701220D01*
X304484Y696220D01*
X309484D01*
G37*
G36*
G01X352700Y710500D02*
X351300Y711900D01*
Y709100D01*
X352700Y710500D01*
G37*
G36*
G01X420655Y122016D02*
G02X422655I1000J0D01*
G01Y120016D01*
G02X420655I-1000J0D01*
G01Y122016D01*
G37*
G36*
G01X559999Y188977D02*
Y143306D01*
X558799D01*
Y185571D01*
X419153D01*
Y119154D01*
X419149D01*
Y117016D01*
X469099D01*
Y112866D01*
X510299D01*
Y117016D01*
X558799D01*
Y143302D01*
X559999D01*
Y112116D01*
X416299D01*
Y188977D01*
X559999D01*
G37*
G36*
G01X396422Y78355D02*
Y73355D01*
X393922Y75855D01*
X396422Y78355D01*
G37*
G36*
G01X374688Y539081D02*
X363488D01*
Y521681D01*
X374688D01*
Y539081D01*
G37*
G36*
G01X374139Y577009D02*
Y546249D01*
X359539D01*
Y577009D01*
X374139D01*
G37*
G36*
G01X375011Y653549D02*
Y650149D01*
X373311Y651849D01*
X375011Y653549D01*
G37*
G36*
G01X370500Y698020D02*
Y672380D01*
X355900D01*
Y698020D01*
X370500D01*
G37*
G36*
G01X454150Y44250D02*
X459150Y49250D01*
X454150D01*
Y44250D01*
G37*
G36*
G01X434828Y122016D02*
G02X436828I1000J0D01*
G01Y120016D01*
G02X434828I-1000J0D01*
G01Y122016D01*
G37*
G36*
G01X449001D02*
G02X451001I1000J0D01*
G01Y120016D01*
G02X449001I-1000J0D01*
G01Y122016D01*
G37*
G36*
G01X463174D02*
G02X465174I1000J0D01*
G01Y120016D01*
G02X463174I-1000J0D01*
G01Y122016D01*
G37*
G36*
G01X427742Y182016D02*
G02X429742I1000J0D01*
G01Y180016D01*
G02X427742I-1000J0D01*
G01Y182016D01*
G37*
G36*
G01X441915D02*
G02X443915I1000J0D01*
G01Y180016D01*
G02X441915I-1000J0D01*
G01Y182016D01*
G37*
G36*
G01X456088D02*
G02X458088I1000J0D01*
G01Y180016D01*
G02X456088I-1000J0D01*
G01Y182016D01*
G37*
G36*
G01X470261D02*
G02X472261I1000J0D01*
G01Y180016D01*
G02X470261I-1000J0D01*
G01Y182016D01*
G37*
G36*
G01X551300Y47148D02*
X553300Y45148D01*
Y49148D01*
X551300Y47148D01*
G37*
G36*
G01X522450Y40848D02*
X524150Y39148D01*
X522450Y37448D01*
Y40848D01*
G37*
G36*
G01X505693Y122016D02*
G02X507693I1000J0D01*
G01Y120016D01*
G02X505693I-1000J0D01*
G01Y122016D01*
G37*
G36*
G01X519866D02*
G02X521866I1000J0D01*
G01Y120016D01*
G02X519866I-1000J0D01*
G01Y122016D01*
G37*
G36*
G01X534039D02*
G02X536039I1000J0D01*
G01Y120016D01*
G02X534039I-1000J0D01*
G01Y122016D01*
G37*
G36*
G01X548212D02*
G02X550212I1000J0D01*
G01Y120016D01*
G02X548212I-1000J0D01*
G01Y122016D01*
G37*
G36*
G01X512780Y182016D02*
G02X514780I1000J0D01*
G01Y180016D01*
G02X512780I-1000J0D01*
G01Y182016D01*
G37*
G36*
G01X526953D02*
G02X528953I1000J0D01*
G01Y180016D01*
G02X526953I-1000J0D01*
G01Y182016D01*
G37*
G36*
G01X541126D02*
G02X543126I1000J0D01*
G01Y180016D01*
G02X541126I-1000J0D01*
G01Y182016D01*
G37*
G36*
G01X555299D02*
G02X557299I1000J0D01*
G01Y180016D01*
G02X555299I-1000J0D01*
G01Y182016D01*
G37*
G36*
G01X596104Y54867D02*
Y49867D01*
X601104Y54867D01*
X596104D01*
G37*
G36*
G01X620500Y315200D02*
Y310200D01*
X640500D01*
Y315200D01*
X620500D01*
G37*
G36*
G01X645921Y422300D02*
X645739Y422057D01*
X645678Y421875D01*
X645495Y421631D01*
X645434Y421449D01*
X645252Y421206D01*
X645191Y421023D01*
X645009Y420780D01*
X644887Y420476D01*
X644704Y420233D01*
X644644Y420050D01*
X644461Y419807D01*
X644400Y419624D01*
X644218Y419381D01*
X644157Y419198D01*
X643975Y418955D01*
X643853Y418651D01*
X643670Y418408D01*
X643610Y418226D01*
X643427Y417982D01*
X643367Y417800D01*
X643184Y417556D01*
X643123Y417374D01*
X642941Y417131D01*
X642880Y416948D01*
X642698Y416705D01*
X642576Y416401D01*
X642393Y416157D01*
X642333Y415975D01*
X642150Y415732D01*
X642089Y415550D01*
X641907Y415306D01*
Y415245D01*
X641785Y415124D01*
X641724Y415185D01*
X641663Y416157D01*
X641603Y416219D01*
X641542Y417374D01*
X641481Y417435D01*
X641420Y418651D01*
X641359Y418712D01*
X641299Y419868D01*
X641238Y419928D01*
X641177Y421145D01*
X641116Y421206D01*
X641056Y422361D01*
X640994Y422422D01*
Y422544D01*
X636129D01*
X636190Y422483D01*
X636251Y421875D01*
X636311Y421814D01*
X636372Y421206D01*
X636433Y421145D01*
X636494Y420597D01*
X636555Y420537D01*
X636616Y419928D01*
X636676Y419868D01*
X636737Y419259D01*
X636798Y419198D01*
X636859Y418651D01*
X636920Y418591D01*
X636980Y417982D01*
X637041Y417921D01*
X637102Y417313D01*
X637163Y417252D01*
X637224Y416705D01*
X637285Y416644D01*
X637345Y416036D01*
X637406Y415975D01*
X637467Y415367D01*
X637528Y415306D01*
X637589Y414759D01*
X637650Y414698D01*
X637710Y414090D01*
X637771Y414029D01*
X637832Y413421D01*
X637893Y413360D01*
X637954Y412813D01*
X638015Y412752D01*
X638075Y412144D01*
X638136Y412083D01*
X638197Y411474D01*
X638257Y411414D01*
X638319Y410867D01*
X638379Y410806D01*
X638440Y410197D01*
X638501Y410137D01*
X638562Y409528D01*
X638622Y409467D01*
X638501Y409224D01*
X638319Y408981D01*
X638197Y408677D01*
X638015Y408433D01*
X637954Y408251D01*
X637771Y408008D01*
X637710Y407826D01*
X637528Y407582D01*
X637467Y407400D01*
X637285Y407156D01*
X637163Y406852D01*
X636980Y406609D01*
X636920Y406426D01*
X636737Y406183D01*
X636676Y406001D01*
X636494Y405757D01*
X636433Y405575D01*
X636251Y405332D01*
X636129Y405028D01*
X635946Y404784D01*
X635886Y404602D01*
X635703Y404359D01*
X635643Y404176D01*
X635460Y403933D01*
X635399Y403750D01*
X635217Y403507D01*
X635095Y403203D01*
X634974Y403081D01*
X640082D01*
X640143Y403264D01*
X640326Y403507D01*
X640386Y403690D01*
X640569Y403933D01*
X640630Y404115D01*
X640812Y404359D01*
X640934Y404663D01*
X641116Y404906D01*
X641177Y405089D01*
X641359Y405332D01*
X641420Y405514D01*
X641603Y405757D01*
X641663Y405940D01*
X641846Y406183D01*
X641968Y406487D01*
X642150Y406731D01*
X642211Y406913D01*
X642393Y407156D01*
X642454Y407339D01*
X642637Y407582D01*
X642698Y407765D01*
X642880Y408008D01*
X642941Y408190D01*
X643123Y408433D01*
X643245Y408738D01*
X643427Y408981D01*
X643488Y409163D01*
X643670Y409407D01*
X643731Y409589D01*
X643914Y409832D01*
X643975Y410015D01*
X644157Y410258D01*
X644279Y410562D01*
X644461Y410806D01*
X644522Y410988D01*
X644704Y411231D01*
X644765Y411414D01*
X644948Y411657D01*
X645009Y411839D01*
X645191Y412083D01*
X645313Y412387D01*
X645495Y412630D01*
X645556Y412813D01*
X645739Y413056D01*
X645799Y413238D01*
X645982Y413481D01*
X646043Y413664D01*
X646225Y413907D01*
X646286Y414090D01*
X646468Y414333D01*
X646590Y414637D01*
X646772Y414880D01*
X646833Y415063D01*
X647016Y415306D01*
X647076Y415489D01*
X647259Y415732D01*
X647320Y415914D01*
X647502Y416157D01*
X647624Y416462D01*
X647806Y416705D01*
X647867Y416887D01*
X648050Y417131D01*
X648110Y417313D01*
X648293Y417556D01*
X648354Y417739D01*
X648536Y417982D01*
X648658Y418286D01*
X648840Y418530D01*
X648901Y418712D01*
X649083Y418955D01*
X649144Y419138D01*
X649327Y419381D01*
X649387Y419563D01*
X649570Y419807D01*
X649692Y420111D01*
X649874Y420354D01*
X649935Y420537D01*
X650117Y420780D01*
X650178Y420962D01*
X650361Y421206D01*
X650422Y421388D01*
X650604Y421631D01*
X650665Y421814D01*
X650847Y422057D01*
X650969Y422361D01*
X651091Y422483D01*
Y422604D01*
X646043D01*
X645921Y422300D01*
G37*
G36*
G01X611741Y421996D02*
X611801Y421935D01*
X611862Y421145D01*
X611923Y421084D01*
X611984Y420354D01*
X612044Y420293D01*
X612106Y419563D01*
X612166Y419503D01*
X612227Y418773D01*
X612288Y418712D01*
X612349Y417982D01*
X612409Y417921D01*
X612470Y417192D01*
X612531Y417131D01*
X612592Y416340D01*
X612653Y416279D01*
X612714Y415550D01*
X612774Y415489D01*
X612835Y414759D01*
X612896Y414698D01*
X612957Y413968D01*
X613018Y413907D01*
X613078Y413178D01*
X613139Y413117D01*
X613200Y412387D01*
X613261Y412326D01*
X613322Y411535D01*
X613383Y411474D01*
X613443Y410745D01*
X613504Y410684D01*
X613565Y409954D01*
X613626Y409893D01*
Y409589D01*
X618126D01*
X618248Y409832D01*
X618431Y410076D01*
X618552Y410380D01*
X618735Y410623D01*
X618856Y410927D01*
X619039Y411170D01*
X619161Y411474D01*
X619343Y411718D01*
X619465Y412022D01*
X619647Y412265D01*
X619769Y412569D01*
X619951Y412813D01*
X620012Y412995D01*
X620194Y413238D01*
X620316Y413543D01*
X620498Y413786D01*
X620620Y414090D01*
X620803Y414333D01*
X620924Y414637D01*
X621107Y414880D01*
X621228Y415185D01*
X621411Y415428D01*
X621532Y415732D01*
X621715Y415975D01*
X621776Y416157D01*
X621958Y416401D01*
X622080Y416705D01*
X622262Y416948D01*
X622445Y417313D01*
X622506Y417252D01*
X622566Y416766D01*
X622627Y416036D01*
X622688Y415671D01*
X622749Y414820D01*
X622809Y414759D01*
X622870Y413664D01*
X622931Y413603D01*
X622992Y412509D01*
X623053Y412448D01*
X623114Y411292D01*
X623174Y411231D01*
X623235Y410137D01*
X623296Y410076D01*
Y409589D01*
X627736D01*
X627857Y409832D01*
X628040Y410076D01*
X628101Y410258D01*
X628283Y410502D01*
X628344Y410684D01*
X628527Y410927D01*
X628587Y411109D01*
X628770Y411353D01*
X628831Y411535D01*
X629013Y411779D01*
X629074Y411961D01*
X629256Y412204D01*
X629317Y412387D01*
X629500Y412630D01*
X629561Y412813D01*
X629743Y413056D01*
X629804Y413238D01*
X629986Y413481D01*
X630108Y413786D01*
X630291Y414029D01*
X630351Y414211D01*
X630533Y414455D01*
X630594Y414637D01*
X630777Y414880D01*
X630838Y415063D01*
X631020Y415306D01*
X631081Y415489D01*
X631263Y415732D01*
X631324Y415914D01*
X631507Y416157D01*
X631568Y416340D01*
X631750Y416583D01*
X631811Y416766D01*
X631993Y417009D01*
X632054Y417192D01*
X632237Y417435D01*
X632297Y417617D01*
X632480Y417861D01*
X632602Y418165D01*
X632784Y418408D01*
X632845Y418591D01*
X633027Y418834D01*
X633088Y419016D01*
X633270Y419259D01*
X633331Y419442D01*
X633514Y419685D01*
X633574Y419868D01*
X633757Y420111D01*
X633818Y420293D01*
X634000Y420537D01*
X634061Y420719D01*
X634244Y420962D01*
X634304Y421145D01*
X634487Y421388D01*
X634548Y421570D01*
X634730Y421814D01*
X634852Y422118D01*
X635034Y422361D01*
X635095Y422483D01*
Y422544D01*
X630047D01*
X629804Y422057D01*
X629743Y421814D01*
X629561Y421510D01*
X629500Y421267D01*
X629378Y421084D01*
X629317Y420841D01*
X629135Y420537D01*
X629074Y420293D01*
X628891Y419989D01*
X628831Y419746D01*
X628709Y419563D01*
X628648Y419320D01*
X628466Y419016D01*
X628405Y418773D01*
X628222Y418469D01*
X628162Y418226D01*
X628040Y418043D01*
X627979Y417800D01*
X627797Y417496D01*
X627736Y417252D01*
X627554Y416948D01*
X627493Y416705D01*
X627371Y416522D01*
X627310Y416279D01*
X627128Y415975D01*
X627067Y415732D01*
X626885Y415428D01*
X626824Y415185D01*
X626702Y415002D01*
X626641Y414759D01*
X626459Y414455D01*
X626398Y414515D01*
X626337Y415489D01*
X626276Y415854D01*
X626215Y416827D01*
X626155Y417192D01*
X626094Y418165D01*
X626033Y418530D01*
X625972Y419503D01*
X625911Y419868D01*
X625850Y420841D01*
X625790Y421206D01*
X625729Y422179D01*
X625668Y422544D01*
X621167D01*
Y422483D01*
X620985Y422239D01*
X620803Y421814D01*
X620620Y421570D01*
X620438Y421145D01*
X620255Y420902D01*
X620073Y420476D01*
X619890Y420233D01*
X619769Y419928D01*
X619586Y419685D01*
X619404Y419259D01*
X619221Y419016D01*
X619039Y418591D01*
X618856Y418347D01*
X618674Y417921D01*
X618491Y417678D01*
X618370Y417374D01*
X618187Y417131D01*
X618005Y416705D01*
X617822Y416462D01*
X617640Y416036D01*
X617457Y415793D01*
X617275Y415367D01*
X617093Y415124D01*
X616971Y414820D01*
X616789Y414576D01*
X616667Y414333D01*
X616606Y414394D01*
X616545Y415732D01*
X616484Y416462D01*
X616424Y417800D01*
X616363Y418530D01*
X616302Y419868D01*
X616241Y420719D01*
X616180Y421935D01*
X616120Y422544D01*
X611680D01*
X611741Y421996D01*
G37*
G36*
G01X605294Y422179D02*
X605233Y422118D01*
X605172Y421631D01*
X605111Y421570D01*
X605050Y421084D01*
X604990Y421023D01*
X604929Y420476D01*
X604868Y420415D01*
X604807Y419928D01*
X604746Y419868D01*
X604685Y419381D01*
X604625Y419320D01*
X604564Y418773D01*
X604503Y418712D01*
X604442Y418226D01*
X604381Y418165D01*
X604320Y417678D01*
X604260Y417617D01*
X604199Y417070D01*
X604138Y417009D01*
X604077Y416522D01*
X604017Y416462D01*
X603956Y415975D01*
X603895Y415914D01*
X603834Y415367D01*
X603773Y415306D01*
X603712Y414820D01*
X603652Y414759D01*
X603591Y414272D01*
X603530Y414211D01*
X603469Y413664D01*
X603408Y413603D01*
X603348Y413117D01*
X603287Y413056D01*
X603226Y412569D01*
X603165Y412509D01*
X603104Y411961D01*
X603043Y411900D01*
X602983Y411414D01*
X602922Y411353D01*
X602861Y410867D01*
X602800Y410806D01*
X602739Y410258D01*
X602678Y410197D01*
X602618Y409711D01*
X602557Y409650D01*
Y409589D01*
X607909D01*
X607970Y409954D01*
X608031Y410015D01*
X608091Y410502D01*
X608152Y410562D01*
X608213Y411109D01*
X608274Y411170D01*
X608335Y411657D01*
X608395Y411718D01*
X608456Y412204D01*
X608517Y412265D01*
X608578Y412813D01*
X608639Y412873D01*
X608700Y413360D01*
X608760Y413421D01*
X608821Y413907D01*
X608882Y413968D01*
X608943Y414515D01*
X609004Y414576D01*
X609065Y415063D01*
X609125Y415124D01*
X609186Y415610D01*
X609247Y415671D01*
X609308Y416219D01*
X609369Y416279D01*
X609430Y416766D01*
X609490Y416827D01*
X609551Y417313D01*
X609612Y417374D01*
X609673Y417861D01*
X609733Y417921D01*
X609794Y418469D01*
X609855Y418530D01*
X609916Y419016D01*
X609977Y419077D01*
X610037Y419563D01*
X610098Y419624D01*
X610159Y420172D01*
X610220Y420233D01*
X610281Y420719D01*
X610342Y420780D01*
X610402Y421267D01*
X610463Y421327D01*
X610524Y421875D01*
X610585Y421935D01*
X610646Y422422D01*
X610707Y422483D01*
Y422544D01*
X605354D01*
X605294Y422179D01*
G37*
G36*
G01X581027Y421814D02*
X581088Y421327D01*
X581148Y421267D01*
X581209Y420537D01*
X581270Y420476D01*
X581331Y419685D01*
X581392Y419624D01*
X581453Y418894D01*
X581513Y418834D01*
X581574Y418104D01*
X581635Y418043D01*
X581696Y417313D01*
X581757Y417252D01*
X581817Y416522D01*
X581878Y416462D01*
X581939Y415671D01*
X582000Y415610D01*
X582061Y414880D01*
X582122Y414820D01*
X582182Y414090D01*
X582243Y414029D01*
X582304Y413299D01*
X582365Y413238D01*
X582426Y412509D01*
X582487Y412448D01*
X582547Y411718D01*
X582608Y411657D01*
X582669Y410867D01*
X582730Y410806D01*
X582791Y410076D01*
X582852Y410015D01*
X582912Y409589D01*
X587352D01*
X587535Y409832D01*
X587656Y410137D01*
X587839Y410380D01*
X587960Y410684D01*
X588143Y410927D01*
X588204Y411109D01*
X588386Y411353D01*
X588507Y411657D01*
X588690Y411900D01*
X588812Y412204D01*
X588994Y412448D01*
X589116Y412752D01*
X589298Y412995D01*
X589359Y413178D01*
X589541Y413421D01*
X589663Y413725D01*
X589846Y413968D01*
X589967Y414272D01*
X590150Y414515D01*
X590271Y414820D01*
X590454Y415063D01*
X590576Y415367D01*
X590758Y415610D01*
X590819Y415793D01*
X591001Y416036D01*
X591123Y416340D01*
X591305Y416583D01*
X591427Y416887D01*
X591609Y417131D01*
Y417192D01*
X591731Y417313D01*
X591792Y417252D01*
X591853Y416157D01*
X591913Y416097D01*
X591974Y415002D01*
X592035Y414941D01*
X592096Y413846D01*
X592157Y413786D01*
X592218Y412630D01*
X592278Y412569D01*
X592339Y411474D01*
X592400Y411414D01*
X592461Y410319D01*
X592522Y410258D01*
X592582Y409589D01*
X597022D01*
X597144Y409893D01*
X597326Y410137D01*
X597387Y410319D01*
X597570Y410562D01*
X597630Y410745D01*
X597813Y410988D01*
X597874Y411170D01*
X598056Y411414D01*
X598178Y411718D01*
X598360Y411961D01*
X598421Y412144D01*
X598604Y412387D01*
X598665Y412569D01*
X598847Y412813D01*
X598907Y412995D01*
X599090Y413238D01*
X599151Y413421D01*
X599333Y413664D01*
X599394Y413846D01*
X599577Y414090D01*
X599637Y414272D01*
X599820Y414515D01*
X599881Y414698D01*
X600063Y414941D01*
X600124Y415124D01*
X600307Y415367D01*
X600428Y415671D01*
X600611Y415914D01*
X600671Y416097D01*
X600854Y416340D01*
X600915Y416522D01*
X601097Y416766D01*
X601158Y416948D01*
X601341Y417192D01*
X601401Y417374D01*
X601584Y417617D01*
X601644Y417800D01*
X601827Y418043D01*
X601888Y418226D01*
X602070Y418469D01*
X602131Y418651D01*
X602313Y418894D01*
X602374Y419077D01*
X602557Y419320D01*
X602678Y419624D01*
X602861Y419868D01*
X602922Y420050D01*
X603104Y420293D01*
X603165Y420476D01*
X603348Y420719D01*
X603408Y420902D01*
X603591Y421145D01*
X603652Y421327D01*
X603834Y421570D01*
X603895Y421753D01*
X604077Y421996D01*
X604138Y422179D01*
X604320Y422422D01*
Y422483D01*
X604381Y422544D01*
X599272D01*
X599212Y422300D01*
X598969Y421875D01*
X598907Y421631D01*
X598725Y421327D01*
X598665Y421084D01*
X598543Y420902D01*
X598482Y420658D01*
X598300Y420354D01*
X598239Y420111D01*
X598056Y419807D01*
X597995Y419563D01*
X597874Y419381D01*
X597813Y419138D01*
X597630Y418834D01*
X597570Y418591D01*
X597387Y418286D01*
X597326Y418043D01*
X597205Y417861D01*
X597144Y417617D01*
X596961Y417313D01*
X596901Y417070D01*
X596718Y416766D01*
X596657Y416522D01*
X596536Y416340D01*
X596475Y416097D01*
X596293Y415793D01*
X596231Y415550D01*
X596049Y415245D01*
X595988Y415002D01*
X595867Y414820D01*
X595806Y414576D01*
X595684Y414455D01*
X595624Y414515D01*
X595563Y415732D01*
X595502Y415793D01*
X595441Y417070D01*
X595380Y417131D01*
X595319Y418408D01*
X595259Y418469D01*
X595198Y419807D01*
X595137Y419868D01*
X595076Y421145D01*
X595015Y421206D01*
X594954Y422483D01*
X594894Y422544D01*
X590393D01*
X590211Y422118D01*
X590028Y421875D01*
X589846Y421449D01*
X589663Y421206D01*
X589481Y420780D01*
X589298Y420537D01*
X589116Y420111D01*
X588933Y419868D01*
X588812Y419563D01*
X588629Y419320D01*
X588447Y418894D01*
X588264Y418651D01*
X588082Y418226D01*
X587899Y417982D01*
X587778Y417678D01*
X587595Y417435D01*
X587413Y417009D01*
X587230Y416766D01*
X587048Y416340D01*
X586865Y416097D01*
X586683Y415671D01*
X586500Y415428D01*
X586379Y415124D01*
X586196Y414880D01*
X586014Y414455D01*
X585893Y414333D01*
X585831Y414394D01*
X585771Y416340D01*
X585710Y416401D01*
X585649Y418408D01*
X585588Y418469D01*
X585528Y420476D01*
X585467Y420537D01*
X585406Y422544D01*
X580905D01*
X581027Y421814D01*
G37*
G36*
G01X638711Y370300D02*
G02I-11811J0D01*
G37*
G36*
G01X608821Y428991D02*
X608335Y428930D01*
X608152Y428808D01*
X607909Y428747D01*
X607666Y428626D01*
X607361Y428382D01*
X607301D01*
X606632Y427652D01*
Y427592D01*
X606449Y427348D01*
X606328Y427105D01*
X606267Y426801D01*
X606206Y426740D01*
X606145Y426132D01*
X606206Y425341D01*
X606267Y425280D01*
X606328Y425037D01*
X606510Y424794D01*
Y424733D01*
X607057Y424246D01*
X607118D01*
X607240Y424125D01*
X607483Y424064D01*
X607544Y424003D01*
X608031Y423943D01*
X608091Y423881D01*
X609065Y423943D01*
X609125Y424003D01*
X609430Y424064D01*
X609490Y424125D01*
X609733Y424186D01*
X609977Y424307D01*
X610342Y424611D01*
X610402D01*
X611072Y425341D01*
X611132Y425524D01*
X611315Y425767D01*
X611376Y426010D01*
X611437Y426071D01*
X611497Y426558D01*
X611558Y426619D01*
X611497Y427531D01*
X611437Y427592D01*
X611376Y427835D01*
X611254Y428078D01*
X610828Y428565D01*
X610585Y428747D01*
X610220Y428930D01*
X609794Y428991D01*
X609733Y429051D01*
X608882D01*
X608821Y428991D01*
G37*
G36*
G01X713744Y418875D02*
Y410875D01*
X722844D01*
Y418875D01*
X713744D01*
G37*
G36*
G01X676087Y422787D02*
X675357Y422726D01*
X675296Y422665D01*
X674871Y422604D01*
X674810Y422544D01*
X674506Y422483D01*
X674324Y422361D01*
X674080Y422300D01*
X673472Y421996D01*
X673168Y421753D01*
X673107D01*
X672742Y421449D01*
X672681D01*
X671769Y420537D01*
X671708Y420597D01*
X671769Y421023D01*
X671830Y421084D01*
X671891Y421570D01*
X671952Y421631D01*
X672012Y422118D01*
X672073Y422179D01*
X672134Y422483D01*
Y422544D01*
X667512D01*
X667451Y422483D01*
X667390Y421996D01*
X667329Y421935D01*
X667269Y421388D01*
X667207Y421327D01*
X667147Y420841D01*
X667086Y420780D01*
X667025Y420293D01*
X666964Y420233D01*
X666904Y419685D01*
X666843Y419624D01*
X666782Y419138D01*
X666721Y419077D01*
X666660Y418591D01*
X666599Y418530D01*
X666539Y418043D01*
X666478Y417982D01*
X666417Y417435D01*
X666356Y417374D01*
X666295Y416887D01*
X666235Y416827D01*
X666174Y416340D01*
X666113Y416279D01*
X666052Y415732D01*
X665991Y415671D01*
X665930Y415185D01*
X665870Y415124D01*
X665809Y414637D01*
X665748Y414576D01*
X665687Y414029D01*
X665626Y413968D01*
X665565Y413481D01*
X665505Y413421D01*
X665444Y412934D01*
X665383Y412873D01*
X665322Y412387D01*
X665261Y412326D01*
X665200Y411779D01*
X665140Y411718D01*
X665079Y411231D01*
X665018Y411170D01*
X664957Y410684D01*
X664896Y410623D01*
X664836Y410076D01*
X664775Y410015D01*
X664714Y409589D01*
X669701D01*
X669762Y409954D01*
X669823Y410015D01*
X669883Y410562D01*
X669944Y410623D01*
X670005Y411109D01*
X670066Y411170D01*
X670127Y411657D01*
X670188Y411718D01*
X670248Y412204D01*
X670309Y412265D01*
X670370Y412752D01*
X670431Y412813D01*
X670492Y413360D01*
X670553Y413421D01*
X670613Y413907D01*
X670674Y413968D01*
X670735Y414455D01*
X670796Y414515D01*
X670857Y415002D01*
X670918Y415063D01*
X670978Y415550D01*
X671039Y415610D01*
X671100Y416036D01*
X671161Y416097D01*
X671222Y416401D01*
X671283Y416462D01*
X671343Y416705D01*
X671404Y416766D01*
X671465Y417009D01*
X671526Y417070D01*
X671587Y417313D01*
X671769Y417556D01*
X671830Y417739D01*
X672073Y418043D01*
Y418104D01*
X672499Y418591D01*
X672560D01*
X672985Y418955D01*
X673350Y419138D01*
X673837Y419198D01*
X673898Y419259D01*
X674506Y419198D01*
X674749Y419016D01*
X674871D01*
Y418894D01*
X674993Y418773D01*
X675053Y418408D01*
X675114Y418347D01*
X675053Y417617D01*
X674993Y417556D01*
X674931Y416948D01*
X674871Y416887D01*
X674810Y416340D01*
X674749Y416279D01*
X674688Y415793D01*
X674628Y415732D01*
X674567Y415185D01*
X674506Y415124D01*
X674445Y414637D01*
X674384Y414576D01*
X674324Y414090D01*
X674263Y414029D01*
X674202Y413481D01*
X674141Y413421D01*
X674080Y412934D01*
X674019Y412873D01*
X673959Y412326D01*
X673898Y412265D01*
X673837Y411779D01*
X673776Y411718D01*
X673715Y411231D01*
X673654Y411170D01*
X673594Y410623D01*
X673533Y410562D01*
X673472Y410076D01*
X673411Y410015D01*
X673350Y409589D01*
X678337D01*
X678398Y410076D01*
X678459Y410137D01*
X678520Y410623D01*
X678581Y410684D01*
X678642Y411231D01*
X678702Y411292D01*
X678763Y411779D01*
X678824Y411839D01*
X678885Y412387D01*
X678946Y412448D01*
X679007Y412934D01*
X679067Y412995D01*
X679128Y413481D01*
X679189Y413543D01*
X679250Y414090D01*
X679311Y414150D01*
X679371Y414637D01*
X679432Y414698D01*
X679493Y415245D01*
X679554Y415306D01*
X679615Y415793D01*
X679676Y415854D01*
X679736Y416401D01*
X679797Y416462D01*
X679858Y416948D01*
X679919Y417009D01*
X679980Y417556D01*
X680041Y417617D01*
X680101Y418226D01*
X680162Y418286D01*
X680223Y419016D01*
X680284Y419077D01*
X680223Y420658D01*
X680162Y420719D01*
X680101Y420962D01*
X680041Y421023D01*
Y421145D01*
X679858Y421388D01*
Y421449D01*
X679432Y421935D01*
X678946Y422361D01*
X678459Y422604D01*
X678155Y422665D01*
X678094Y422726D01*
X677486Y422787D01*
X677425Y422848D01*
X676148D01*
X676087Y422787D01*
G37*
G36*
G01X660639D02*
X659909Y422726D01*
X659848Y422665D01*
X659483Y422604D01*
X659423Y422544D01*
X659119Y422483D01*
X659058Y422422D01*
X658815Y422361D01*
X658754Y422300D01*
X658511Y422239D01*
X658267Y422118D01*
X658024Y421935D01*
X657963D01*
X657659Y421692D01*
X657598D01*
X657112Y421267D01*
X657051D01*
X656382Y420597D01*
X656321Y420658D01*
X656382Y421145D01*
X656443Y421206D01*
X656504Y421692D01*
X656564Y421753D01*
X656625Y422239D01*
X656686Y422300D01*
Y422544D01*
X652064D01*
X652003Y422118D01*
X651942Y422057D01*
X651881Y421510D01*
X651820Y421449D01*
X651759Y420962D01*
X651699Y420902D01*
X651638Y420415D01*
X651577Y420354D01*
X651516Y419807D01*
X651456Y419746D01*
X651394Y419259D01*
X651334Y419198D01*
X651273Y418712D01*
X651212Y418651D01*
X651151Y418165D01*
X651091Y418104D01*
X651030Y417556D01*
X650969Y417496D01*
X650908Y417009D01*
X650847Y416948D01*
X650787Y416462D01*
X650726Y416401D01*
X650665Y415854D01*
X650604Y415793D01*
X650543Y415306D01*
X650482Y415245D01*
X650422Y414759D01*
X650361Y414698D01*
X650300Y414150D01*
X650239Y414090D01*
X650178Y413603D01*
X650117Y413543D01*
X650057Y413056D01*
X649996Y412995D01*
X649935Y412509D01*
X649874Y412448D01*
X649813Y411900D01*
X649752Y411839D01*
X649692Y411353D01*
X649631Y411292D01*
X649570Y410806D01*
X649509Y410745D01*
X649448Y410197D01*
X649387Y410137D01*
X649327Y409650D01*
X649266Y409589D01*
X654314D01*
X654375Y410137D01*
X654435Y410197D01*
X654496Y410684D01*
X654557Y410745D01*
X654618Y411231D01*
X654679Y411292D01*
X654740Y411779D01*
X654800Y411839D01*
X654861Y412326D01*
X654922Y412387D01*
X654983Y412934D01*
X655044Y412995D01*
X655105Y413481D01*
X655165Y413543D01*
X655226Y414029D01*
X655287Y414090D01*
X655348Y414576D01*
X655409Y414637D01*
X655470Y415124D01*
X655530Y415185D01*
X655591Y415671D01*
X655652Y415732D01*
X655713Y416097D01*
X655774Y416157D01*
X655834Y416462D01*
X655895Y416522D01*
X655956Y416827D01*
X656382Y417678D01*
X656625Y417982D01*
Y418043D01*
X657172Y418651D01*
X657476Y418894D01*
X657963Y419138D01*
X658450Y419198D01*
X658511Y419259D01*
X659119Y419198D01*
X659483Y418894D01*
X659605Y418712D01*
X659666Y418226D01*
X659605Y417435D01*
X659544Y417374D01*
X659483Y416827D01*
X659423Y416766D01*
X659362Y416219D01*
X659301Y416157D01*
X659240Y415610D01*
X659180Y415550D01*
X659119Y415063D01*
X659058Y415002D01*
X658997Y414455D01*
X658936Y414394D01*
X658875Y413907D01*
X658815Y413846D01*
X658754Y413360D01*
X658693Y413299D01*
X658632Y412752D01*
X658571Y412691D01*
X658511Y412204D01*
X658450Y412144D01*
X658389Y411596D01*
X658328Y411535D01*
X658267Y411049D01*
X658206Y410988D01*
X658146Y410502D01*
X658085Y410441D01*
X658024Y409893D01*
X657963Y409832D01*
Y409589D01*
X662889D01*
X662950Y409893D01*
X663011Y409954D01*
X663072Y410502D01*
X663133Y410562D01*
X663194Y411049D01*
X663254Y411109D01*
X663315Y411657D01*
X663376Y411718D01*
X663437Y412204D01*
X663498Y412265D01*
X663558Y412752D01*
X663619Y412813D01*
X663680Y413360D01*
X663741Y413421D01*
X663802Y413907D01*
X663863Y413968D01*
X663923Y414515D01*
X663984Y414576D01*
X664045Y415063D01*
X664106Y415124D01*
X664167Y415610D01*
X664228Y415671D01*
X664288Y416219D01*
X664349Y416279D01*
X664410Y416766D01*
X664471Y416827D01*
X664531Y417374D01*
X664593Y417435D01*
X664653Y418043D01*
X664714Y418104D01*
X664775Y418773D01*
X664836Y418834D01*
X664896Y419807D01*
X664836Y420537D01*
X664775Y420597D01*
X664714Y420902D01*
X664653Y420962D01*
X664593Y421206D01*
X664410Y421449D01*
Y421510D01*
X663984Y421996D01*
X663558Y422361D01*
X663194Y422544D01*
X662950Y422604D01*
X662889Y422665D01*
X662464Y422726D01*
X662403Y422787D01*
X661430Y422848D01*
X660700D01*
X660639Y422787D01*
G37*
G36*
G01X670200Y373400D02*
Y375200D01*
X674700D01*
Y373400D01*
X670200D01*
G37*
G36*
G01X661200Y368900D02*
Y370700D01*
X664800D01*
Y368900D01*
X661200D01*
G37*
G36*
G01X670200D02*
Y370700D01*
X672900D01*
Y368900D01*
X670200D01*
G37*
G36*
G01X664800Y364400D02*
Y375200D01*
X666600D01*
Y364400D01*
X664800D01*
G37*
G36*
G01X668400D02*
Y375200D01*
X670200D01*
Y364400D01*
X668400D01*
G37*
G36*
G01X659400D02*
Y375200D01*
X661200D01*
Y364400D01*
X659400D01*
G37*
G36*
G01X683385Y425037D02*
X683507Y424794D01*
X682960D01*
X682899Y424855D01*
X682717Y425280D01*
X682534Y425524D01*
Y425645D01*
X682352Y425706D01*
X681926Y425767D01*
Y424794D01*
X681500D01*
Y426590D01*
X681926D01*
Y426132D01*
X682230D01*
X682838Y426193D01*
X682899Y426375D01*
X682838Y426740D01*
X682656D01*
X682595Y426801D01*
X681926D01*
Y426591D01*
X681500D01*
Y427166D01*
X682656D01*
X683020Y427105D01*
X683264Y426922D01*
X683325Y426680D01*
X683385Y426619D01*
X683325Y426254D01*
X683081Y425950D01*
X682838Y425889D01*
X682777Y425828D01*
X682899Y425706D01*
X682960D01*
X683020Y425645D01*
X683142Y425463D01*
X683203Y425280D01*
X683385Y425037D01*
G37*
G36*
G01X683872Y424307D02*
X683568Y424064D01*
X683325Y424003D01*
X683142Y423881D01*
X682108Y423821D01*
X682048Y423881D01*
X681683Y423943D01*
X681318Y424125D01*
X681074Y424307D01*
X680649Y424794D01*
X680406Y425280D01*
X680344Y426193D01*
X680345Y426199D01*
X680730D01*
X680709Y426010D01*
X680770Y425402D01*
X680892Y425159D01*
X681135Y424855D01*
Y424794D01*
X681561Y424429D01*
X681804Y424307D01*
X682230Y424246D01*
X682291Y424186D01*
X683020Y424246D01*
X683081Y424307D01*
X683325Y424368D01*
X683690Y424672D01*
X684115Y425159D01*
X684176Y425402D01*
X684237Y425463D01*
X684298Y425889D01*
X684237Y426497D01*
X684176Y426558D01*
X684115Y426801D01*
X683811Y427166D01*
Y427287D01*
X683690D01*
X683325Y427592D01*
X683203D01*
X683142Y427652D01*
X682777Y427713D01*
X682717Y427774D01*
X681987Y427713D01*
X681926Y427652D01*
X681683Y427592D01*
X681439Y427409D01*
X681378D01*
X680953Y426922D01*
X680770Y426558D01*
X680730Y426200D01*
X680345D01*
X680406Y426680D01*
X680649Y427166D01*
X680831Y427409D01*
X681318Y427835D01*
X681683Y428017D01*
X682048Y428078D01*
X682108Y428139D01*
X682899D01*
X682960Y428078D01*
X683325Y428017D01*
X683568Y427896D01*
X683872Y427652D01*
X683933D01*
X684359Y427166D01*
X684480Y426922D01*
X684541Y426680D01*
X684602Y426619D01*
X684663Y425524D01*
X684602Y425463D01*
X684541Y425159D01*
X684359Y424794D01*
X683933Y424307D01*
X683872D01*
G37*
G36*
G01X669788Y535099D02*
X671488Y536799D01*
X668088D01*
X669788Y535099D01*
G37*
G36*
G01X770040Y26065D02*
Y28935D01*
X775160D01*
Y26065D01*
X770040D01*
G37*
G36*
G01X768213Y535099D02*
X769913Y536799D01*
X766513D01*
X768213Y535099D01*
G37*
G36*
G01X855822Y177415D02*
X859872D01*
X855822Y181465D01*
Y177415D01*
G37*
G36*
G01X796644Y417875D02*
Y409875D01*
X805744D01*
Y417875D01*
X796644D01*
G37*
G36*
G01X852114Y369549D02*
X856164D01*
X852114Y373599D01*
Y369549D01*
G37*
%LPC*%
G75*
G36*
G01X626900Y359670D02*
X628975Y359875D01*
X630970Y360480D01*
X632805Y361460D01*
X633874Y362340D01*
X631434Y364780D01*
X631004D01*
X630906Y364788D01*
X630205Y365000D01*
X629880Y365175D01*
Y364780D01*
X628280D01*
Y367935D01*
X625563Y370652D01*
X625155Y370320D01*
X624519Y369979D01*
X623863Y369780D01*
X621305D01*
Y364780D01*
X619735D01*
Y376480D01*
X618940Y377274D01*
X618060Y376205D01*
X617080Y374370D01*
X616475Y372375D01*
X616270Y370300D01*
X616475Y368225D01*
X617080Y366230D01*
X618060Y364395D01*
X619385Y362785D01*
X620995Y361460D01*
X622830Y360480D01*
X624825Y359875D01*
X626900Y359670D01*
G37*
G36*
G01X634859Y363325D02*
X635740Y364395D01*
X636720Y366230D01*
X637325Y368225D01*
X637530Y370300D01*
X637325Y372375D01*
X636720Y374370D01*
X635740Y376205D01*
X634415Y377815D01*
X632805Y379140D01*
X630970Y380120D01*
X628975Y380725D01*
X626900Y380930D01*
X624825Y380725D01*
X622830Y380120D01*
X620995Y379140D01*
X619924Y378258D01*
X621166Y377015D01*
X623555D01*
X623829Y376980D01*
X624520Y376770D01*
X625155Y376430D01*
X625715Y375975D01*
X626170Y375415D01*
X626510Y374780D01*
X626720Y374090D01*
X626790Y373375D01*
X626720Y372660D01*
X626510Y371970D01*
X626406Y371777D01*
X628280Y369903D01*
Y376820D01*
X629880D01*
Y372765D01*
X630205Y372940D01*
X630900Y373150D01*
X631625Y373220D01*
X632350Y373150D01*
X633045Y372940D01*
X633685Y372595D01*
X634245Y372135D01*
X634705Y371575D01*
X635050Y370935D01*
X635259Y370242D01*
X635330Y369515D01*
Y368425D01*
X635260Y367700D01*
X635050Y367005D01*
X634705Y366365D01*
X634245Y365805D01*
X633685Y365345D01*
X633135Y365049D01*
X634859Y363325D01*
G37*
G36*
G01X631935Y366249D02*
X632055Y366260D01*
X632471Y366390D01*
X632853Y366592D01*
X633189Y366869D01*
X633462Y367203D01*
X633663Y367584D01*
X633791Y367998D01*
X633830Y368425D01*
Y369515D01*
X633792Y369945D01*
X633660Y370360D01*
X633460Y370740D01*
X633185Y371075D01*
X632850Y371351D01*
X632468Y371551D01*
X632053Y371680D01*
X631626Y371720D01*
X631196Y371680D01*
X630780Y371550D01*
X630400Y371350D01*
X630065Y371075D01*
X629880Y370850D01*
Y368303D01*
X631935Y366249D01*
G37*
G36*
G01X621305Y371355D02*
X623915D01*
X623945Y371365D01*
X624325Y371565D01*
X624507Y371708D01*
X621305Y374910D01*
Y371355D01*
G37*
G36*
G01X625246Y372936D02*
X625250Y372950D01*
X625290Y373375D01*
X625250Y373800D01*
X625125Y374205D01*
X624925Y374585D01*
X624655Y374915D01*
X624325Y375185D01*
X623945Y375385D01*
X623860Y375415D01*
X622766D01*
X625246Y372936D01*
G37*
%LPD*%
G75*
G54D10*
G01X348587Y103000D02*
Y105400D01*
G01X370620Y51600D02*
Y54000D01*
G01Y47000D02*
Y49400D01*
G01X373200Y60250D02*
X370800D01*
G01X370320Y85100D02*
Y87500D01*
G01Y80500D02*
Y82900D01*
G01X370800Y73950D02*
X373200D01*
G01X554438Y763780D02*
G03X564911I5236J0D01*
G01X617428D02*
G03X627901I5237J0D01*
G01X585933D02*
G03X596406I5236J0D01*
G01X711914D02*
G03X722386I5236J0D01*
G01X680419D02*
G03X690891I5236J0D01*
G01X648924D02*
G03X659396I5236J0D01*
G01X847835Y262795D02*
X887205D01*
Y223425D01*
X847835D01*
Y262795D01*
G01X800000Y574803D02*
X839370D01*
Y614173D01*
X800000D01*
Y574803D01*
G01X846457Y679134D02*
X885827D01*
Y718504D01*
X846457D01*
G54D20*
G01X32000Y51500D02*
X36000D01*
G01X71768Y61755D02*
X75768D01*
G01X133900Y627100D02*
X129900D01*
G01X71427Y692785D02*
X75427D01*
G01X125300Y640500D02*
X129300D01*
G01X113619Y709995D02*
X117619D01*
G01X171949Y691015D02*
Y689915D01*
G01Y693715D02*
Y692615D01*
G01X247824Y631614D02*
Y627614D01*
G01X281032Y733436D02*
X285032D01*
G01X343034Y125612D02*
X347034D01*
G01X342034Y115112D02*
X338034D01*
G01X347034D02*
X343034D01*
G01X304724Y553463D02*
Y579963D01*
X303224D01*
G01X315724Y553463D02*
X304724D01*
G01X315724Y579963D02*
Y553463D01*
G01Y579963D02*
X294224D01*
G01X310224Y576463D02*
X313724Y579963D01*
G01X310224Y576463D02*
X306724Y579963D01*
G01X292018Y662782D02*
X296018D01*
G01X350180Y639214D02*
X354180D01*
G01X368700Y699200D02*
X347200D01*
G01X360682Y183174D02*
Y187174D01*
G01X372220Y583586D02*
X368220D01*
G01X363200Y695700D02*
X366700Y699200D01*
G01X363200Y695700D02*
X359700Y699200D01*
G01X357700Y672700D02*
Y699200D01*
X356200D01*
G01X368700Y672700D02*
X357700D01*
G01X368700Y699200D02*
Y672700D01*
G01X453288Y52522D02*
Y56522D01*
G01X436055Y45144D02*
Y49144D01*
G01X436057Y40488D02*
Y44488D01*
G01X436046Y49800D02*
Y53800D01*
G01X509855Y25202D02*
X510955D01*
G01X507155D02*
X508255D01*
G01X506381Y25199D02*
X502381D01*
G01X537108Y72041D02*
X541108D01*
G01X576604Y57767D02*
X575504D01*
G01X579304D02*
X578204D01*
G01X639347Y60207D02*
X643347D01*
G01X633781Y60211D02*
X629781D01*
G01X582104Y43967D02*
Y47967D01*
G01X606247Y28307D02*
Y32307D01*
G01X598147Y66207D02*
X597047D01*
G01X600847D02*
X599747D01*
G01X601747Y64907D02*
X605747D01*
G01X784100Y25800D02*
Y26900D01*
G01Y23100D02*
Y24200D01*
G01X784200Y29000D02*
Y27900D01*
G01Y31700D02*
Y30600D01*
G01X831772Y174677D02*
X830672D01*
G01X834472D02*
X833372D01*
G01X843122Y158314D02*
Y162314D01*
G01X851422Y143014D02*
Y147014D01*
G01X847506Y338240D02*
Y342240D01*
G01X823568Y370219D02*
Y369118D01*
G01Y372920D02*
Y371819D01*
G01X848820Y368572D02*
Y364572D01*
G01X863968Y212564D02*
Y208564D01*
G01X860320Y407672D02*
Y403672D01*
G54D11*
G01X-36569Y-23804D02*
Y-103804D01*
G01D02*
X1258031D01*
G01X-40569Y-7804D02*
G02I-12000J0D01*
G01X-45719D02*
G02I-6850J0D01*
G01X-52569Y-23804D02*
Y8196D01*
G01X-36569Y-23804D02*
X1258031D01*
G01X-36569Y-59304D02*
X1258031D01*
G01X-36569Y-7804D02*
X-68569D01*
G01X59859Y583825D02*
Y590125D01*
X66159D01*
G01X62812Y581857D02*
Y588157D01*
X69112D01*
G01X95964Y510452D02*
X91314D01*
G01X128100Y627000D02*
X123100D01*
G01X94654Y641650D02*
Y636650D01*
G01X90783Y676624D02*
Y671624D01*
G01Y684524D02*
Y679524D01*
G01X94654Y649550D02*
Y644550D01*
G01X89050Y658354D02*
X94050D01*
G01X81250Y658454D02*
X86250D01*
G01X114649Y734515D02*
X119649D01*
G01X106949D02*
X111949D01*
G01X122320Y736191D02*
X127320D01*
G01X91520Y734491D02*
X96520D01*
G01X99249Y734515D02*
X104249D01*
G01X155565Y456500D02*
X165665D01*
G01X167365Y447400D02*
X157265D01*
G01X214300Y713900D02*
X209300D01*
G01X206220Y742991D02*
X189620D01*
G01X252500Y456500D02*
X262600D01*
G01X264300Y447400D02*
X254200D01*
G01X220197Y609568D02*
X226497D01*
Y603268D01*
G01X280600Y662000D02*
X274600D01*
G01X222100Y713900D02*
X217100D01*
G01X326540Y621900D02*
Y616900D01*
G01X329936Y631304D02*
X334936D01*
G01X326540Y614000D02*
Y609000D01*
G01X322136Y631404D02*
X327136D01*
G01X351839Y578269D02*
X361339Y578279D01*
G01X294224Y579963D02*
X303224D01*
G01X306736Y662204D02*
X311736D01*
G01X314636D02*
X319636D01*
G01X324574Y686770D02*
Y681770D01*
G01X311370Y702974D02*
X316370D01*
G01X319170Y702874D02*
X324170D01*
G01X324574Y694470D02*
Y689470D01*
G01X347200Y699200D02*
X356200D01*
G01X303870Y734974D02*
X308870D01*
G01X295970D02*
X300970D01*
G01X359400Y130400D02*
X376000D01*
G01X369705Y238115D02*
Y229015D01*
G01X365589Y518269D02*
X357589D01*
G01X470531Y-23804D02*
Y-103804D01*
G01X535548Y59931D02*
X526448D01*
G01X608031Y-23804D02*
Y-103804D01*
G01X617047Y79907D02*
Y74907D01*
G01Y71807D02*
Y66807D01*
G01X572805Y219190D02*
X815162D01*
Y252002D01*
X846204D01*
G01X864250Y264431D02*
Y282275D01*
X572805D01*
Y219190D01*
G01X666347Y36107D02*
X661347D01*
G01X658347D02*
X653347D01*
G01X711294Y410575D02*
Y402875D01*
G01X723031Y-23804D02*
Y-103804D01*
G01X778600Y28935D02*
Y34675D01*
G01X794194Y409575D02*
Y401875D01*
G01X890531Y-23804D02*
Y-103804D01*
G01X901122Y72714D02*
X896122D01*
G01X893122D02*
X888122D01*
G01X885122D02*
X880122D01*
G01X893672Y102838D02*
Y119438D01*
G01Y82338D02*
Y98938D01*
G01X889292Y211635D02*
Y206635D01*
G01X892113Y203850D02*
Y198850D01*
G01X889292Y219335D02*
Y214335D01*
G01X867201Y291508D02*
Y274908D01*
G01Y312008D02*
Y295408D01*
G01X896991Y402239D02*
X901991D01*
G01X889294Y402241D02*
X894294D01*
G01X881602Y402256D02*
X886602D01*
G01X1060531Y-23804D02*
Y-103804D01*
G01X1258031Y-23804D02*
Y-103804D01*
G01X1286031Y-7804D02*
G02I-12000J0D01*
G01X1280881D02*
G02I-6850J0D01*
G01X1274031Y-23804D02*
Y8196D01*
G01X1290031Y-7804D02*
X1258031D01*
G54D12*
G01X65224Y34449D02*
G02I-4200J0D01*
G01X37664D02*
G02I-4200J0D01*
G01X60302Y24606D02*
G02I-4200J0D01*
G01X42586D02*
G02I-4200J0D01*
G01X112468Y44292D02*
G02I-4200J0D01*
G01X107546Y34449D02*
G02I-4200J0D01*
G01X89830D02*
G02I-4200J0D01*
G01X84908Y44292D02*
G02I-4200J0D01*
G01X177389Y669291D02*
G02I-14200J0D01*
G01X357043Y62913D02*
G02I-3500J0D01*
G01X349957Y57007D02*
G02I-3500J0D01*
G01X357043Y55039D02*
G02I-3500J0D01*
G01D02*
G02I-3500J0D01*
G01X349957Y57007D02*
G02I-3500J0D01*
G01X343731Y47253D02*
G02X334931I-4400J0D01*
G01D02*
Y52353D01*
G01D02*
G02X343731I4400J0D01*
G01D02*
Y47253D01*
G01Y90729D02*
G02X334931I-4400J0D01*
G01D02*
Y93129D01*
G01D02*
G02X343731I4400J0D01*
G01D02*
Y90729D01*
G01X357022Y86917D02*
G02X356329Y88653I-3479J-382D01*
G01X349957Y84567D02*
G02I-3500J0D01*
G01X357043Y78661D02*
G02I-3500J0D01*
G01X349957Y74724D02*
G02I-3500J0D01*
G01X357043Y70787D02*
G02I-3500J0D01*
G01X349957Y66850D02*
G02I-3500J0D01*
G01X365069Y51003D02*
Y48603D01*
G01D02*
G02X356269I-4400J0D01*
G01D02*
Y51003D01*
G01D02*
G02X365069I4400J0D01*
G01Y94479D02*
Y89379D01*
G01X356329Y88653D02*
G02X356269Y89379I4340J724D01*
G01D02*
Y94479D01*
G01D02*
G02X365069I4400J0D01*
G01Y89379D02*
G02X357022Y86917I-4400J0D01*
G01X824924Y24409D02*
G02I-3900J0D01*
G01X814924D02*
G02I-3900J0D01*
G01X804924D02*
G02I-3900J0D01*
G54D13*
G01X125200Y511400D02*
X121600D01*
Y515300D01*
G01X96564Y510852D02*
Y509002D01*
G01X90664Y510852D02*
Y509002D01*
G01X202551Y665571D02*
X204851D01*
G01X280333Y621667D02*
X283933D01*
Y617767D01*
G01X251131Y696624D02*
X253981D01*
Y693924D01*
G01X271200Y682500D02*
X268350D01*
Y685200D01*
G01X263531Y696424D02*
X266381D01*
Y693724D01*
G01X349700Y118800D02*
Y122800D01*
X355500D01*
G01X320056Y193705D02*
Y191705D01*
G01X308412Y593391D02*
Y596241D01*
X311112D01*
G01X341600Y591400D02*
Y588550D01*
X338900D01*
G01X353500Y709500D02*
Y713500D01*
X359300D01*
G01X394108Y76649D02*
Y75149D01*
G01X369135Y213899D02*
X371985D01*
Y211199D01*
G01X370100Y483400D02*
X367250D01*
Y486100D01*
G01X369161Y655349D02*
X373361D01*
Y651449D01*
G01X544345Y44198D02*
X550345D01*
Y49548D01*
G01X526493Y38433D02*
Y39933D01*
G01X668799Y535386D02*
X670799D01*
G01X767224D02*
X769224D01*
G54D14*
G01X120197Y74016D02*
Y43308D01*
G01X219213Y433268D02*
X188504D01*
G01X264050Y599850D02*
X271800D01*
G01X287520Y74016D02*
Y43308D01*
G01X338761Y196418D02*
Y204168D01*
G01X355538Y540731D02*
X363288D01*
G01X408268Y379088D02*
Y348379D01*
G01Y688303D02*
Y719012D01*
G01X568110Y292684D02*
Y261975D01*
G01Y292684D02*
Y261975D01*
G01Y581748D02*
Y551040D01*
G01X846457Y709449D02*
Y740158D01*
G54D15*
G01X44600Y45000D02*
X41400D01*
G01X84368Y55255D02*
X81168D01*
G01X304619Y525094D02*
X311319D01*
G54D16*
G01X677500Y370700D02*
G03I-10900J0D01*
G54D17*
G01X283945Y544394D02*
X280545D01*
G54D18*
G01X623670Y320290D02*
X623010D01*
G01X623110Y320380D02*
X623770D01*
G01X623860Y320490D02*
X623210D01*
G01X623310Y320580D02*
X623960D01*
G01X624060Y320690D02*
X623400D01*
G01X623500Y320790D02*
X624150D01*
G01X624250Y320880D02*
X623600D01*
G01X623690Y320990D02*
X624350D01*
G01X624440Y321080D02*
X623790D01*
G01X623880Y321190D02*
X624540D01*
G01X624640Y321290D02*
X623980D01*
G01X624080Y321380D02*
X624730D01*
G01X624830Y321490D02*
X624185D01*
G01X624180D02*
X624230D01*
G01X624270Y321580D02*
X624310D01*
G01X624270D02*
X624920D01*
G01X625020Y321690D02*
X624370D01*
G01X624470Y321790D02*
X625120D01*
G01X625220Y321880D02*
X624560D01*
G01X624660Y321990D02*
X625310D01*
G01X625410Y322080D02*
X624750D01*
G01X624850Y322190D02*
X625510D01*
G01X625600Y322290D02*
X624950D01*
G01X625050Y322380D02*
X625700D01*
G01X625790Y322490D02*
X625140D01*
G01X625240Y322580D02*
X625890D01*
G01X625990Y322690D02*
X625330D01*
G01X625430Y322790D02*
X626090D01*
G01X626180Y322880D02*
X625530D01*
G01X625620Y322990D02*
X626280D01*
G01X626470Y323190D02*
X625820D01*
G01X626010Y323380D02*
X626660D01*
G01X621370Y337800D02*
X621400Y337820D01*
G01X621370Y337260D02*
Y337800D01*
G01X621380Y337240D02*
X621370Y337260D01*
G01X621430Y337130D02*
X621380Y337240D01*
G01X621440Y337120D02*
X621430Y337130D01*
G01X626620Y331530D02*
X621440Y337120D01*
G01X621370Y337790D02*
X621430D01*
G01X621370Y337690D02*
X621520D01*
G01X621610Y337580D02*
X621370D01*
G01Y337490D02*
X621710D01*
G01X621800Y337380D02*
X621370D01*
G01Y337290D02*
X621890D01*
G01X621990Y337190D02*
X621400D01*
G01X621470Y337080D02*
X622080D01*
G01X622170Y336990D02*
X621560D01*
G01X621650Y336880D02*
X622260D01*
G01X622360Y336790D02*
X621750D01*
G01X621840Y336690D02*
X622450D01*
G01X622540Y336580D02*
X621930D01*
G01X622020Y336490D02*
X622640D01*
G01X622730Y336380D02*
X622120D01*
G01X622210Y336290D02*
X622820D01*
G01X622920Y336190D02*
X622300D01*
G01X622400Y336080D02*
X623010D01*
G01X623100Y335990D02*
X622490D01*
G01X622580Y335880D02*
X623200D01*
G01X623290Y335790D02*
X622680D01*
G01X622770Y335690D02*
X623380D01*
G01X623480Y335580D02*
X622860D01*
G01X622950Y335490D02*
X623570D01*
G01X623660Y335380D02*
X623050D01*
G01X623140Y335290D02*
X623750D01*
G01X623850Y335190D02*
X623230D01*
G01X623330Y335080D02*
X623940D01*
G01X624030Y334990D02*
X623420D01*
G01X623510Y334880D02*
X624120D01*
G01X624220Y334790D02*
X623610D01*
G01X623700Y334690D02*
X624310D01*
G01X624400Y334580D02*
X623790D01*
G01X623880Y334490D02*
X624500D01*
G01X624590Y334380D02*
X623980D01*
G01X624070Y334290D02*
X624680D01*
G01X624780Y334190D02*
X624160D01*
G01X624250Y334080D02*
X624870D01*
G01X624960Y333990D02*
X624350D01*
G01X624440Y333880D02*
X625060D01*
G01X625150Y333790D02*
X624530D01*
G01X624620Y333690D02*
X625240D01*
G01X625340Y333580D02*
X624720D01*
G01X624810Y333490D02*
X625430D01*
G01X625520Y333380D02*
X624900D01*
G01X624990Y333290D02*
X625620D01*
G01X625710Y333190D02*
X625090D01*
G01X625180Y333080D02*
X625800D01*
G01X625890Y332990D02*
X625270D01*
G01X625370Y332880D02*
X625990D01*
G01X626080Y332790D02*
X625460D01*
G01X625550Y332690D02*
X626170D01*
G01X626270Y332580D02*
X625650D01*
G01X625830Y332380D02*
X627070D01*
G01X627080Y332190D02*
X626020D01*
G01X625770Y334480D02*
X626280D01*
G01X625730Y334440D02*
X625770Y334480D01*
G01X625730Y333980D02*
Y334440D01*
G01X625770Y333940D02*
X625730Y333980D01*
G01Y334380D02*
X635980D01*
G01X635910Y334190D02*
X625730D01*
G01Y333990D02*
X635750D01*
G01X628380Y335290D02*
X626950D01*
G01X626370Y334550D02*
X626280Y334480D01*
G01X626390Y334600D02*
X626370Y334550D01*
G01X626390Y334610D02*
Y334600D01*
G01X626510Y334860D02*
X626390Y334610D01*
G01X626530Y334870D02*
X626510Y334860D01*
G01X626960Y335290D02*
X626530Y334870D01*
G01X626290Y334490D02*
X627020D01*
G01X627130Y334820D02*
X627240Y334890D01*
G01X626960Y334650D02*
X627130Y334820D01*
G01X626940Y334540D02*
X626960Y334650D01*
G01X627030Y334480D02*
X626940Y334540D01*
G01X627100Y334790D02*
X626480D01*
G01X626430Y334690D02*
X627000D01*
G01X626950Y334580D02*
X626380D01*
G01X626640Y334990D02*
X628320D01*
G01Y335190D02*
X626850D01*
G01X627200Y331590D02*
X630430Y328110D01*
G01X627190Y331590D02*
X627200D01*
G01X627150Y331640D02*
X627190Y331590D01*
G01X627120Y331700D02*
X627150Y331640D01*
G01X626940Y333830D02*
X627120Y331700D01*
G01X627040Y333940D02*
X626940Y333830D01*
G01X627460Y327790D02*
X626990D01*
G01X626980Y327990D02*
X627440D01*
G01X627420Y328190D02*
X626960D01*
G01X626940Y328380D02*
X627410D01*
G01X627390Y328580D02*
X626920D01*
G01X626900Y328790D02*
X627370D01*
G01X627360Y328990D02*
X626890D01*
G01X626870Y329190D02*
X627340D01*
G01X627320Y329380D02*
X626850D01*
G01X626840Y329580D02*
X627310D01*
G01X627290Y329790D02*
X626820D01*
G01X626800Y329990D02*
X627270D01*
G01X627250Y330190D02*
X626790D01*
G01X626770Y330380D02*
X627240D01*
G01X627220Y330580D02*
X626750D01*
G01X626740Y330690D02*
X627250D01*
G01X627750Y330990D02*
X626720D01*
G01X626700Y331190D02*
X627570D01*
G01X626640Y331500D02*
X626620Y331530D01*
G01X626680Y331400D02*
X626640Y331500D01*
G01X626680Y331390D02*
Y331400D01*
G01Y331380D02*
Y331390D01*
G01X627380Y331380D02*
X626680D01*
G01X626580Y331580D02*
X627200D01*
G01X627130Y331690D02*
X626480D01*
G01X626390Y331790D02*
X627120D01*
G01X627110Y331880D02*
X626300D01*
G01X626200Y331990D02*
X627100D01*
G01X627090Y332080D02*
X626110D01*
G01X625920Y332290D02*
X627070D01*
G01X627060Y332490D02*
X626580D01*
G01X626370Y333940D02*
X625770D01*
G01X626470Y333850D02*
X626370Y333940D01*
G01X626590Y332500D02*
X626470Y333850D01*
G01X626430Y333880D02*
X626990D01*
G01X626940Y333790D02*
X626480D01*
G01X626490Y333690D02*
X626960D01*
G01Y333580D02*
X626490D01*
G01X626500Y333490D02*
X626970D01*
G01X626980Y333380D02*
X626510D01*
G01X626520Y333290D02*
X626990D01*
G01X627000Y333190D02*
X626530D01*
G01X626540Y333080D02*
X627010D01*
G01Y332990D02*
X626550D01*
G01Y332880D02*
X627020D01*
G01X627030Y332790D02*
X626570D01*
G01Y332690D02*
X627040D01*
G01X627050Y332580D02*
X626580D01*
G01X626420Y332430D02*
X621400Y337820D01*
G01X626530Y332400D02*
X626420Y332430D01*
G01X626590Y332500D02*
X626530Y332400D01*
G01X625740Y332490D02*
X626360D01*
G01X626680Y331380D02*
X627120Y326230D01*
G01X627130Y326190D02*
X627600D01*
G01X627610Y325990D02*
X627140D01*
G01X627160Y325790D02*
X627630D01*
G01X627650Y325580D02*
X627180D01*
G01X627200Y325380D02*
X627670D01*
G01X627710Y325290D02*
X627210D01*
G01X627220Y324640D02*
X627120Y324530D01*
G01X627250Y324710D02*
X627220Y324640D01*
G01X627070Y324490D02*
X627760D01*
G01Y324290D02*
X626880D01*
G01X626690Y324080D02*
X627780D01*
G01X627140Y323880D02*
X626490D01*
G01X626400Y323790D02*
X627050D01*
G01X626950Y323690D02*
X626300D01*
G01X626200Y323580D02*
X626860D01*
G01X626760Y323490D02*
X626110D01*
G01X625920Y323290D02*
X626570D01*
G01X626370Y323080D02*
X625720D01*
G01X627100Y326490D02*
X627570D01*
G01X627550Y326690D02*
X627090D01*
G01X627070Y326880D02*
X627540D01*
G01X627520Y327080D02*
X627050D01*
G01X627030Y327290D02*
X627500D01*
G01X627490Y327490D02*
X627020D01*
G01X627010Y327580D02*
X627480D01*
G01X627470Y327690D02*
X627000D01*
G01X626980Y327880D02*
X627450D01*
G01X627440Y328080D02*
X626970D01*
G01X626950Y328290D02*
X627420D01*
G01X627400Y328490D02*
X626930D01*
G01X626920Y328690D02*
X627380D01*
G01X627360Y328880D02*
X626900D01*
G01X626880Y329080D02*
X627350D01*
G01X627330Y329290D02*
X626860D01*
G01X626850Y329490D02*
X627310D01*
G01X627300Y329690D02*
X626830D01*
G01X626810Y329880D02*
X627280D01*
G01X627260Y330080D02*
X626790D01*
G01X626780Y330290D02*
X627240D01*
G01X627230Y330490D02*
X626760D01*
G01X627390Y330710D02*
X630120Y327770D01*
G01X627270Y330730D02*
X627390Y330710D01*
G01X627220Y330630D02*
X627270Y330730D01*
G01X627490Y327380D02*
X627030D01*
G01X627040Y327190D02*
X627510D01*
G01X627530Y326990D02*
X627060D01*
G01X627080Y326790D02*
X627550D01*
G01X627560Y326580D02*
X627090D01*
G01X627110Y326380D02*
X627580D01*
G01X627590Y326290D02*
X627120D01*
G01X627250Y324770D02*
Y324710D01*
G01X627120Y326230D02*
X627250Y324770D01*
G01X627240Y324690D02*
X627920D01*
G01X627770Y324510D02*
X627750Y324440D01*
G01X627820Y324590D02*
X627770Y324510D01*
G01X627750Y324380D02*
X626980D01*
G01X626790Y324190D02*
X627770D01*
G01X627790Y323880D02*
X627290D01*
G01X627260Y323920D02*
X627160Y323900D01*
G01X627530Y321480D02*
X627640D01*
G01X627530Y321490D02*
Y321480D01*
G01X627330Y323840D02*
X627530Y321490D01*
G01X627260Y323920D02*
X627330Y323840D01*
G01X627630Y321580D02*
X627520D01*
G01X627525D02*
X633120D01*
G01X633185Y321490D02*
X627530D01*
G01X627770Y320440D02*
X628660D01*
G01X627730Y320480D02*
X627770Y320440D01*
G01X627730Y321160D02*
Y320480D01*
G01X627700Y321230D02*
X627730Y321160D01*
G01X627550Y321390D02*
X627700Y321230D01*
G01X627540Y321410D02*
X627550Y321390D01*
G01X627530Y321470D02*
X627540Y321410D01*
G01X628700Y320490D02*
X627730D01*
G01Y320690D02*
X628700D01*
G01Y320880D02*
X627730D01*
G01Y321080D02*
X628700D01*
G01X627980Y321790D02*
X627510D01*
G01X627490Y321880D02*
X627960D01*
G01X627950Y322080D02*
X627480D01*
G01X627460Y322290D02*
X627930D01*
G01X627910Y322490D02*
X627440D01*
G01X627430Y322690D02*
X627900D01*
G01X627880Y322880D02*
X627410D01*
G01X627390Y323080D02*
X627860D01*
G01X627850Y323290D02*
X627380D01*
G01X627360Y323490D02*
X627830D01*
G01X627810Y323690D02*
X627350D01*
G01X627240Y324880D02*
X628110D01*
G01X628300Y325080D02*
X627220D01*
G01X627190Y325490D02*
X627660D01*
G01X627670Y325340D02*
X627220Y330630D01*
G01X627410Y330690D02*
X628030D01*
G01X628220Y330490D02*
X627600D01*
G01X627780Y330290D02*
X628400D01*
G01X627660Y331080D02*
X626710D01*
G01X626690Y331290D02*
X627480D01*
G01X627290Y331490D02*
X626650D01*
G01X627350Y334900D02*
X627240Y334890D01*
G01X627400Y334810D02*
X627350Y334900D01*
G01X627400Y334580D02*
Y334810D01*
G01X627300Y334480D02*
X627400Y334580D01*
G01X627030Y334480D02*
X627300D01*
G01X627230Y334880D02*
X626540D01*
G01X627410Y335870D02*
X627440Y335890D01*
G01X627400Y335840D02*
X627410Y335870D01*
G01X627400Y335640D02*
Y335840D01*
G01X627390Y335600D02*
X627400Y335640D01*
G01X627370Y335550D02*
X627390Y335600D01*
G01X627320Y335490D02*
X627370Y335550D01*
G01X627230Y335450D02*
X627320Y335490D01*
G01X626960Y335290D02*
X627230Y335450D01*
G01X627440Y335880D02*
X628270D01*
G01X627400Y335690D02*
X630290D01*
G01X630280Y335490D02*
X627300D01*
G01X627350Y334880D02*
X628320D01*
G01Y334690D02*
X627400D01*
G01X627310Y334490D02*
X628420D01*
G01X627610Y326080D02*
X627140D01*
G01X627150Y325880D02*
X627620D01*
G01X627640Y325690D02*
X627170D01*
G01X627740Y325250D02*
X627840Y325280D01*
G01X627670Y325340D02*
X627740Y325250D01*
G01X627650Y321290D02*
X633430D01*
G01X627970Y321860D02*
X627750Y324440D01*
G01X627970Y321790D02*
Y321860D01*
G01X628070Y321700D02*
X627970Y321790D01*
G01X632170Y321700D02*
X628070D01*
G01X627820Y324580D02*
X627170D01*
G01X627250Y324790D02*
X628010D01*
G01X627830Y324590D02*
X627820D01*
G01X627830Y324600D02*
Y324590D01*
G01Y324600D02*
X630420Y327290D01*
G01X630230Y327080D02*
X629590D01*
G01X629390Y326880D02*
X630040D01*
G01X629850Y326690D02*
X629200D01*
G01X629010Y326490D02*
X629650D01*
G01X629560Y326380D02*
X628910D01*
G01X628960Y326440D02*
X627840Y325280D01*
G01X627850Y325290D02*
X628490D01*
G01X628400Y325190D02*
X627220D01*
G01X627230Y324990D02*
X628210D01*
G01X627950Y325380D02*
X628590D01*
G01X628690Y325490D02*
X628050D01*
G01X628140Y325580D02*
X628790D01*
G01X628880Y325690D02*
X628240D01*
G01X628330Y325790D02*
X628980D01*
G01X629070Y325880D02*
X628430D01*
G01X628530Y325990D02*
X629170D01*
G01X629270Y326080D02*
X628620D01*
G01X628720Y326190D02*
X629360D01*
G01X629460Y326290D02*
X628810D01*
G01X629640Y328290D02*
X630270D01*
G01X630080Y328490D02*
X629460D01*
G01X629270Y328690D02*
X629890D01*
G01X629710Y328880D02*
X629080D01*
G01X628990Y328990D02*
X629610D01*
G01X629520Y329080D02*
X628900D01*
G01X628810Y329190D02*
X629430D01*
G01X629330Y329290D02*
X628710D01*
G01X628620Y329380D02*
X629240D01*
G01X629150Y329490D02*
X628530D01*
G01X628430Y329580D02*
X629060D01*
G01X628960Y329690D02*
X628340D01*
G01X628250Y329790D02*
X628870D01*
G01X628780Y329880D02*
X628150D01*
G01X628060Y329990D02*
X628680D01*
G01X628590Y330080D02*
X627970D01*
G01X627880Y330190D02*
X628500D01*
G01X628310Y330380D02*
X627690D01*
G01X627500Y330580D02*
X628120D01*
G01X627940Y330790D02*
X626740D01*
G01X626730Y330880D02*
X627850D01*
G01X629700Y330160D02*
X629740Y330120D01*
G01X628320Y334580D02*
X627400D01*
G01X628420Y334480D02*
X628320Y334580D01*
G01X627400Y334790D02*
X628320D01*
G01X629650Y335490D02*
X629760Y335380D01*
G01X629380Y335460D02*
X629650Y335490D01*
G01X629100Y335430D02*
X629380Y335460D01*
G01X628980Y335420D02*
X629100Y335430D01*
G01X628880Y335400D02*
X628980Y335420D01*
G01X628630Y335360D02*
X628880Y335400D01*
G01X628620Y335360D02*
X628630D01*
G01X628530Y335340D02*
X628620Y335360D01*
G01X628520Y335340D02*
X628530D01*
G01X628400Y335320D02*
X628520Y335340D01*
G01X628320Y335220D02*
X628400Y335320D01*
G01X628320Y334580D02*
Y335220D01*
G01X628260Y335890D02*
X627440D01*
G01X628280Y335880D02*
X628260Y335890D01*
G01X628310Y335870D02*
X628280Y335880D01*
G01X628340Y335850D02*
X628310Y335870D01*
G01X628420Y335830D02*
X628340Y335850D01*
G01X628440Y335840D02*
X628420Y335830D01*
G01X628680Y335880D02*
X628440Y335840D01*
G01X629180Y335950D02*
X628680Y335880D01*
G01X629300Y335960D02*
X629180Y335950D01*
G01X629360Y335960D02*
X629300D01*
G01X629520Y335980D02*
X629360Y335960D01*
G01X629660Y335990D02*
X629520Y335980D01*
G01X627120Y335380D02*
X628770D01*
G01X628320Y335080D02*
X626750D01*
G01X628420Y334480D02*
X634260D01*
G01X632330Y335990D02*
X629640D01*
G01X629660D02*
X629760Y336090D01*
G01X627790Y323990D02*
X626590D01*
G01X627330Y323790D02*
X627800D01*
G01X627820Y323580D02*
X627350D01*
G01X627370Y323380D02*
X627840D01*
G01X627850Y323190D02*
X627380D01*
G01X627400Y322990D02*
X627870D01*
G01X627890Y322790D02*
X627420D01*
G01X627440Y322580D02*
X627900D01*
G01X627920Y322380D02*
X627460D01*
G01X627470Y322190D02*
X627940D01*
G01X627960Y321990D02*
X627490D01*
G01X627720Y321190D02*
X628770D01*
G01X628700Y320480D02*
X628660Y320440D01*
G01X628700Y321120D02*
Y320480D01*
G01X628800Y321220D02*
X628700Y321120D01*
G01Y320580D02*
X627730D01*
G01Y320790D02*
X628700D01*
G01Y320990D02*
X627730D01*
G01X632270Y322170D02*
Y322180D01*
G01X632260Y322100D02*
X632270Y322170D01*
G01X632260Y321840D02*
Y322100D01*
G01X632270Y321820D02*
X632260Y321840D01*
G01X632170Y321700D02*
X632270Y321820D01*
G01Y322190D02*
X633040D01*
G01X633000Y321990D02*
X632260D01*
G01X632240Y321790D02*
X633040D01*
G01X630880Y327620D02*
Y327760D01*
G01X633580Y324720D02*
X630880Y327620D01*
G01X630900Y327790D02*
X630110D01*
G01X630120Y327630D02*
X628960Y326440D01*
G01X630120Y327770D02*
Y327630D01*
G01X629110Y326580D02*
X629750D01*
G01X629940Y326790D02*
X629300D01*
G01X629490Y326990D02*
X630140D01*
G01X630330Y327190D02*
X629680D01*
G01X630570Y327290D02*
X632250Y325470D01*
G01X630420Y327290D02*
X630570D01*
G01X629780D02*
X630420D01*
G01X632240Y325490D02*
X632870D01*
G01X632680Y325690D02*
X632050D01*
G01X631870Y325880D02*
X632500D01*
G01X632310Y326080D02*
X631680D01*
G01X631590Y326190D02*
X632220D01*
G01X632120Y326290D02*
X631490D01*
G01X631400Y326380D02*
X632030D01*
G01X631940Y326490D02*
X631310D01*
G01X631220Y326580D02*
X631850D01*
G01X631750Y326690D02*
X631120D01*
G01X631030Y326790D02*
X631660D01*
G01X631570Y326880D02*
X630940D01*
G01X630850Y326990D02*
X631480D01*
G01X631380Y327080D02*
X630750D01*
G01X630660Y327190D02*
X631290D01*
G01X631200Y327290D02*
X630550D01*
G01X630920Y327580D02*
X630070D01*
G01X630120Y327690D02*
X630880D01*
G01X631000Y327880D02*
X630010D01*
G01X629920Y327990D02*
X631100D01*
G01X631200Y328080D02*
X629830D01*
G01X629740Y328190D02*
X630360D01*
G01X630570Y328110D02*
X632000Y329580D01*
G01X630430Y328110D02*
X630570D01*
G01X631900Y329490D02*
X632540D01*
G01X632350Y329290D02*
X631710D01*
G01X631620Y329190D02*
X632250D01*
G01X632160Y329080D02*
X631520D01*
G01X631420Y328990D02*
X632060D01*
G01X631970Y328880D02*
X631330D01*
G01X631230Y328790D02*
X631870D01*
G01X631770Y328690D02*
X631130D01*
G01X631040Y328580D02*
X631680D01*
G01X631580Y328490D02*
X630940D01*
G01X630850Y328380D02*
X631480D01*
G01X631390Y328290D02*
X630750D01*
G01X630650Y328190D02*
X631290D01*
G01X631010Y327490D02*
X629980D01*
G01X629880Y327380D02*
X631100D01*
G01X630170Y328380D02*
X629550D01*
G01X629360Y328580D02*
X629990D01*
G01X629800Y328790D02*
X629180D01*
G01X629790Y330120D02*
X632280D01*
G01X629740D02*
X629790D01*
G01X632290Y329880D02*
X632930D01*
G01X632740Y329690D02*
X632100D01*
G01X633220Y330190D02*
X629700D01*
G01X629740Y331150D02*
X629790D01*
G01X629700Y331110D02*
X629740Y331150D01*
G01X629700Y330160D02*
Y331110D01*
G01Y330990D02*
X632960D01*
G01X632990Y330790D02*
X629700D01*
G01Y330580D02*
X633610D01*
G01X633410Y330380D02*
X629700D01*
G01X629760Y335040D02*
Y335380D01*
G01X629800Y334990D02*
X629760Y335040D01*
G01X629750Y335380D02*
X632380D01*
G01X632250Y334990D02*
X629800D01*
G01X632300Y335040D02*
X632250Y334990D01*
G01X632300Y335320D02*
Y335040D01*
G01X629760Y335080D02*
X632300D01*
G01Y335190D02*
X629760D01*
G01Y335290D02*
X632300D01*
G01X631850Y335600D02*
Y335560D01*
G01X631750Y335700D02*
X631850Y335600D01*
G01X630310Y335700D02*
X631750D01*
G01X630210Y335600D02*
X630310Y335700D01*
G01X630210Y335560D02*
Y335600D01*
G01X630310Y335450D02*
X630210Y335560D01*
G01X631750Y335450D02*
X630310D01*
G01X631850Y335560D02*
X631750Y335450D01*
G01X631850Y335580D02*
X633820D01*
G01X633530Y335690D02*
X631760D01*
G01X629760Y336120D02*
Y336090D01*
G01X629800Y336160D02*
X629760Y336120D01*
G01X632250Y336160D02*
X629800D01*
G01X632300Y336120D02*
X632250Y336160D01*
G01X632300Y336020D02*
Y336120D01*
G01X629750Y336080D02*
X632300D01*
G01X630210Y335580D02*
X627380D01*
G01X627400Y335790D02*
X633160D01*
G01X632380Y335920D02*
X632300Y336020D01*
G01X632430Y335920D02*
X632380D01*
G01X632990Y335830D02*
X632430Y335920D01*
G01X633170Y335790D02*
X632990Y335830D01*
G01X632610Y335880D02*
X628740D01*
G01X632810Y335350D02*
X633220Y335260D01*
G01X632520Y335400D02*
X632810Y335350D01*
G01X632490Y335400D02*
X632520D01*
G01X632410Y335420D02*
X632490Y335400D01*
G01X632300Y335320D02*
X632410Y335420D01*
G01X632600Y335380D02*
X634190D01*
G01X632910Y331150D02*
X629790D01*
G01X629700Y331080D02*
X632960D01*
G01X632950Y331110D02*
X632910Y331150D01*
G01X633130Y330760D02*
X633330Y330960D01*
G01X633020Y330730D02*
X633130Y330760D01*
G01X632960Y330830D02*
X633020Y330730D01*
G01X632960Y331010D02*
Y330830D01*
G01Y331020D02*
Y331010D01*
G01X632950Y331110D02*
X632960Y331020D01*
G01X633160Y330790D02*
X633800D01*
G01X632960Y330880D02*
X629700D01*
G01X631810Y329380D02*
X632450D01*
G01X632370Y330060D02*
X632280Y330120D01*
G01X632350Y329950D02*
X632370Y330060D01*
G01X632000Y329580D02*
X632350Y329950D01*
G01X632640Y329580D02*
X632000D01*
G01X632330Y330080D02*
X633120D01*
G01X633030Y329990D02*
X632360D01*
G01X632200Y329790D02*
X632830D01*
G01X632400Y325990D02*
X631770D01*
G01X631960Y325790D02*
X632590D01*
G01X632770Y325580D02*
X632140D01*
G01X632330Y325380D02*
X632960D01*
G01X633050Y325290D02*
X632420D01*
G01X632510Y325190D02*
X633150D01*
G01X633240Y325080D02*
X632610D01*
G01X632700Y324990D02*
X633330D01*
G01X633520Y324790D02*
X632890D01*
G01X633070Y324580D02*
X634210D01*
G01X634200Y324490D02*
X633170D01*
G01X632310Y322360D02*
X632270Y322180D01*
G01X632310Y322370D02*
Y322360D01*
G01X632420Y322680D02*
X632310Y322370D01*
G01X632430Y322690D02*
X632420Y322680D01*
G01X632640Y323000D02*
X632430Y322690D01*
G01X632650Y323010D02*
X632640Y323000D01*
G01X632890Y323230D02*
X632650Y323010D01*
G01X632900Y323230D02*
X632890D01*
G01X633020Y323310D02*
X632900Y323230D01*
G01X633030Y323320D02*
X633020Y323310D01*
G01X633090Y323350D02*
X633030Y323320D01*
G01X633250Y323420D02*
X633090Y323350D01*
G01X632260Y322080D02*
X633020D01*
G01X633060Y321690D02*
X627510D01*
G01X633050Y321710D02*
X633060Y321690D01*
G01X633000Y321970D02*
X633050Y321710D01*
G01X633000Y321980D02*
Y321970D01*
G01Y322000D02*
Y321980D01*
G01X627550Y321380D02*
X633290D01*
G01X633210Y321450D02*
X633150Y321540D01*
G01X633220Y321440D02*
X633210Y321450D01*
G01X633230Y321430D02*
X633220Y321440D01*
G01X633070Y321680D02*
X633060Y321690D01*
G01X633150Y321550D02*
X633070Y321680D01*
G01X633020Y321880D02*
X632260D01*
G01X632290Y322290D02*
X633060D01*
G01X633050Y322260D02*
X633000Y322000D01*
G01X633060Y322280D02*
X633050Y322260D01*
G01X633280Y322010D02*
X633290Y322030D01*
G01X633230Y322540D02*
X633450Y322700D01*
G01X633220Y322530D02*
X633230Y322540D01*
G01X633210Y322510D02*
X633220Y322530D01*
G01X633070Y322300D02*
X633210Y322510D01*
G01X633060Y322280D02*
X633070Y322300D01*
G01X633290Y322580D02*
X632390D01*
G01X632350Y322490D02*
X633190D01*
G01X633120Y322380D02*
X632310D01*
G01X632490Y322790D02*
X633750D01*
G01X633160Y323380D02*
X634830D01*
G01X634920Y323290D02*
X632980D01*
G01X632740Y323080D02*
X635110D01*
G01X635290Y322880D02*
X632570D01*
G01X633150Y321490D02*
X633190D01*
G01X633230Y321430D02*
X633450Y321270D01*
G01X633020Y320690D02*
X634570D01*
G01X634730Y320790D02*
X632840D01*
G01X632400Y321220D02*
X628800D01*
G01X632480Y321190D02*
X632400Y321220D01*
G01X632490Y321180D02*
X632480Y321190D01*
G01X632490Y321170D02*
Y321180D01*
G01X632530Y321100D02*
X632490Y321170D01*
G01X632540Y321100D02*
X632530D01*
G01X632550Y321090D02*
X632540Y321100D01*
G01X632620Y320990D02*
X632550Y321090D01*
G01X632630Y320980D02*
X632620Y320990D01*
G01X632860Y320760D02*
X632630Y320980D01*
G01Y320990D02*
X634970D01*
G01X632880Y320750D02*
X632860Y320760D01*
G01X633680Y320450D02*
X634020Y320460D01*
G01X633670Y320450D02*
X633680D01*
G01X633660D02*
X633670D01*
G01X633500Y320470D02*
X633660Y320450D01*
G01X633480Y320470D02*
X633500D01*
G01X632880Y320750D02*
X633480Y320470D01*
G01X634130Y320490D02*
X633460D01*
G01Y321260D02*
X633450Y321270D01*
G01X633480Y321260D02*
X633460D01*
G01X633650Y321200D02*
X633480Y321260D01*
G01X633870Y321190D02*
X633890D01*
G01X633740D02*
X633870D01*
G01X633670Y321200D02*
X633740Y321190D01*
G01X633650Y321200D02*
X633670D01*
G01X633310Y321820D02*
X633280Y322010D01*
G01X633320Y321790D02*
X633310Y321820D01*
G01X633490Y321570D02*
X633320Y321790D01*
G01X633510Y321560D02*
X633490Y321570D01*
G01X633680Y321480D02*
X633510Y321560D01*
G01X633690Y321480D02*
X633680D01*
G01X633730Y321470D02*
X633690Y321480D01*
G01X633790Y321470D02*
X633730D01*
G01X633810D02*
X633790D01*
G01X633840Y322500D02*
X633850D01*
G01X633750D02*
X633840D01*
G01X633730Y322490D02*
X633750Y322500D01*
G01X633420Y322330D02*
X633730Y322490D01*
G01X633400Y322310D02*
X633420Y322330D01*
G01X633290Y322030D02*
X633400Y322310D01*
G01X633460Y322710D02*
X633450Y322700D01*
G01X633480Y322710D02*
X633460D01*
G01X633650Y322770D02*
X633480Y322710D01*
G01X633670Y322770D02*
X633650D01*
G01X633740Y322780D02*
X633670Y322770D01*
G01X633760Y322790D02*
X633740Y322780D01*
G01X633820Y322790D02*
X633760D01*
G01X633850Y322780D02*
X633820Y322790D01*
G01X633430Y322690D02*
X632430D01*
G01X633340Y322170D02*
X634280D01*
G01X634300Y321970D02*
X633290D01*
G01X633340Y321770D02*
X634250D01*
G01X634070Y321570D02*
X633500D01*
G01X633810Y321470D02*
X633940Y321490D01*
G01X634140Y322360D02*
X633490D01*
G01X633890Y322780D02*
X634090Y322730D01*
G01X633850Y322780D02*
X633890D01*
G01X633340Y323450D02*
X633250Y323420D01*
G01X633350Y323460D02*
X633340Y323450D01*
G01X633490Y323490D02*
X633350Y323460D01*
G01X633570Y323510D02*
X633490Y323490D01*
G01X633350Y324290D02*
X632250Y325470D01*
G01X633610Y324010D02*
X633350Y324290D01*
G01X633640Y323960D02*
X633610Y324010D01*
G01X633670Y323810D02*
X633640Y323960D01*
G01X633680Y323790D02*
X633670Y323810D01*
G01X633680Y323770D02*
Y323790D01*
G01X633660Y323600D02*
X633680Y323770D01*
G01X633660Y323590D02*
Y323600D01*
G01X633570Y323510D02*
X633660Y323590D01*
G01X632790Y324880D02*
X633430D01*
G01X633750Y324780D02*
X634260Y331010D01*
G01X633690Y324700D02*
X633750Y324780D01*
G01X633580Y324720D02*
X633690Y324700D01*
G01X633350Y330990D02*
X633330Y330960D01*
G01X633990Y330990D02*
X633350D01*
G01D02*
X634160Y331830D01*
G01X633740Y331380D02*
X636000D01*
G01Y331190D02*
X633550D01*
G01X633250Y330880D02*
X633890D01*
G01X633700Y330690D02*
X629700D01*
G01Y330490D02*
X633510D01*
G01X633310Y330290D02*
X629700D01*
G01X633920Y326790D02*
X634380D01*
G01X634370Y326580D02*
X633900D01*
G01X633880Y326380D02*
X634350D01*
G01X634340Y326190D02*
X633870D01*
G01X633850Y325990D02*
X634320D01*
G01X634310Y325790D02*
X633840D01*
G01X633820Y325580D02*
X634290D01*
G01X634270Y325380D02*
X633810D01*
G01X633790Y325190D02*
X634250D01*
G01X634240Y324990D02*
X633770D01*
G01X633750Y324790D02*
X634220D01*
G01X634180Y324290D02*
X633350D01*
G01X633540Y324080D02*
X634180D01*
G01X634360Y323880D02*
X633660D01*
G01X633670Y323690D02*
X634550D01*
G01X633500Y335180D02*
X633220Y335260D01*
G01X633510Y335170D02*
X633500Y335180D01*
G01X633620Y335140D02*
X633510Y335170D01*
G01X633620Y335130D02*
Y335140D01*
G01X633730Y335090D02*
X633620Y335130D01*
G01X633740Y335080D02*
X633730Y335090D01*
G01X634600Y335080D02*
X633740D01*
G01X633460Y335190D02*
X634490D01*
G01X633290Y335750D02*
X633170Y335790D01*
G01X633400Y335730D02*
X633290Y335750D01*
G01X633640Y335650D02*
X633400Y335730D01*
G01X633750Y335610D02*
X633640Y335650D01*
G01X633810Y335590D02*
X633750Y335610D01*
G01X633100Y335290D02*
X634350D01*
G01X634030Y335490D02*
X631780D01*
G01X634350Y334530D02*
X634260Y334480D01*
G01X634340Y334630D02*
X634350Y334530D01*
G01X634270Y334740D02*
X634340Y334630D01*
G01X634250Y334760D02*
X634270Y334740D01*
G01X633950Y334980D02*
X634250Y334760D01*
G01X633940Y334990D02*
X633950Y334980D01*
G01X633930Y334990D02*
X633940D01*
G01X633740Y335080D02*
X633930Y334990D01*
G01X634270Y334490D02*
X635990D01*
G01X635970Y334690D02*
X634310D01*
G01X634080Y334880D02*
X635890D01*
G01X636000Y332880D02*
X634220D01*
G01X634190Y331860D02*
X634160Y331830D01*
G01X634220Y331920D02*
X634190Y331860D01*
G01X634220Y332940D02*
Y331920D01*
G01X634120Y331790D02*
X634790D01*
G01X634960Y331990D02*
X634220D01*
G01Y332190D02*
X635150D01*
G01X635340Y332380D02*
X634220D01*
G01Y332490D02*
X636000D01*
G01Y332690D02*
X634220D01*
G01X634330Y333020D02*
X634430Y333120D01*
G01X634260Y333020D02*
X634330D01*
G01X634220Y332980D02*
X634260Y333020D01*
G01X634220Y332940D02*
Y332980D01*
G01X633930Y331580D02*
X636000D01*
G01X634720Y330880D02*
X634250D01*
G01X634090Y331090D02*
X630880Y327760D01*
G01X634200Y331110D02*
X634090Y331090D01*
G01X634260Y331010D02*
X634200Y331110D01*
G01X633980Y327580D02*
X634450D01*
G01X634460Y327690D02*
X633990D01*
G01X634010Y327880D02*
X634480D01*
G01X634490Y328080D02*
X634030D01*
G01X634040Y328290D02*
X634510D01*
G01X634520Y328490D02*
X634060D01*
G01X634070Y328690D02*
X634540D01*
G01X634560Y328880D02*
X634090D01*
G01X634110Y329080D02*
X634570D01*
G01X634590Y329290D02*
X634120D01*
G01X634140Y329490D02*
X634610D01*
G01X634620Y329690D02*
X634160D01*
G01X634170Y329880D02*
X634640D01*
G01X634650Y330080D02*
X634190D01*
G01X634200Y330290D02*
X634670D01*
G01X634690Y330490D02*
X634220D01*
G01X634240Y330690D02*
X634700D01*
G01X634090Y331080D02*
X633450D01*
G01X633970Y327380D02*
X634440D01*
G01X634420Y327190D02*
X633950D01*
G01X633940Y326990D02*
X634400D01*
G01X634390Y326880D02*
X633930D01*
G01X633910Y326690D02*
X634380D01*
G01X634360Y326490D02*
X633890D01*
G01X633880Y326290D02*
X634350D01*
G01X634330Y326080D02*
X633860D01*
G01X633850Y325880D02*
X634310D01*
G01X634300Y325690D02*
X633830D01*
G01X633810Y325490D02*
X634280D01*
G01X634260Y325290D02*
X633800D01*
G01X633780Y325080D02*
X634250D01*
G01X634230Y324880D02*
X633760D01*
G01X634220Y324690D02*
X632980D01*
G01X633260Y324380D02*
X634190D01*
G01X634180Y324190D02*
X633450D01*
G01X633620Y323990D02*
X634260D01*
G01X634200Y324050D02*
X635160Y323030D01*
G01X635480Y322690D02*
X634150D01*
G01X634130Y322710D02*
X634090Y322730D01*
G01X634130Y322710D02*
X634440Y322450D01*
G01X634210Y322270D02*
X633380D01*
G01X633300Y322070D02*
X634290D01*
G01X634100Y322400D02*
X633850Y322500D01*
G01X634120Y322390D02*
X634100Y322400D01*
G01X634270Y322190D02*
X634120Y322390D01*
G01X634280Y322160D02*
X634270Y322190D01*
G01X633940Y322470D02*
X633670D01*
G01X633960Y321490D02*
X633940D01*
G01X634180Y321630D02*
X633960Y321490D01*
G01X634190Y321650D02*
X634180Y321630D01*
G01X634300Y321880D02*
X634190Y321650D01*
G01X634310Y321900D02*
X634300Y321880D01*
G01X634280Y322160D02*
X634310Y321900D01*
G01X634150Y321290D02*
X635170D01*
G01X634030Y320460D02*
X634020D01*
G01X634320Y320530D02*
X634030Y320460D01*
G01X634330Y320540D02*
X634320Y320530D01*
G01X634840Y320850D02*
X634330Y320540D01*
G01X634090Y321240D02*
X634130Y321260D01*
G01X633890Y321190D02*
X634090Y321240D01*
G01X634200Y321670D02*
X633420D01*
G01X633300Y321860D02*
X634300D01*
G01X634190Y324070D02*
X634170Y324140D01*
G01X634200Y324060D02*
X634190Y324070D01*
G01X634200Y324050D02*
Y324060D01*
G01X633960Y335530D02*
X633810Y335590D01*
G01X633970Y335520D02*
X633960Y335530D01*
G01X635220Y335240D02*
X635280Y335250D01*
G01X635210Y335240D02*
X635220D01*
G01X635100Y335210D02*
X635210Y335240D01*
G01X635090Y335210D02*
X635100D01*
G01X634960Y335160D02*
X635090Y335210D01*
G01X634960Y335150D02*
Y335160D01*
G01X634900Y335120D02*
X634960Y335150D01*
G01X634880Y335100D02*
X634900Y335120D01*
G01X634820Y335050D02*
X634880Y335100D01*
G01X634800Y335030D02*
X634820Y335050D01*
G01X634660Y335030D02*
X634800D01*
G01X634480Y335200D02*
X634660Y335030D01*
G01X634470Y335210D02*
X634480Y335200D01*
G01X633970Y335520D02*
X634470Y335210D01*
G01X635030Y335190D02*
X635550D01*
G01X635600Y333880D02*
X634440D01*
G01X634490Y333830D02*
X634430Y333120D01*
G01X634400Y333080D02*
X634950D01*
G01X635240Y333810D02*
X635270Y333800D01*
G01X635160Y333820D02*
X635240Y333810D01*
G01X635090Y333840D02*
X635160Y333820D01*
G01X635080Y333840D02*
X635090D01*
G01X634950Y333750D02*
X635080Y333840D01*
G01X634900Y333140D02*
X634950Y333750D01*
G01X635000Y333030D02*
X634900Y333140D01*
G01X635000Y333790D02*
X634490D01*
G01X634390Y333940D02*
X627040D01*
G01X634490Y333830D02*
X634390Y333940D01*
G01X634030Y331690D02*
X634850D01*
G01X634820Y331840D02*
X635370Y332420D01*
G01X634790Y331790D02*
X634820Y331840D01*
G01X634790Y331750D02*
Y331790D01*
G01X634890Y331640D02*
X634790Y331750D01*
G01X635250Y332290D02*
X634220D01*
G01Y332080D02*
X635050D01*
G01X634860Y331880D02*
X634200D01*
G01X634220Y331080D02*
X634750D01*
G01X634740Y331070D02*
X634170Y324140D01*
G01X634450Y323790D02*
X633680D01*
G01X633650Y323580D02*
X634640D01*
G01X634730Y323490D02*
X633460D01*
G01X632850Y323190D02*
X635010D01*
G01X635200Y322990D02*
X632630D01*
G01X632480Y321190D02*
X635110D01*
G01X634930Y320940D02*
X634840Y320850D01*
G01X634990Y321010D02*
X634930Y320940D01*
G01X635120Y321200D02*
X634990Y321010D01*
G01X634880Y320880D02*
X632730D01*
G01X632550Y321080D02*
X635040D01*
G01X635240Y321450D02*
X635300Y321620D01*
G01X635200Y321350D02*
X635240Y321450D01*
G01X635200Y321340D02*
Y321350D01*
G01X635130Y321210D02*
X635200Y321340D01*
G01X635120Y321200D02*
X635130Y321210D01*
G01X635290Y321580D02*
X634475D01*
G01X634480D02*
X634540D01*
G01X634440Y321520D02*
X634130Y321260D01*
G01X634470Y321570D02*
X634440Y321520D01*
G01X634270Y321380D02*
X635220D01*
G01X635250Y321490D02*
X634460D01*
G01X635220D02*
X635250D01*
G01X634470Y322400D02*
X634440Y322450D01*
G01X634590Y322010D02*
X634470Y322400D01*
G01X634590Y321950D02*
Y322010D01*
G01X634470Y321570D02*
X634590Y321950D01*
G01X634400Y322490D02*
X635660D01*
G01X635850Y322290D02*
X634510D01*
G01X634570Y322080D02*
X636030D01*
G01X635330Y321880D02*
X634570D01*
G01X634510Y321690D02*
X635310D01*
G01X634400Y320580D02*
X633240D01*
G01X633940Y327080D02*
X634410D01*
G01X634430Y327290D02*
X633960D01*
G01X633980Y327490D02*
X634440D01*
G01X634470Y327790D02*
X634000D01*
G01X634010Y327990D02*
X634480D01*
G01X634500Y328190D02*
X634030D01*
G01X634050Y328380D02*
X634510D01*
G01X634530Y328580D02*
X634070D01*
G01X634080Y328790D02*
X634550D01*
G01X634570Y328990D02*
X634100D01*
G01X634110Y329190D02*
X634580D01*
G01X634600Y329380D02*
X634130D01*
G01X634150Y329580D02*
X634610D01*
G01X634630Y329790D02*
X634160D01*
G01X634180Y329990D02*
X634640D01*
G01X634660Y330190D02*
X634200D01*
G01X634210Y330380D02*
X634680D01*
G01X634700Y330580D02*
X634230D01*
G01X634240Y330790D02*
X634710D01*
G01X634730Y330990D02*
X634260D01*
G01X634740Y331070D02*
X634830Y331160D01*
G01X635160Y333020D02*
X635280D01*
G01X635000Y333030D02*
X635160Y333020D01*
G01X634910Y333190D02*
X634440D01*
G01X634450Y333290D02*
X634920D01*
G01Y333380D02*
X634460D01*
G01Y333490D02*
X634930D01*
G01X634940Y333580D02*
X634470D01*
G01X634480Y333690D02*
X634950D01*
G01X635350Y335250D02*
X635280D01*
G01X635360Y335240D02*
X635350Y335250D01*
G01X635620Y335170D02*
X635360Y335240D01*
G01X635630Y335160D02*
X635620Y335170D01*
G01X635830Y334990D02*
X635630Y335160D01*
G01X635840Y334980D02*
X635830Y334990D01*
G01X635960Y334750D02*
X635840Y334980D01*
G01X635970Y334730D02*
X635960Y334750D01*
G01X635990Y334450D02*
X635970Y334730D01*
G01X635990Y334440D02*
Y334450D01*
G01X635910Y334180D02*
X635990Y334440D01*
G01X635900Y334170D02*
X635910Y334180D01*
G01X635740Y333970D02*
X635900Y334170D01*
G01X635730Y333950D02*
X635740Y333970D01*
G01X635500Y333830D02*
X635730Y333950D01*
G01X635480Y333830D02*
X635500D01*
G01X635360Y333810D02*
X635480Y333830D01*
G01X635350Y333810D02*
X635360D01*
G01X635290Y333800D02*
X635350Y333810D01*
G01X635270Y333800D02*
X635290D01*
G01X634860Y335080D02*
X635720D01*
G01X635830Y334990D02*
X633940D01*
G01X634220Y334790D02*
X635940D01*
G01X635980Y334580D02*
X634350D01*
G01X635840Y334080D02*
X625730D01*
G01Y334290D02*
X635940D01*
G01X636250Y333990D02*
X636880D01*
G01X636980Y334080D02*
X636350D01*
G01X636440Y334190D02*
X637080D01*
G01X637170Y334290D02*
X636540D01*
G01X636640Y334380D02*
X637270D01*
G01X637360Y334490D02*
X636740D01*
G01X636830Y334580D02*
X637460D01*
G01X637560Y334690D02*
X636930D01*
G01X637030Y334790D02*
X637660D01*
G01X637850Y334990D02*
X637220D01*
G01X637410Y335190D02*
X638040D01*
G01X636790Y333880D02*
X636160D01*
G01X636060Y333790D02*
X636690D01*
G01X636590Y333690D02*
X635960D01*
G01X635860Y333580D02*
X636500D01*
G01X636400Y333490D02*
X635770D01*
G01X635670Y333380D02*
X636310D01*
G01X636210Y333290D02*
X635580D01*
G01X635480Y333190D02*
X636110D01*
G01X635960Y331160D02*
X634830D01*
G01X636000Y331180D02*
X635960Y331160D01*
G01X636000Y331190D02*
Y331180D01*
G01Y333010D02*
Y331190D01*
G01Y333020D02*
Y333010D01*
G01X636030Y333100D02*
X636000Y333020D01*
G01X635480Y332440D02*
X635370Y332420D01*
G01X635540Y332340D02*
X635480Y332440D01*
G01X635540Y331740D02*
Y332340D01*
G01X635440Y331640D02*
X635540Y331740D01*
G01X634890Y331640D02*
X635440D01*
G01X635510Y332380D02*
X636000D01*
G01Y332290D02*
X635540D01*
G01Y332190D02*
X636000D01*
G01Y332080D02*
X635540D01*
G01Y331990D02*
X636000D01*
G01Y331880D02*
X635540D01*
G01Y331790D02*
X636000D01*
G01Y331690D02*
X635490D01*
G01X636000Y331490D02*
X633830D01*
G01X633640Y331290D02*
X636000D01*
G01Y332580D02*
X634220D01*
G01Y332790D02*
X636000D01*
G01Y332990D02*
X634220D01*
G01X635280Y333020D02*
X635350Y333050D01*
G01X635380Y333080D02*
X636020D01*
G01X635380Y322790D02*
X633830D01*
G01X634270Y322580D02*
X635570D01*
G01X635750Y322380D02*
X634480D01*
G01X634530Y322190D02*
X635940D01*
G01X636130Y321990D02*
X635440D01*
G01X635300Y321640D02*
Y321620D01*
G01X635340Y321910D02*
X635300Y321640D01*
G01X635400Y321990D02*
X635340Y321910D01*
G01X635320Y321790D02*
X634540D01*
G01X635400Y321990D02*
X635510Y321970D01*
G01X634590Y321990D02*
X635400D01*
G01X635590Y321880D02*
X636220D01*
G01X636310Y321790D02*
X635680D01*
G01X635770Y321690D02*
X636410D01*
G01X636460Y321580D02*
X636500D01*
G01X636510D02*
X635870D01*
G01X635960Y321490D02*
X636595D01*
G01X636590D02*
X636540D01*
G01X636695Y321380D02*
X636050D01*
G01X636140Y321290D02*
X636780D01*
G01X636870Y321190D02*
X636235D01*
G01X636335Y321080D02*
X636970D01*
G01X637060Y320990D02*
X636420D01*
G01X636525Y320880D02*
X637150D01*
G01X637250Y320790D02*
X636610D01*
G01X636700Y320690D02*
X637340D01*
G01X637430Y320580D02*
X636790D01*
G01X636880Y320490D02*
X637530D01*
G01X637710Y320290D02*
X637070D01*
G01X636980Y320380D02*
X637620D01*
G01X637800Y320190D02*
X637160D01*
G01X637260Y320080D02*
X637900D01*
G01X637990Y319990D02*
X637350D01*
G01X637440Y319880D02*
X638080D01*
G01X638180Y319790D02*
X637530D01*
G01X637630Y319690D02*
X638270D01*
G01X638360Y319580D02*
X637720D01*
G01X637810Y319490D02*
X638460D01*
G01X638550Y319380D02*
X637910D01*
G01X638000Y319290D02*
X638640D01*
G01X638830Y319080D02*
X638190D01*
G01X638370Y318880D02*
X638980D01*
G01X638970Y318940D02*
X635160Y323030D01*
G01X638640Y318600D02*
X638660Y318580D01*
G01X635510Y321970D02*
X638640Y318600D01*
G01X638560Y318690D02*
X638780D01*
G01X621700Y318920D02*
X627120Y324530D01*
G01X621670Y318890D02*
X621700Y318920D01*
G01X621680Y318870D02*
X621670Y318890D01*
G01X621990Y318600D02*
X621680Y318870D01*
G01X622020Y318590D02*
X621990Y318600D01*
G01X622040D02*
X622020Y318590D01*
G01X627160Y323900D02*
X622040Y318600D01*
G01X622120Y318690D02*
X621890D01*
G01X621770Y318790D02*
X622220D01*
G01X622320Y318880D02*
X621670D01*
G01X621760Y318990D02*
X622420D01*
G01X622510Y319080D02*
X621860D01*
G01X621950Y319190D02*
X622610D01*
G01X622700Y319290D02*
X622050D01*
G01X622140Y319380D02*
X622800D01*
G01X622900Y319490D02*
X622240D01*
G01X622340Y319580D02*
X622990D01*
G01X623090Y319690D02*
X622440D01*
G01X622530Y319790D02*
X623190D01*
G01X623280Y319880D02*
X622630D01*
G01X622730Y319990D02*
X623380D01*
G01X623480Y320080D02*
X622820D01*
G01X622920Y320190D02*
X623570D01*
G01X635350Y333050D02*
X639930Y337790D01*
G01X639960Y337180D02*
X636030Y333100D01*
G01X637120Y334880D02*
X637750D01*
G01X637940Y335080D02*
X637310D01*
G01X637510Y335290D02*
X638140D01*
G01X638240Y335380D02*
X637610D01*
G01X637700Y335490D02*
X638330D01*
G01X638430Y335580D02*
X637800D01*
G01X637900Y335690D02*
X638520D01*
G01X638620Y335790D02*
X637990D01*
G01X638180Y335990D02*
X638810D01*
G01X639010Y336190D02*
X638380D01*
G01X638570Y336380D02*
X639200D01*
G01X639100Y336290D02*
X638480D01*
G01X638670Y336490D02*
X639290D01*
G01X639390Y336580D02*
X638760D01*
G01X638860Y336690D02*
X639490D01*
G01X639590Y336790D02*
X638960D01*
G01X639050Y336880D02*
X639680D01*
G01X639780Y336990D02*
X639150D01*
G01X639250Y337080D02*
X639870D01*
G01X639980Y337290D02*
X639440D01*
G01X639970Y337210D02*
X639980Y337290D01*
G01X639960Y337180D02*
X639970Y337210D01*
G01X639350Y337190D02*
X639960D01*
G01X639980Y337780D02*
X639930Y337790D01*
G01X639980Y337290D02*
Y337780D01*
G01X639920Y337790D02*
X639960D01*
G01X639980Y337690D02*
X639830D01*
G01X639730Y337580D02*
X639980D01*
G01Y337490D02*
X639630D01*
G01X639540Y337380D02*
X639980D01*
G01X638910Y336080D02*
X638280D01*
G01X638090Y335880D02*
X638720D01*
G01X638740Y319190D02*
X638090D01*
G01X638280Y318990D02*
X638920D01*
G01X638690Y318600D02*
X638660Y318580D01*
G01X638980Y318890D02*
X638690Y318600D01*
G01X638990Y318910D02*
X638980Y318890D01*
G01Y318920D02*
X638990Y318910D01*
G01X638970Y318940D02*
X638980Y318920D01*
G01X638460Y318790D02*
X638880D01*
G54D19*
G01X-9023Y-84471D02*
X-8149Y-83596D01*
X-7494Y-82138D01*
X-7057Y-80095D01*
X-7494Y-78346D01*
X-8367Y-77179D01*
X-9896Y-76304D01*
X-15791D01*
Y-93804D01*
X-8586D01*
X-7057Y-92638D01*
X-6184Y-90887D01*
X-5747Y-88846D01*
X-6184Y-86804D01*
X-7494Y-85054D01*
X-9023Y-84471D01*
X-15791D01*
G01X3674Y-93804D02*
Y-82138D01*
G01Y-84471D02*
X4766Y-83304D01*
X5858Y-82429D01*
X7386Y-82138D01*
X8477Y-82429D01*
X9788Y-83304D01*
G01X19646Y-99054D02*
X20956Y-99637D01*
X22703Y-99054D01*
X23794Y-97888D01*
X24668Y-96429D01*
X25977Y-91763D01*
X28816Y-82138D01*
G01X21829D02*
X25977Y-91763D01*
G01X45224Y-83596D02*
X43696Y-82429D01*
X42386Y-82138D01*
X40639Y-82721D01*
X39329Y-83887D01*
X38456Y-85929D01*
X38237Y-87971D01*
X38456Y-90013D01*
X39329Y-91763D01*
X40639Y-93221D01*
X42386Y-93804D01*
X43914Y-93221D01*
X45224Y-92054D01*
G01X55956Y-85929D02*
X62943D01*
X62288Y-83887D01*
X61196Y-82721D01*
X59668Y-82138D01*
X58139Y-82429D01*
X56829Y-83304D01*
X55956Y-85346D01*
X55519Y-87096D01*
Y-88846D01*
X55956Y-90596D01*
X57048Y-92346D01*
X58358Y-93512D01*
X59886Y-93804D01*
X61414Y-93221D01*
X62943Y-91471D01*
G01X99034Y-77763D02*
X97724Y-76887D01*
X96196Y-76304D01*
X94449D01*
X92484Y-77179D01*
X90956Y-78637D01*
X89864Y-80388D01*
X88991Y-83304D01*
X88772Y-85929D01*
X89209Y-88554D01*
X89864Y-90304D01*
X91174Y-92054D01*
X92703Y-93221D01*
X94231Y-93804D01*
X95759D01*
X97288Y-93221D01*
X98598Y-92346D01*
X99690Y-91180D01*
G01X115661Y-93804D02*
Y-82138D01*
G01Y-84179D02*
X114788Y-83013D01*
X113477Y-82429D01*
X111949Y-82138D01*
X110421Y-82721D01*
X109111Y-83887D01*
X108237Y-85637D01*
X107801Y-87971D01*
X108237Y-90304D01*
X109111Y-92054D01*
X110421Y-93221D01*
X111949Y-93804D01*
X113477Y-93512D01*
X114788Y-92638D01*
X115661Y-91471D01*
G01X125519Y-93804D02*
Y-82138D01*
G01Y-85054D02*
X126393Y-83596D01*
X127703Y-82429D01*
X129449Y-82138D01*
X130977Y-82429D01*
X132288Y-83596D01*
X132943Y-85637D01*
Y-93804D01*
G01X142146Y-99054D02*
X143456Y-99637D01*
X145203Y-99054D01*
X146294Y-97888D01*
X147168Y-96429D01*
X148477Y-91763D01*
X151316Y-82138D01*
G01X144329D02*
X148477Y-91763D01*
G01X164231Y-93804D02*
X162921Y-93512D01*
X161611Y-92346D01*
X160737Y-90304D01*
X160301Y-87971D01*
X160737Y-85637D01*
X161611Y-83596D01*
X162921Y-82429D01*
X164231Y-82138D01*
X165541Y-82429D01*
X166851Y-83596D01*
X167724Y-85637D01*
X167943Y-87971D01*
X167724Y-90304D01*
X166851Y-92346D01*
X165541Y-93512D01*
X164231Y-93804D01*
G01X178019D02*
Y-82138D01*
G01Y-85054D02*
X178893Y-83596D01*
X180203Y-82429D01*
X181949Y-82138D01*
X183477Y-82429D01*
X184788Y-83596D01*
X185443Y-85637D01*
Y-93804D01*
G01X214111Y-76304D02*
X219351D01*
G01X216731D02*
Y-93804D01*
G01X214111D02*
X219351D01*
G01X234231D02*
X232484Y-93512D01*
X230956Y-92346D01*
X229646Y-90596D01*
X228772Y-88554D01*
X228336Y-86221D01*
Y-83887D01*
X228772Y-81554D01*
X229646Y-79512D01*
X230956Y-77763D01*
X232484Y-76596D01*
X234231Y-76304D01*
X235977Y-76596D01*
X237506Y-77763D01*
X238816Y-79512D01*
X239690Y-81554D01*
X240126Y-83887D01*
Y-86221D01*
X239690Y-88554D01*
X238816Y-90596D01*
X237506Y-92346D01*
X235977Y-93512D01*
X234231Y-93804D01*
G01X246054D02*
Y-76304D01*
X251731Y-90887D01*
X257408Y-76304D01*
Y-93804D01*
G01X285639Y-99637D02*
X283456Y-96721D01*
X282364Y-93804D01*
Y-82138D01*
X283456Y-79221D01*
X285639Y-76304D01*
G01X298554Y-93804D02*
Y-76304D01*
X304231Y-90887D01*
X309908Y-76304D01*
Y-93804D01*
G01X321731Y-94387D02*
X321294Y-94096D01*
Y-93512D01*
X321731Y-93221D01*
X322168Y-93512D01*
Y-94096D01*
X321731Y-94387D01*
G01X335083Y-79221D02*
X336393Y-77471D01*
X337921Y-76596D01*
X339668Y-76304D01*
X341851Y-76887D01*
X343379Y-78346D01*
X343816Y-80095D01*
X343598Y-81846D01*
X342724Y-83304D01*
X338358Y-86221D01*
X336393Y-88262D01*
X335083Y-91180D01*
X334646Y-93804D01*
X343816D01*
G01X374231D02*
X372921Y-93512D01*
X371611Y-92346D01*
X370737Y-90304D01*
X370301Y-87971D01*
X370737Y-85637D01*
X371611Y-83596D01*
X372921Y-82429D01*
X374231Y-82138D01*
X375541Y-82429D01*
X376851Y-83596D01*
X377724Y-85637D01*
X377943Y-87971D01*
X377724Y-90304D01*
X376851Y-92346D01*
X375541Y-93512D01*
X374231Y-93804D01*
G01X388019D02*
Y-82138D01*
G01Y-85054D02*
X388893Y-83596D01*
X390203Y-82429D01*
X391949Y-82138D01*
X393477Y-82429D01*
X394788Y-83596D01*
X395443Y-85637D01*
Y-93804D01*
G01X409231D02*
Y-76304D01*
G01X422146Y-99054D02*
X423456Y-99637D01*
X425203Y-99054D01*
X426294Y-97888D01*
X427168Y-96429D01*
X428477Y-91763D01*
X431316Y-82138D01*
G01X424329D02*
X428477Y-91763D01*
G01X445323Y-99637D02*
X447506Y-96721D01*
X448598Y-93804D01*
Y-82138D01*
X447506Y-79221D01*
X445323Y-76304D01*
G01X176054Y-48804D02*
Y-31304D01*
X181731Y-45887D01*
X187408Y-31304D01*
Y-48804D01*
G01X199231D02*
X197921Y-48512D01*
X196611Y-47346D01*
X195737Y-45304D01*
X195301Y-42971D01*
X195737Y-40637D01*
X196611Y-38596D01*
X197921Y-37429D01*
X199231Y-37138D01*
X200541Y-37429D01*
X201851Y-38596D01*
X202724Y-40637D01*
X202943Y-42971D01*
X202724Y-45304D01*
X201851Y-47346D01*
X200541Y-48512D01*
X199231Y-48804D01*
G01X220661Y-31304D02*
Y-48804D01*
G01Y-46180D02*
X219788Y-47638D01*
X218477Y-48512D01*
X216949Y-48804D01*
X215203Y-48221D01*
X213893Y-46763D01*
X213019Y-45013D01*
X212801Y-42971D01*
X213019Y-40929D01*
X213893Y-39179D01*
X215203Y-37721D01*
X216949Y-37138D01*
X218477Y-37429D01*
X219569Y-38013D01*
X220661Y-39179D01*
G01X230956Y-40929D02*
X237943D01*
X237288Y-38887D01*
X236196Y-37721D01*
X234668Y-37138D01*
X233139Y-37429D01*
X231829Y-38304D01*
X230956Y-40346D01*
X230519Y-42096D01*
Y-43846D01*
X230956Y-45596D01*
X232048Y-47346D01*
X233358Y-48512D01*
X234886Y-48804D01*
X236414Y-48221D01*
X237943Y-46471D01*
G01X251731Y-48804D02*
Y-31304D01*
G01X504231Y-93804D02*
Y-76304D01*
X501611Y-79804D01*
G01Y-93804D02*
X506851D01*
G01X517583Y-86513D02*
X519111Y-84471D01*
X520421Y-83304D01*
X522168Y-82721D01*
X523696Y-83304D01*
X524788Y-84471D01*
X525661Y-86221D01*
X525879Y-88262D01*
X525661Y-90013D01*
X524788Y-91763D01*
X523477Y-93221D01*
X521949Y-93804D01*
X520203Y-93221D01*
X518674Y-91471D01*
X517801Y-88846D01*
X517583Y-85929D01*
X518019Y-82138D01*
X518674Y-80095D01*
X519766Y-78054D01*
X521294Y-76596D01*
X522823Y-76304D01*
X524351Y-76887D01*
X525443Y-78346D01*
G01X534428Y-90304D02*
X535737Y-92346D01*
X537484Y-93512D01*
X539449Y-93804D01*
X541196Y-93512D01*
X542943Y-92054D01*
X544034Y-90304D01*
X544253Y-88554D01*
X543816Y-86513D01*
X542288Y-85054D01*
X540759Y-84471D01*
X538794D01*
G01X540759D02*
X542069Y-83596D01*
X543161Y-82138D01*
X543598Y-80388D01*
X543161Y-78637D01*
X542069Y-77179D01*
X540104Y-76304D01*
X538139Y-76596D01*
X536174Y-77763D01*
G01X559351Y-93804D02*
Y-76304D01*
X551272Y-88846D01*
X562190D01*
G01X570083Y-79221D02*
X571393Y-77471D01*
X572921Y-76596D01*
X574668Y-76304D01*
X576851Y-76887D01*
X578379Y-78346D01*
X578816Y-80095D01*
X578598Y-81846D01*
X577724Y-83304D01*
X573358Y-86221D01*
X571393Y-88262D01*
X570083Y-91180D01*
X569646Y-93804D01*
X578816D01*
G01X491114Y-48804D02*
Y-31304D01*
X496354D01*
X498101Y-32179D01*
X499411Y-34221D01*
X499848Y-36554D01*
X499411Y-38887D01*
X498319Y-40637D01*
X496354Y-41513D01*
X491114D01*
G01X517784Y-32763D02*
X516474Y-31887D01*
X514946Y-31304D01*
X513199D01*
X511234Y-32179D01*
X509706Y-33637D01*
X508614Y-35388D01*
X507741Y-38304D01*
X507522Y-40929D01*
X507959Y-43554D01*
X508614Y-45304D01*
X509924Y-47054D01*
X511453Y-48221D01*
X512981Y-48804D01*
X514509D01*
X516038Y-48221D01*
X517348Y-47346D01*
X518440Y-46180D01*
G01X532227Y-39471D02*
X533101Y-38596D01*
X533756Y-37138D01*
X534193Y-35095D01*
X533756Y-33346D01*
X532883Y-32179D01*
X531354Y-31304D01*
X525459D01*
Y-48804D01*
X532664D01*
X534193Y-47638D01*
X535066Y-45887D01*
X535503Y-43846D01*
X535066Y-41804D01*
X533756Y-40054D01*
X532227Y-39471D01*
X525459D01*
G01X541431Y-54637D02*
X554531D01*
G01X560459Y-48804D02*
Y-31304D01*
X570503Y-48804D01*
Y-31304D01*
G01X582981Y-48804D02*
X581234Y-48512D01*
X579706Y-47346D01*
X578396Y-45596D01*
X577522Y-43554D01*
X577086Y-41221D01*
Y-38887D01*
X577522Y-36554D01*
X578396Y-34512D01*
X579706Y-32763D01*
X581234Y-31596D01*
X582981Y-31304D01*
X584727Y-31596D01*
X586256Y-32763D01*
X587566Y-34512D01*
X588440Y-36554D01*
X588876Y-38887D01*
Y-41221D01*
X588440Y-43554D01*
X587566Y-45596D01*
X586256Y-47346D01*
X584727Y-48512D01*
X582981Y-48804D01*
G01X633822Y-31304D02*
X639281Y-48804D01*
X644740Y-31304D01*
G01X661148Y-48804D02*
X652414D01*
Y-31304D01*
X661148D01*
G01X657654Y-39762D02*
X652414D01*
G01X669914Y-48804D02*
Y-31304D01*
X675373D01*
X677119Y-32179D01*
X678211Y-33346D01*
X678648Y-35679D01*
X678211Y-38013D01*
X676901Y-39471D01*
X675373Y-40346D01*
X669914D01*
G01X675373D02*
X678648Y-48804D01*
G01X691781Y-49387D02*
X691344Y-49096D01*
Y-48512D01*
X691781Y-48221D01*
X692218Y-48512D01*
Y-49096D01*
X691781Y-49387D01*
G01X661383Y-79221D02*
X662693Y-77471D01*
X664221Y-76596D01*
X665968Y-76304D01*
X668151Y-76887D01*
X669679Y-78346D01*
X670116Y-80095D01*
X669898Y-81846D01*
X669024Y-83304D01*
X664658Y-86221D01*
X662693Y-88262D01*
X661383Y-91180D01*
X660946Y-93804D01*
X670116D01*
G01X771731Y-76304D02*
Y-93804D01*
G01X766709Y-76304D02*
X776753D01*
G01X784646Y-91471D02*
X786393Y-92929D01*
X788358Y-93804D01*
X790104D01*
X791851Y-92929D01*
X793161Y-91471D01*
X793816Y-89429D01*
X793379Y-87388D01*
X792288Y-85637D01*
X790323Y-84471D01*
X787703Y-83887D01*
X786174Y-82721D01*
X785519Y-80679D01*
X785956Y-78637D01*
X787048Y-77179D01*
X788576Y-76304D01*
X790104D01*
X791633Y-76887D01*
X792943Y-78346D01*
G01X804111Y-76304D02*
X809351D01*
G01X806731D02*
Y-93804D01*
G01X804111D02*
X809351D01*
G01X819864Y-76304D02*
Y-93804D01*
X828598D01*
G01X836928D02*
Y-76304D01*
G01X845224D02*
X836928Y-87096D01*
G01X846534Y-93804D02*
X840639Y-82138D01*
G01X767364Y-31304D02*
Y-48804D01*
X776098D01*
G01X793161D02*
Y-37138D01*
G01Y-39179D02*
X792288Y-38013D01*
X790977Y-37429D01*
X789449Y-37138D01*
X787921Y-37721D01*
X786611Y-38887D01*
X785737Y-40637D01*
X785301Y-42971D01*
X785737Y-45304D01*
X786611Y-47054D01*
X787921Y-48221D01*
X789449Y-48804D01*
X790977Y-48512D01*
X792288Y-47638D01*
X793161Y-46471D01*
G01X802146Y-54054D02*
X803456Y-54637D01*
X805203Y-54054D01*
X806294Y-52888D01*
X807168Y-51429D01*
X808477Y-46763D01*
X811316Y-37138D01*
G01X804329D02*
X808477Y-46763D01*
G01X820956Y-40929D02*
X827943D01*
X827288Y-38887D01*
X826196Y-37721D01*
X824668Y-37138D01*
X823139Y-37429D01*
X821829Y-38304D01*
X820956Y-40346D01*
X820519Y-42096D01*
Y-43846D01*
X820956Y-45596D01*
X822048Y-47346D01*
X823358Y-48512D01*
X824886Y-48804D01*
X826414Y-48221D01*
X827943Y-46471D01*
G01X838674Y-48804D02*
Y-37138D01*
G01Y-39471D02*
X839766Y-38304D01*
X840858Y-37429D01*
X842386Y-37138D01*
X843477Y-37429D01*
X844788Y-38304D01*
G01X931781Y-93804D02*
X930034Y-93512D01*
X928506Y-92346D01*
X927196Y-90596D01*
X926322Y-88554D01*
X925886Y-86221D01*
Y-83887D01*
X926322Y-81554D01*
X927196Y-79512D01*
X928506Y-77763D01*
X930034Y-76596D01*
X931781Y-76304D01*
X933527Y-76596D01*
X935056Y-77763D01*
X936366Y-79512D01*
X937240Y-81554D01*
X937676Y-83887D01*
Y-86221D01*
X937240Y-88554D01*
X936366Y-90596D01*
X935056Y-92346D01*
X933527Y-93512D01*
X931781Y-93804D01*
G01X933527Y-89137D02*
X936148Y-93804D01*
G01X944478Y-76304D02*
Y-88846D01*
X945351Y-91471D01*
X947098Y-93221D01*
X949281Y-93804D01*
X951464Y-93221D01*
X953211Y-91471D01*
X954084Y-88846D01*
Y-76304D01*
G01X964161D02*
X969401D01*
G01X966781D02*
Y-93804D01*
G01X964161D02*
X969401D01*
G01X979259D02*
Y-76304D01*
X989303Y-93804D01*
Y-76304D01*
G01X1006584Y-77763D02*
X1005274Y-76887D01*
X1003746Y-76304D01*
X1001999D01*
X1000034Y-77179D01*
X998506Y-78637D01*
X997414Y-80388D01*
X996541Y-83304D01*
X996322Y-85929D01*
X996759Y-88554D01*
X997414Y-90304D01*
X998724Y-92054D01*
X1000253Y-93221D01*
X1001781Y-93804D01*
X1003309D01*
X1004838Y-93221D01*
X1006148Y-92346D01*
X1007240Y-91180D01*
G01X1019281Y-93804D02*
Y-85929D01*
X1014914Y-76304D01*
G01X1023648D02*
X1019281Y-85929D01*
G01X909478Y-48804D02*
Y-31304D01*
X913844D01*
X915591Y-32179D01*
X916901Y-33346D01*
X917993Y-35095D01*
X918866Y-37138D01*
X919084Y-40054D01*
X918866Y-42971D01*
X917993Y-45013D01*
X916901Y-46763D01*
X915591Y-47929D01*
X913844Y-48804D01*
X909478D01*
G01X928506Y-40929D02*
X935493D01*
X934838Y-38887D01*
X933746Y-37721D01*
X932218Y-37138D01*
X930689Y-37429D01*
X929379Y-38304D01*
X928506Y-40346D01*
X928069Y-42096D01*
Y-43846D01*
X928506Y-45596D01*
X929598Y-47346D01*
X930908Y-48512D01*
X932436Y-48804D01*
X933964Y-48221D01*
X935493Y-46471D01*
G01X946006Y-46763D02*
X947098Y-47929D01*
X948626Y-48804D01*
X949936D01*
X951246Y-48221D01*
X952119Y-47346D01*
X952556Y-46180D01*
X952338Y-44429D01*
X951464Y-43554D01*
X947534Y-41804D01*
X946661Y-39762D01*
X947098Y-38304D01*
X947971Y-37429D01*
X949281Y-37138D01*
X950591Y-37429D01*
X951901Y-38304D01*
G01X966781Y-37138D02*
Y-48804D01*
G01Y-32471D02*
X966344Y-32179D01*
Y-31596D01*
X966781Y-31304D01*
X967218Y-31596D01*
Y-32179D01*
X966781Y-32471D01*
G01X981224Y-53179D02*
X982753Y-54346D01*
X984499Y-54637D01*
X986027Y-54346D01*
X987338Y-52888D01*
X988211Y-50846D01*
Y-37138D01*
G01Y-39471D02*
X987338Y-38304D01*
X986027Y-37429D01*
X984499Y-37138D01*
X982753Y-37721D01*
X981661Y-38887D01*
X980787Y-40929D01*
X980351Y-42971D01*
X980569Y-44721D01*
X981443Y-46763D01*
X982753Y-48221D01*
X984499Y-48804D01*
X985809Y-48512D01*
X987338Y-47346D01*
X988211Y-46180D01*
G01X998069Y-48804D02*
Y-37138D01*
G01Y-40054D02*
X998943Y-38596D01*
X1000253Y-37429D01*
X1001999Y-37138D01*
X1003527Y-37429D01*
X1004838Y-38596D01*
X1005493Y-40637D01*
Y-48804D01*
G01X1016006Y-40929D02*
X1022993D01*
X1022338Y-38887D01*
X1021246Y-37721D01*
X1019718Y-37138D01*
X1018189Y-37429D01*
X1016879Y-38304D01*
X1016006Y-40346D01*
X1015569Y-42096D01*
Y-43846D01*
X1016006Y-45596D01*
X1017098Y-47346D01*
X1018408Y-48512D01*
X1019936Y-48804D01*
X1021464Y-48221D01*
X1022993Y-46471D01*
G01X1033724Y-48804D02*
Y-37138D01*
G01Y-39471D02*
X1034816Y-38304D01*
X1035908Y-37429D01*
X1037436Y-37138D01*
X1038527Y-37429D01*
X1039838Y-38304D01*
G01X1080481Y-76304D02*
X1078734Y-76887D01*
X1077424Y-78346D01*
X1076551Y-80095D01*
X1075896Y-82429D01*
X1075678Y-85054D01*
X1075896Y-87679D01*
X1076551Y-90013D01*
X1077424Y-91763D01*
X1078734Y-93221D01*
X1080481Y-93804D01*
X1082227Y-93221D01*
X1083538Y-91763D01*
X1084411Y-90013D01*
X1085066Y-87679D01*
X1085284Y-85054D01*
X1085066Y-82429D01*
X1084411Y-80095D01*
X1083538Y-78346D01*
X1082227Y-76887D01*
X1080481Y-76304D01*
G01X1097981Y-93804D02*
X1099509Y-93512D01*
X1101256Y-92638D01*
X1102348Y-91180D01*
X1102784Y-89137D01*
X1102348Y-87096D01*
X1101038Y-85346D01*
X1099073Y-84471D01*
X1096889D01*
X1095579Y-83887D01*
X1094487Y-82429D01*
X1094051Y-80388D01*
X1094706Y-78346D01*
X1096234Y-76887D01*
X1097981Y-76304D01*
X1099727Y-76887D01*
X1101256Y-78346D01*
X1101911Y-80388D01*
X1101474Y-82429D01*
X1100383Y-83887D01*
X1099073Y-84471D01*
X1096889D01*
X1094924Y-85346D01*
X1093614Y-87096D01*
X1093178Y-89137D01*
X1093614Y-91180D01*
X1094706Y-92638D01*
X1096453Y-93512D01*
X1097981Y-93804D01*
G01X1111551Y-94387D02*
X1119411Y-76304D01*
G01X1132981D02*
X1131234Y-76887D01*
X1129924Y-78346D01*
X1129051Y-80095D01*
X1128396Y-82429D01*
X1128178Y-85054D01*
X1128396Y-87679D01*
X1129051Y-90013D01*
X1129924Y-91763D01*
X1131234Y-93221D01*
X1132981Y-93804D01*
X1134727Y-93221D01*
X1136038Y-91763D01*
X1136911Y-90013D01*
X1137566Y-87679D01*
X1137784Y-85054D01*
X1137566Y-82429D01*
X1136911Y-80095D01*
X1136038Y-78346D01*
X1134727Y-76887D01*
X1132981Y-76304D01*
G01X1150044Y-93804D02*
X1150481Y-90013D01*
X1151136Y-86804D01*
X1152009Y-83887D01*
X1153101Y-80679D01*
X1154848Y-76304D01*
X1146114D01*
G01X1164051Y-94387D02*
X1171911Y-76304D01*
G01X1181333Y-79221D02*
X1182643Y-77471D01*
X1184171Y-76596D01*
X1185918Y-76304D01*
X1188101Y-76887D01*
X1189629Y-78346D01*
X1190066Y-80095D01*
X1189848Y-81846D01*
X1188974Y-83304D01*
X1184608Y-86221D01*
X1182643Y-88262D01*
X1181333Y-91180D01*
X1180896Y-93804D01*
X1190066D01*
G01X1202981Y-76304D02*
X1201234Y-76887D01*
X1199924Y-78346D01*
X1199051Y-80095D01*
X1198396Y-82429D01*
X1198178Y-85054D01*
X1198396Y-87679D01*
X1199051Y-90013D01*
X1199924Y-91763D01*
X1201234Y-93221D01*
X1202981Y-93804D01*
X1204727Y-93221D01*
X1206038Y-91763D01*
X1206911Y-90013D01*
X1207566Y-87679D01*
X1207784Y-85054D01*
X1207566Y-82429D01*
X1206911Y-80095D01*
X1206038Y-78346D01*
X1204727Y-76887D01*
X1202981Y-76304D01*
G01X1220481Y-93804D02*
Y-76304D01*
X1217861Y-79804D01*
G01Y-93804D02*
X1223101D01*
G01X1237544D02*
X1237981Y-90013D01*
X1238636Y-86804D01*
X1239509Y-83887D01*
X1240601Y-80679D01*
X1242348Y-76304D01*
X1233614D01*
G01X1128178Y-48804D02*
Y-31304D01*
X1132544D01*
X1134291Y-32179D01*
X1135601Y-33346D01*
X1136693Y-35095D01*
X1137566Y-37138D01*
X1137784Y-40054D01*
X1137566Y-42971D01*
X1136693Y-45013D01*
X1135601Y-46763D01*
X1134291Y-47929D01*
X1132544Y-48804D01*
X1128178D01*
G01X1154411D02*
Y-37138D01*
G01Y-39179D02*
X1153538Y-38013D01*
X1152227Y-37429D01*
X1150699Y-37138D01*
X1149171Y-37721D01*
X1147861Y-38887D01*
X1146987Y-40637D01*
X1146551Y-42971D01*
X1146987Y-45304D01*
X1147861Y-47054D01*
X1149171Y-48221D01*
X1150699Y-48804D01*
X1152227Y-48512D01*
X1153538Y-47638D01*
X1154411Y-46471D01*
G01X1167981Y-31304D02*
Y-48804D01*
G01X1164924Y-37138D02*
X1171038D01*
G01X1182206Y-40929D02*
X1189193D01*
X1188538Y-38887D01*
X1187446Y-37721D01*
X1185918Y-37138D01*
X1184389Y-37429D01*
X1183079Y-38304D01*
X1182206Y-40346D01*
X1181769Y-42096D01*
Y-43846D01*
X1182206Y-45596D01*
X1183298Y-47346D01*
X1184608Y-48512D01*
X1186136Y-48804D01*
X1187664Y-48221D01*
X1189193Y-46471D01*
G01X69575Y61830D02*
X67075D01*
Y62871D01*
X67200Y63205D01*
X67367Y63413D01*
X67700Y63496D01*
X68033Y63413D01*
X68242Y63163D01*
X68367Y62871D01*
Y61830D01*
G01Y62871D02*
X69575Y63496D01*
G01Y66263D02*
X67075D01*
X68867Y64721D01*
Y66805D01*
G01X69575Y68863D02*
X69533Y69155D01*
X69408Y69488D01*
X69200Y69696D01*
X68908Y69780D01*
X68617Y69696D01*
X68367Y69446D01*
X68242Y69071D01*
Y68655D01*
X68158Y68405D01*
X67950Y68196D01*
X67658Y68113D01*
X67367Y68238D01*
X67158Y68530D01*
X67075Y68863D01*
X67158Y69196D01*
X67367Y69488D01*
X67658Y69613D01*
X67950Y69530D01*
X68158Y69321D01*
X68242Y69071D01*
Y68655D01*
X68367Y68280D01*
X68617Y68030D01*
X68908Y67946D01*
X69200Y68030D01*
X69408Y68238D01*
X69533Y68571D01*
X69575Y68863D01*
G01X30265Y48484D02*
X27765D01*
Y49525D01*
X27890Y49859D01*
X28057Y50067D01*
X28390Y50150D01*
X28723Y50067D01*
X28932Y49817D01*
X29057Y49525D01*
Y48484D01*
G01Y49525D02*
X30265Y50150D01*
G01X29223Y51625D02*
X28932Y51917D01*
X28765Y52167D01*
X28682Y52500D01*
X28765Y52792D01*
X28932Y53000D01*
X29182Y53167D01*
X29473Y53209D01*
X29723Y53167D01*
X29973Y53000D01*
X30182Y52750D01*
X30265Y52459D01*
X30182Y52125D01*
X29932Y51834D01*
X29557Y51667D01*
X29140Y51625D01*
X28598Y51709D01*
X28307Y51834D01*
X28015Y52042D01*
X27807Y52334D01*
X27765Y52625D01*
X27848Y52917D01*
X28057Y53125D01*
G01X29890Y54600D02*
X30098Y54850D01*
X30223Y55142D01*
X30265Y55517D01*
X30182Y55892D01*
X30015Y56184D01*
X29723Y56392D01*
X29390Y56434D01*
X29057Y56350D01*
X28848Y56142D01*
X28682Y55850D01*
X28640Y55559D01*
X28682Y55267D01*
X28848Y54892D01*
X27765Y55017D01*
Y56142D01*
G01X40500Y55200D02*
X36500D01*
Y47800D01*
G01X63441Y43461D02*
Y45961D01*
X64482D01*
X64816Y45836D01*
X65024Y45669D01*
X65107Y45336D01*
X65024Y45003D01*
X64774Y44794D01*
X64482Y44669D01*
X63441D01*
G01X64482D02*
X65107Y43461D01*
G01X67874D02*
Y45961D01*
X66332Y44169D01*
X68416D01*
G01X70391Y43461D02*
X70474Y44003D01*
X70599Y44461D01*
X70766Y44878D01*
X70974Y45336D01*
X71307Y45961D01*
X69641D01*
G01X60700Y43000D02*
Y47000D01*
X53300D01*
G01X63283Y63580D02*
X63158Y63330D01*
X63075Y63038D01*
Y62705D01*
X63200Y62330D01*
X63408Y62038D01*
X63658Y61830D01*
X64075Y61663D01*
X64450Y61621D01*
X64825Y61705D01*
X65075Y61830D01*
X65325Y62080D01*
X65492Y62371D01*
X65575Y62663D01*
Y62955D01*
X65492Y63246D01*
X65367Y63496D01*
X65200Y63705D01*
G01X63492Y64971D02*
X63242Y65221D01*
X63117Y65513D01*
X63075Y65846D01*
X63158Y66263D01*
X63367Y66555D01*
X63617Y66638D01*
X63867Y66596D01*
X64075Y66430D01*
X64492Y65596D01*
X64783Y65221D01*
X65200Y64971D01*
X65575Y64888D01*
Y66638D01*
G01X64533Y68071D02*
X64242Y68363D01*
X64075Y68613D01*
X63992Y68946D01*
X64075Y69238D01*
X64242Y69446D01*
X64492Y69613D01*
X64783Y69655D01*
X65033Y69613D01*
X65283Y69446D01*
X65492Y69196D01*
X65575Y68905D01*
X65492Y68571D01*
X65242Y68280D01*
X64867Y68113D01*
X64450Y68071D01*
X63908Y68155D01*
X63617Y68280D01*
X63325Y68488D01*
X63117Y68780D01*
X63075Y69071D01*
X63158Y69363D01*
X63367Y69571D01*
G01X23473Y50234D02*
X23348Y49984D01*
X23265Y49692D01*
Y49359D01*
X23390Y48984D01*
X23598Y48692D01*
X23848Y48484D01*
X24265Y48317D01*
X24640Y48275D01*
X25015Y48359D01*
X25265Y48484D01*
X25515Y48734D01*
X25682Y49025D01*
X25765Y49317D01*
Y49609D01*
X25682Y49900D01*
X25557Y50150D01*
X25390Y50359D01*
G01X25265Y51500D02*
X25557Y51750D01*
X25723Y52084D01*
X25765Y52459D01*
X25723Y52792D01*
X25515Y53125D01*
X25265Y53334D01*
X25015Y53375D01*
X24723Y53292D01*
X24515Y53000D01*
X24432Y52709D01*
Y52334D01*
G01Y52709D02*
X24307Y52959D01*
X24098Y53167D01*
X23848Y53250D01*
X23598Y53167D01*
X23390Y52959D01*
X23265Y52584D01*
X23307Y52209D01*
X23473Y51834D01*
G01X25765Y55517D02*
X23265D01*
X23765Y55017D01*
G01X25765D02*
Y56017D01*
G01X15837Y37151D02*
Y39651D01*
X16878D01*
X17212Y39526D01*
X17420Y39359D01*
X17503Y39026D01*
X17420Y38693D01*
X17170Y38484D01*
X16878Y38359D01*
X15837D01*
G01X16878D02*
X17503Y37151D01*
G01X18895Y37484D02*
X19228Y37276D01*
X19603Y37151D01*
X19937D01*
X20270Y37276D01*
X20520Y37484D01*
X20645Y37776D01*
X20562Y38068D01*
X20353Y38318D01*
X19978Y38484D01*
X19478Y38568D01*
X19187Y38734D01*
X19062Y39026D01*
X19145Y39318D01*
X19353Y39526D01*
X19645Y39651D01*
X19937D01*
X20228Y39568D01*
X20478Y39359D01*
G01X22870Y39651D02*
Y37151D01*
G01X21912Y39651D02*
X23828D01*
G01X25970Y37151D02*
Y39651D01*
X25470Y39151D01*
G01Y37151D02*
X26470D01*
G01X39344Y506D02*
Y11906D01*
X31694D01*
Y30706D01*
X29644D01*
Y41306D01*
X64844D01*
Y30706D01*
X62794D01*
Y11906D01*
X55144D01*
Y506D01*
X39344D01*
G01X44500Y61533D02*
X42000D01*
Y62367D01*
X42125Y62700D01*
X42292Y62950D01*
X42542Y63158D01*
X42833Y63325D01*
X43250Y63367D01*
X43667Y63325D01*
X43958Y63158D01*
X44208Y62950D01*
X44375Y62700D01*
X44500Y62367D01*
Y61533D01*
G01X44000Y64633D02*
X44292Y64883D01*
X44458Y65217D01*
X44500Y65592D01*
X44458Y65925D01*
X44250Y66258D01*
X44000Y66467D01*
X43750Y66508D01*
X43458Y66425D01*
X43250Y66133D01*
X43167Y65842D01*
Y65467D01*
G01Y65842D02*
X43042Y66092D01*
X42833Y66300D01*
X42583Y66383D01*
X42333Y66300D01*
X42125Y66092D01*
X42000Y65717D01*
X42042Y65342D01*
X42208Y64967D01*
G01X45100Y45500D02*
X40900D01*
G01X45100Y57200D02*
Y45500D01*
G01X40900Y57200D02*
X45100D01*
G01X40900Y45500D02*
Y57200D01*
G01X55930Y60089D02*
X55680Y60214D01*
X55388Y60297D01*
X55055D01*
X54680Y60172D01*
X54388Y59964D01*
X54180Y59714D01*
X54013Y59297D01*
X53971Y58922D01*
X54055Y58547D01*
X54180Y58297D01*
X54430Y58047D01*
X54721Y57880D01*
X55013Y57797D01*
X55305D01*
X55596Y57880D01*
X55846Y58005D01*
X56055Y58172D01*
G01X57196D02*
X57446Y57964D01*
X57738Y57839D01*
X58113Y57797D01*
X58488Y57880D01*
X58780Y58047D01*
X58988Y58339D01*
X59030Y58672D01*
X58946Y59005D01*
X58738Y59214D01*
X58446Y59380D01*
X58155Y59422D01*
X57863Y59380D01*
X57488Y59214D01*
X57613Y60297D01*
X58738D01*
G01X60421Y59880D02*
X60671Y60130D01*
X60963Y60255D01*
X61296Y60297D01*
X61713Y60214D01*
X62005Y60005D01*
X62088Y59755D01*
X62046Y59505D01*
X61880Y59297D01*
X61046Y58880D01*
X60671Y58589D01*
X60421Y58172D01*
X60338Y57797D01*
X62088D01*
G01X63605Y58089D02*
X63896Y57880D01*
X64230Y57797D01*
X64563Y57880D01*
X64855Y58130D01*
X65063Y58505D01*
X65146Y58880D01*
Y59339D01*
X65063Y59714D01*
X64855Y60047D01*
X64605Y60214D01*
X64313Y60297D01*
X63980Y60214D01*
X63730Y60047D01*
X63563Y59797D01*
X63480Y59464D01*
X63563Y59172D01*
X63771Y58880D01*
X64021Y58714D01*
X64313Y58672D01*
X64646Y58755D01*
X64896Y58964D01*
X65146Y59339D01*
G01X53200Y48000D02*
X47700D01*
Y56000D01*
X53300D01*
G01X65300Y48000D02*
X59800D01*
G01X65300D02*
Y56000D01*
X59800D01*
G01X23600Y171400D02*
Y143600D01*
X51400D01*
Y171400D01*
X23600D01*
G01X61100D02*
Y143600D01*
X88900D01*
Y171400D01*
X61100D01*
G01X114500Y416669D02*
Y451952D01*
X44500D01*
Y457169D01*
X13500D01*
Y416669D01*
X80400D01*
G01X23300Y422320D02*
X20800D01*
Y423361D01*
X20925Y423695D01*
X21092Y423903D01*
X21425Y423986D01*
X21758Y423903D01*
X21967Y423653D01*
X22092Y423361D01*
Y422320D01*
G01Y423361D02*
X23300Y423986D01*
G01X22800Y425336D02*
X23092Y425586D01*
X23258Y425920D01*
X23300Y426295D01*
X23258Y426628D01*
X23050Y426961D01*
X22800Y427170D01*
X22550Y427211D01*
X22258Y427128D01*
X22050Y426836D01*
X21967Y426545D01*
Y426170D01*
G01Y426545D02*
X21842Y426795D01*
X21633Y427003D01*
X21383Y427086D01*
X21133Y427003D01*
X20925Y426795D01*
X20800Y426420D01*
X20842Y426045D01*
X21008Y425670D01*
G01X23300Y429270D02*
X22758Y429353D01*
X22300Y429478D01*
X21883Y429645D01*
X21425Y429853D01*
X20800Y430186D01*
Y428520D01*
G01X23300Y432370D02*
X22758Y432453D01*
X22300Y432578D01*
X21883Y432745D01*
X21425Y432953D01*
X20800Y433286D01*
Y431620D01*
G01X48172Y420749D02*
X50672D01*
G01X48172Y419791D02*
Y421707D01*
G01X50672Y423016D02*
X48172D01*
Y424016D01*
X48297Y424349D01*
X48589Y424599D01*
X48922Y424682D01*
X49255Y424599D01*
X49505Y424391D01*
X49630Y424016D01*
Y423016D01*
G01X48589Y426157D02*
X48339Y426407D01*
X48214Y426699D01*
X48172Y427032D01*
X48255Y427449D01*
X48464Y427741D01*
X48714Y427824D01*
X48964Y427782D01*
X49172Y427616D01*
X49589Y426782D01*
X49880Y426407D01*
X50297Y426157D01*
X50672Y426074D01*
Y427824D01*
G01X48172Y430049D02*
X48255Y429716D01*
X48464Y429466D01*
X48714Y429299D01*
X49047Y429174D01*
X49422Y429132D01*
X49797Y429174D01*
X50130Y429299D01*
X50380Y429466D01*
X50589Y429716D01*
X50672Y430049D01*
X50589Y430382D01*
X50380Y430632D01*
X50130Y430799D01*
X49797Y430924D01*
X49422Y430966D01*
X49047Y430924D01*
X48714Y430799D01*
X48464Y430632D01*
X48255Y430382D01*
X48172Y430049D01*
G01X50672Y433649D02*
X48172D01*
X49964Y432107D01*
Y434191D01*
G01X33067Y449900D02*
X33600Y450250D01*
X34000Y450834D01*
X34267Y451650D01*
X34000Y452350D01*
X33467Y452817D01*
X32533Y453167D01*
X28933D01*
Y446167D01*
X33333D01*
X34267Y446634D01*
X34800Y447334D01*
X35067Y448150D01*
X34800Y448967D01*
X34000Y449667D01*
X33067Y449900D01*
X28933D01*
G01X18300Y461500D02*
X18217Y460833D01*
X17883Y460250D01*
X17383Y459750D01*
X16800Y459417D01*
X16133Y459250D01*
X15467D01*
X14800Y459417D01*
X14217Y459750D01*
X13717Y460250D01*
X13383Y460833D01*
X13300Y461500D01*
X13383Y462167D01*
X13717Y462750D01*
X14217Y463250D01*
X14800Y463583D01*
X15467Y463750D01*
X16133D01*
X16800Y463583D01*
X17383Y463250D01*
X17883Y462750D01*
X18217Y462167D01*
X18300Y461500D01*
G01X17633Y465350D02*
X18050Y466017D01*
X18300Y466767D01*
Y467433D01*
X18050Y468100D01*
X17633Y468600D01*
X17050Y468850D01*
X16467Y468683D01*
X15967Y468267D01*
X15633Y467517D01*
X15467Y466517D01*
X15133Y465933D01*
X14550Y465683D01*
X13967Y465850D01*
X13550Y466267D01*
X13300Y466850D01*
Y467433D01*
X13467Y468017D01*
X13883Y468517D01*
G01X13717Y474533D02*
X13467Y474033D01*
X13300Y473450D01*
Y472783D01*
X13550Y472033D01*
X13967Y471450D01*
X14467Y471033D01*
X15300Y470700D01*
X16050Y470617D01*
X16800Y470783D01*
X17300Y471033D01*
X17800Y471533D01*
X18133Y472117D01*
X18300Y472700D01*
Y473283D01*
X18133Y473867D01*
X17883Y474367D01*
X17550Y474783D01*
G01X18300Y478300D02*
X13300D01*
X14300Y477300D01*
G01X18300D02*
Y479300D01*
G01X18467Y483900D02*
X18383Y483733D01*
X18217D01*
X18133Y483900D01*
X18217Y484067D01*
X18383D01*
X18467Y483900D01*
G01X16217D02*
X16133Y483733D01*
X15967D01*
X15883Y483900D01*
X15967Y484067D01*
X16133D01*
X16217Y483900D01*
G01X14133Y487917D02*
X13633Y488417D01*
X13383Y489000D01*
X13300Y489667D01*
X13467Y490500D01*
X13883Y491083D01*
X14383Y491250D01*
X14883Y491167D01*
X15300Y490833D01*
X16133Y489167D01*
X16717Y488417D01*
X17550Y487917D01*
X18300Y487750D01*
Y491250D01*
G01Y496100D02*
X13300D01*
X16883Y493017D01*
Y497183D01*
G01X18300Y498533D02*
X13300D01*
X17467Y500700D01*
X13300Y502867D01*
X18300D01*
G01Y504550D02*
X13300D01*
G01Y508050D02*
X18300D01*
G01X15800D02*
Y504550D01*
G01X13300Y510317D02*
Y513483D01*
X18300Y510317D01*
Y513483D01*
G01X23136Y435920D02*
X20636D01*
Y436961D01*
X20761Y437295D01*
X20928Y437503D01*
X21261Y437586D01*
X21594Y437503D01*
X21803Y437253D01*
X21928Y436961D01*
Y435920D01*
G01Y436961D02*
X23136Y437586D01*
G01X22636Y438936D02*
X22928Y439186D01*
X23094Y439520D01*
X23136Y439895D01*
X23094Y440228D01*
X22886Y440561D01*
X22636Y440770D01*
X22386Y440811D01*
X22094Y440728D01*
X21886Y440436D01*
X21803Y440145D01*
Y439770D01*
G01Y440145D02*
X21678Y440395D01*
X21469Y440603D01*
X21219Y440686D01*
X20969Y440603D01*
X20761Y440395D01*
X20636Y440020D01*
X20678Y439645D01*
X20844Y439270D01*
G01X23136Y442870D02*
X22594Y442953D01*
X22136Y443078D01*
X21719Y443245D01*
X21261Y443453D01*
X20636Y443786D01*
Y442120D01*
G01X22844Y445345D02*
X23053Y445636D01*
X23136Y445970D01*
X23053Y446303D01*
X22803Y446595D01*
X22428Y446803D01*
X22053Y446886D01*
X21594D01*
X21219Y446803D01*
X20886Y446595D01*
X20719Y446345D01*
X20636Y446053D01*
X20719Y445720D01*
X20886Y445470D01*
X21136Y445303D01*
X21469Y445220D01*
X21761Y445303D01*
X22053Y445511D01*
X22219Y445761D01*
X22261Y446053D01*
X22178Y446386D01*
X21969Y446636D01*
X21594Y446886D01*
G01X29276Y431979D02*
X26776D01*
Y433020D01*
X26901Y433354D01*
X27068Y433562D01*
X27401Y433645D01*
X27734Y433562D01*
X27943Y433312D01*
X28068Y433020D01*
Y431979D01*
G01Y433020D02*
X29276Y433645D01*
G01X28776Y434995D02*
X29068Y435245D01*
X29234Y435579D01*
X29276Y435954D01*
X29234Y436287D01*
X29026Y436620D01*
X28776Y436829D01*
X28526Y436870D01*
X28234Y436787D01*
X28026Y436495D01*
X27943Y436204D01*
Y435829D01*
G01Y436204D02*
X27818Y436454D01*
X27609Y436662D01*
X27359Y436745D01*
X27109Y436662D01*
X26901Y436454D01*
X26776Y436079D01*
X26818Y435704D01*
X26984Y435329D01*
G01X29276Y438929D02*
X28734Y439012D01*
X28276Y439137D01*
X27859Y439304D01*
X27401Y439512D01*
X26776Y439845D01*
Y438179D01*
G01X29276Y442112D02*
X29234Y442404D01*
X29109Y442737D01*
X28901Y442945D01*
X28609Y443029D01*
X28318Y442945D01*
X28068Y442695D01*
X27943Y442320D01*
Y441904D01*
X27859Y441654D01*
X27651Y441445D01*
X27359Y441362D01*
X27068Y441487D01*
X26859Y441779D01*
X26776Y442112D01*
X26859Y442445D01*
X27068Y442737D01*
X27359Y442862D01*
X27651Y442779D01*
X27859Y442570D01*
X27943Y442320D01*
Y441904D01*
X28068Y441529D01*
X28318Y441279D01*
X28609Y441195D01*
X28901Y441279D01*
X29109Y441487D01*
X29234Y441820D01*
X29276Y442112D01*
G01X33488Y432077D02*
X30988D01*
Y433118D01*
X31113Y433452D01*
X31280Y433660D01*
X31613Y433743D01*
X31946Y433660D01*
X32155Y433410D01*
X32280Y433118D01*
Y432077D01*
G01Y433118D02*
X33488Y433743D01*
G01X32988Y435093D02*
X33280Y435343D01*
X33446Y435677D01*
X33488Y436052D01*
X33446Y436385D01*
X33238Y436718D01*
X32988Y436927D01*
X32738Y436968D01*
X32446Y436885D01*
X32238Y436593D01*
X32155Y436302D01*
Y435927D01*
G01Y436302D02*
X32030Y436552D01*
X31821Y436760D01*
X31571Y436843D01*
X31321Y436760D01*
X31113Y436552D01*
X30988Y436177D01*
X31030Y435802D01*
X31196Y435427D01*
G01X33488Y439027D02*
X32946Y439110D01*
X32488Y439235D01*
X32071Y439402D01*
X31613Y439610D01*
X30988Y439943D01*
Y438277D01*
G01X32446Y441418D02*
X32155Y441710D01*
X31988Y441960D01*
X31905Y442293D01*
X31988Y442585D01*
X32155Y442793D01*
X32405Y442960D01*
X32696Y443002D01*
X32946Y442960D01*
X33196Y442793D01*
X33405Y442543D01*
X33488Y442252D01*
X33405Y441918D01*
X33155Y441627D01*
X32780Y441460D01*
X32363Y441418D01*
X31821Y441502D01*
X31530Y441627D01*
X31238Y441835D01*
X31030Y442127D01*
X30988Y442418D01*
X31071Y442710D01*
X31280Y442918D01*
G01X18208Y422566D02*
X15708D01*
Y423607D01*
X15833Y423941D01*
X16000Y424149D01*
X16333Y424232D01*
X16666Y424149D01*
X16875Y423899D01*
X17000Y423607D01*
Y422566D01*
G01Y423607D02*
X18208Y424232D01*
G01X17708Y425582D02*
X18000Y425832D01*
X18166Y426166D01*
X18208Y426541D01*
X18166Y426874D01*
X17958Y427207D01*
X17708Y427416D01*
X17458Y427457D01*
X17166Y427374D01*
X16958Y427082D01*
X16875Y426791D01*
Y426416D01*
G01Y426791D02*
X16750Y427041D01*
X16541Y427249D01*
X16291Y427332D01*
X16041Y427249D01*
X15833Y427041D01*
X15708Y426666D01*
X15750Y426291D01*
X15916Y425916D01*
G01X15708Y429599D02*
X15791Y429266D01*
X16000Y429016D01*
X16250Y428849D01*
X16583Y428724D01*
X16958Y428682D01*
X17333Y428724D01*
X17666Y428849D01*
X17916Y429016D01*
X18125Y429266D01*
X18208Y429599D01*
X18125Y429932D01*
X17916Y430182D01*
X17666Y430349D01*
X17333Y430474D01*
X16958Y430516D01*
X16583Y430474D01*
X16250Y430349D01*
X16000Y430182D01*
X15791Y429932D01*
X15708Y429599D01*
G01X18208Y432699D02*
X18166Y432991D01*
X18041Y433324D01*
X17833Y433532D01*
X17541Y433616D01*
X17250Y433532D01*
X17000Y433282D01*
X16875Y432907D01*
Y432491D01*
X16791Y432241D01*
X16583Y432032D01*
X16291Y431949D01*
X16000Y432074D01*
X15791Y432366D01*
X15708Y432699D01*
X15791Y433032D01*
X16000Y433324D01*
X16291Y433449D01*
X16583Y433366D01*
X16791Y433157D01*
X16875Y432907D01*
Y432491D01*
X17000Y432116D01*
X17250Y431866D01*
X17541Y431782D01*
X17833Y431866D01*
X18041Y432074D01*
X18166Y432407D01*
X18208Y432699D01*
G01X58535Y431556D02*
X56035D01*
Y432597D01*
X56160Y432931D01*
X56327Y433139D01*
X56660Y433222D01*
X56993Y433139D01*
X57202Y432889D01*
X57327Y432597D01*
Y431556D01*
G01Y432597D02*
X58535Y433222D01*
G01X56452Y434697D02*
X56202Y434947D01*
X56077Y435239D01*
X56035Y435572D01*
X56118Y435989D01*
X56327Y436281D01*
X56577Y436364D01*
X56827Y436322D01*
X57035Y436156D01*
X57452Y435322D01*
X57743Y434947D01*
X58160Y434697D01*
X58535Y434614D01*
Y436364D01*
G01X57493Y437797D02*
X57202Y438089D01*
X57035Y438339D01*
X56952Y438672D01*
X57035Y438964D01*
X57202Y439172D01*
X57452Y439339D01*
X57743Y439381D01*
X57993Y439339D01*
X58243Y439172D01*
X58452Y438922D01*
X58535Y438631D01*
X58452Y438297D01*
X58202Y438006D01*
X57827Y437839D01*
X57410Y437797D01*
X56868Y437881D01*
X56577Y438006D01*
X56285Y438214D01*
X56077Y438506D01*
X56035Y438797D01*
X56118Y439089D01*
X56327Y439297D01*
G01X58160Y440772D02*
X58368Y441022D01*
X58493Y441314D01*
X58535Y441689D01*
X58452Y442064D01*
X58285Y442356D01*
X57993Y442564D01*
X57660Y442606D01*
X57327Y442522D01*
X57118Y442314D01*
X56952Y442022D01*
X56910Y441731D01*
X56952Y441439D01*
X57118Y441064D01*
X56035Y441189D01*
Y442314D01*
G01X54477Y432864D02*
X51977D01*
Y433905D01*
X52102Y434239D01*
X52269Y434447D01*
X52602Y434530D01*
X52935Y434447D01*
X53144Y434197D01*
X53269Y433905D01*
Y432864D01*
G01Y433905D02*
X54477Y434530D01*
G01X52394Y436005D02*
X52144Y436255D01*
X52019Y436547D01*
X51977Y436880D01*
X52060Y437297D01*
X52269Y437589D01*
X52519Y437672D01*
X52769Y437630D01*
X52977Y437464D01*
X53394Y436630D01*
X53685Y436255D01*
X54102Y436005D01*
X54477Y435922D01*
Y437672D01*
G01X53435Y439105D02*
X53144Y439397D01*
X52977Y439647D01*
X52894Y439980D01*
X52977Y440272D01*
X53144Y440480D01*
X53394Y440647D01*
X53685Y440689D01*
X53935Y440647D01*
X54185Y440480D01*
X54394Y440230D01*
X54477Y439939D01*
X54394Y439605D01*
X54144Y439314D01*
X53769Y439147D01*
X53352Y439105D01*
X52810Y439189D01*
X52519Y439314D01*
X52227Y439522D01*
X52019Y439814D01*
X51977Y440105D01*
X52060Y440397D01*
X52269Y440605D01*
G01X54477Y443497D02*
X51977D01*
X53769Y441955D01*
Y444039D01*
G01X37457Y432466D02*
X34957D01*
Y433507D01*
X35082Y433841D01*
X35249Y434049D01*
X35582Y434132D01*
X35915Y434049D01*
X36124Y433799D01*
X36249Y433507D01*
Y432466D01*
G01Y433507D02*
X37457Y434132D01*
G01X35374Y435607D02*
X35124Y435857D01*
X34999Y436149D01*
X34957Y436482D01*
X35040Y436899D01*
X35249Y437191D01*
X35499Y437274D01*
X35749Y437232D01*
X35957Y437066D01*
X36374Y436232D01*
X36665Y435857D01*
X37082Y435607D01*
X37457Y435524D01*
Y437274D01*
G01X36415Y438707D02*
X36124Y438999D01*
X35957Y439249D01*
X35874Y439582D01*
X35957Y439874D01*
X36124Y440082D01*
X36374Y440249D01*
X36665Y440291D01*
X36915Y440249D01*
X37165Y440082D01*
X37374Y439832D01*
X37457Y439541D01*
X37374Y439207D01*
X37124Y438916D01*
X36749Y438749D01*
X36332Y438707D01*
X35790Y438791D01*
X35499Y438916D01*
X35207Y439124D01*
X34999Y439416D01*
X34957Y439707D01*
X35040Y439999D01*
X35249Y440207D01*
G01X36957Y441682D02*
X37249Y441932D01*
X37415Y442266D01*
X37457Y442641D01*
X37415Y442974D01*
X37207Y443307D01*
X36957Y443516D01*
X36707Y443557D01*
X36415Y443474D01*
X36207Y443182D01*
X36124Y442891D01*
Y442516D01*
G01Y442891D02*
X35999Y443141D01*
X35790Y443349D01*
X35540Y443432D01*
X35290Y443349D01*
X35082Y443141D01*
X34957Y442766D01*
X34999Y442391D01*
X35165Y442016D01*
G01X41557Y432466D02*
X39057D01*
Y433507D01*
X39182Y433841D01*
X39349Y434049D01*
X39682Y434132D01*
X40015Y434049D01*
X40224Y433799D01*
X40349Y433507D01*
Y432466D01*
G01Y433507D02*
X41557Y434132D01*
G01X39474Y435607D02*
X39224Y435857D01*
X39099Y436149D01*
X39057Y436482D01*
X39140Y436899D01*
X39349Y437191D01*
X39599Y437274D01*
X39849Y437232D01*
X40057Y437066D01*
X40474Y436232D01*
X40765Y435857D01*
X41182Y435607D01*
X41557Y435524D01*
Y437274D01*
G01X40515Y438707D02*
X40224Y438999D01*
X40057Y439249D01*
X39974Y439582D01*
X40057Y439874D01*
X40224Y440082D01*
X40474Y440249D01*
X40765Y440291D01*
X41015Y440249D01*
X41265Y440082D01*
X41474Y439832D01*
X41557Y439541D01*
X41474Y439207D01*
X41224Y438916D01*
X40849Y438749D01*
X40432Y438707D01*
X39890Y438791D01*
X39599Y438916D01*
X39307Y439124D01*
X39099Y439416D01*
X39057Y439707D01*
X39140Y439999D01*
X39349Y440207D01*
G01X39474Y441807D02*
X39224Y442057D01*
X39099Y442349D01*
X39057Y442682D01*
X39140Y443099D01*
X39349Y443391D01*
X39599Y443474D01*
X39849Y443432D01*
X40057Y443266D01*
X40474Y442432D01*
X40765Y442057D01*
X41182Y441807D01*
X41557Y441724D01*
Y443474D01*
G01X70923Y432515D02*
X68423D01*
Y433556D01*
X68548Y433890D01*
X68715Y434098D01*
X69048Y434181D01*
X69381Y434098D01*
X69590Y433848D01*
X69715Y433556D01*
Y432515D01*
G01Y433556D02*
X70923Y434181D01*
G01Y436448D02*
X68423D01*
X68923Y435948D01*
G01X70923D02*
Y436948D01*
G01Y440048D02*
X68423D01*
X70215Y438506D01*
Y440590D01*
G01X70631Y441940D02*
X70840Y442231D01*
X70923Y442565D01*
X70840Y442898D01*
X70590Y443190D01*
X70215Y443398D01*
X69840Y443481D01*
X69381D01*
X69006Y443398D01*
X68673Y443190D01*
X68506Y442940D01*
X68423Y442648D01*
X68506Y442315D01*
X68673Y442065D01*
X68923Y441898D01*
X69256Y441815D01*
X69548Y441898D01*
X69840Y442106D01*
X70006Y442356D01*
X70048Y442648D01*
X69965Y442981D01*
X69756Y443231D01*
X69381Y443481D01*
G01X66764Y433340D02*
X64264D01*
Y434381D01*
X64389Y434715D01*
X64556Y434923D01*
X64889Y435006D01*
X65222Y434923D01*
X65431Y434673D01*
X65556Y434381D01*
Y433340D01*
G01Y434381D02*
X66764Y435006D01*
G01Y437273D02*
X64264D01*
X64764Y436773D01*
G01X66764D02*
Y437773D01*
G01Y440290D02*
X66222Y440373D01*
X65764Y440498D01*
X65347Y440665D01*
X64889Y440873D01*
X64264Y441206D01*
Y439540D01*
G01X66764Y443473D02*
X66722Y443765D01*
X66597Y444098D01*
X66389Y444306D01*
X66097Y444390D01*
X65806Y444306D01*
X65556Y444056D01*
X65431Y443681D01*
Y443265D01*
X65347Y443015D01*
X65139Y442806D01*
X64847Y442723D01*
X64556Y442848D01*
X64347Y443140D01*
X64264Y443473D01*
X64347Y443806D01*
X64556Y444098D01*
X64847Y444223D01*
X65139Y444140D01*
X65347Y443931D01*
X65431Y443681D01*
Y443265D01*
X65556Y442890D01*
X65806Y442640D01*
X66097Y442556D01*
X66389Y442640D01*
X66597Y442848D01*
X66722Y443181D01*
X66764Y443473D01*
G01X62456Y435069D02*
X59956D01*
Y436110D01*
X60081Y436444D01*
X60248Y436652D01*
X60581Y436735D01*
X60914Y436652D01*
X61123Y436402D01*
X61248Y436110D01*
Y435069D01*
G01Y436110D02*
X62456Y436735D01*
G01Y439002D02*
X59956D01*
X60456Y438502D01*
G01X62456D02*
Y439502D01*
G01Y442019D02*
X61914Y442102D01*
X61456Y442227D01*
X61039Y442394D01*
X60581Y442602D01*
X59956Y442935D01*
Y441269D01*
G01X62456Y445119D02*
X61914Y445202D01*
X61456Y445327D01*
X61039Y445494D01*
X60581Y445702D01*
X59956Y446035D01*
Y444369D01*
G01X50426Y437239D02*
X47926D01*
Y438280D01*
X48051Y438614D01*
X48218Y438822D01*
X48551Y438905D01*
X48884Y438822D01*
X49093Y438572D01*
X49218Y438280D01*
Y437239D01*
G01Y438280D02*
X50426Y438905D01*
G01Y441172D02*
X47926D01*
X48426Y440672D01*
G01X50426D02*
Y441672D01*
G01X50051Y443355D02*
X50259Y443605D01*
X50384Y443897D01*
X50426Y444272D01*
X50343Y444647D01*
X50176Y444939D01*
X49884Y445147D01*
X49551Y445189D01*
X49218Y445105D01*
X49009Y444897D01*
X48843Y444605D01*
X48801Y444314D01*
X48843Y444022D01*
X49009Y443647D01*
X47926Y443772D01*
Y444897D01*
G01X50426Y447372D02*
X50384Y447664D01*
X50259Y447997D01*
X50051Y448205D01*
X49759Y448289D01*
X49468Y448205D01*
X49218Y447955D01*
X49093Y447580D01*
Y447164D01*
X49009Y446914D01*
X48801Y446705D01*
X48509Y446622D01*
X48218Y446747D01*
X48009Y447039D01*
X47926Y447372D01*
X48009Y447705D01*
X48218Y447997D01*
X48509Y448122D01*
X48801Y448039D01*
X49009Y447830D01*
X49093Y447580D01*
Y447164D01*
X49218Y446789D01*
X49468Y446539D01*
X49759Y446455D01*
X50051Y446539D01*
X50259Y446747D01*
X50384Y447080D01*
X50426Y447372D01*
G01X18396Y436072D02*
X15896D01*
Y437113D01*
X16021Y437447D01*
X16188Y437655D01*
X16521Y437738D01*
X16854Y437655D01*
X17063Y437405D01*
X17188Y437113D01*
Y436072D01*
G01Y437113D02*
X18396Y437738D01*
G01X17896Y439088D02*
X18188Y439338D01*
X18354Y439672D01*
X18396Y440047D01*
X18354Y440380D01*
X18146Y440713D01*
X17896Y440922D01*
X17646Y440963D01*
X17354Y440880D01*
X17146Y440588D01*
X17063Y440297D01*
Y439922D01*
G01Y440297D02*
X16938Y440547D01*
X16729Y440755D01*
X16479Y440838D01*
X16229Y440755D01*
X16021Y440547D01*
X15896Y440172D01*
X15938Y439797D01*
X16104Y439422D01*
G01X18396Y443105D02*
X15896D01*
X16396Y442605D01*
G01X18396D02*
Y443605D01*
G01X16313Y445413D02*
X16063Y445663D01*
X15938Y445955D01*
X15896Y446288D01*
X15979Y446705D01*
X16188Y446997D01*
X16438Y447080D01*
X16688Y447038D01*
X16896Y446872D01*
X17313Y446038D01*
X17604Y445663D01*
X18021Y445413D01*
X18396Y445330D01*
Y447080D01*
G01X46276Y428969D02*
X43776D01*
Y430010D01*
X43901Y430344D01*
X44068Y430552D01*
X44401Y430635D01*
X44734Y430552D01*
X44943Y430302D01*
X45068Y430010D01*
Y428969D01*
G01Y430010D02*
X46276Y430635D01*
G01X45901Y431985D02*
X46109Y432235D01*
X46234Y432527D01*
X46276Y432902D01*
X46193Y433277D01*
X46026Y433569D01*
X45734Y433777D01*
X45401Y433819D01*
X45068Y433735D01*
X44859Y433527D01*
X44693Y433235D01*
X44651Y432944D01*
X44693Y432652D01*
X44859Y432277D01*
X43776Y432402D01*
Y433527D01*
G01X44193Y435210D02*
X43943Y435460D01*
X43818Y435752D01*
X43776Y436085D01*
X43859Y436502D01*
X44068Y436794D01*
X44318Y436877D01*
X44568Y436835D01*
X44776Y436669D01*
X45193Y435835D01*
X45484Y435460D01*
X45901Y435210D01*
X46276Y435127D01*
Y436877D01*
G01X45901Y438185D02*
X46109Y438435D01*
X46234Y438727D01*
X46276Y439102D01*
X46193Y439477D01*
X46026Y439769D01*
X45734Y439977D01*
X45401Y440019D01*
X45068Y439935D01*
X44859Y439727D01*
X44693Y439435D01*
X44651Y439144D01*
X44693Y438852D01*
X44859Y438477D01*
X43776Y438602D01*
Y439727D01*
G01X61159Y533707D02*
X96593D01*
Y588825D01*
X61159D01*
Y533707D01*
G01X61500Y508017D02*
X59000D01*
Y509058D01*
X59125Y509392D01*
X59292Y509600D01*
X59625Y509683D01*
X59958Y509600D01*
X60167Y509350D01*
X60292Y509058D01*
Y508017D01*
G01Y509058D02*
X61500Y509683D01*
G01X59417Y511158D02*
X59167Y511408D01*
X59042Y511700D01*
X59000Y512033D01*
X59083Y512450D01*
X59292Y512742D01*
X59542Y512825D01*
X59792Y512783D01*
X60000Y512617D01*
X60417Y511783D01*
X60708Y511408D01*
X61125Y511158D01*
X61500Y511075D01*
Y512825D01*
G01X61000Y514133D02*
X61292Y514383D01*
X61458Y514717D01*
X61500Y515092D01*
X61458Y515425D01*
X61250Y515758D01*
X61000Y515967D01*
X60750Y516008D01*
X60458Y515925D01*
X60250Y515633D01*
X60167Y515342D01*
Y514967D01*
G01Y515342D02*
X60042Y515592D01*
X59833Y515800D01*
X59583Y515883D01*
X59333Y515800D01*
X59125Y515592D01*
X59000Y515217D01*
X59042Y514842D01*
X59208Y514467D01*
G01X59417Y517358D02*
X59167Y517608D01*
X59042Y517900D01*
X59000Y518233D01*
X59083Y518650D01*
X59292Y518942D01*
X59542Y519025D01*
X59792Y518983D01*
X60000Y518817D01*
X60417Y517983D01*
X60708Y517608D01*
X61125Y517358D01*
X61500Y517275D01*
Y519025D01*
G01Y496017D02*
X59000D01*
Y497058D01*
X59125Y497392D01*
X59292Y497600D01*
X59625Y497683D01*
X59958Y497600D01*
X60167Y497350D01*
X60292Y497058D01*
Y496017D01*
G01Y497058D02*
X61500Y497683D01*
G01X59417Y499158D02*
X59167Y499408D01*
X59042Y499700D01*
X59000Y500033D01*
X59083Y500450D01*
X59292Y500742D01*
X59542Y500825D01*
X59792Y500783D01*
X60000Y500617D01*
X60417Y499783D01*
X60708Y499408D01*
X61125Y499158D01*
X61500Y499075D01*
Y500825D01*
G01X61000Y502133D02*
X61292Y502383D01*
X61458Y502717D01*
X61500Y503092D01*
X61458Y503425D01*
X61250Y503758D01*
X61000Y503967D01*
X60750Y504008D01*
X60458Y503925D01*
X60250Y503633D01*
X60167Y503342D01*
Y502967D01*
G01Y503342D02*
X60042Y503592D01*
X59833Y503800D01*
X59583Y503883D01*
X59333Y503800D01*
X59125Y503592D01*
X59000Y503217D01*
X59042Y502842D01*
X59208Y502467D01*
G01X61500Y506150D02*
X59000D01*
X59500Y505650D01*
G01X61500D02*
Y506650D01*
G01X38806Y545876D02*
Y541876D01*
X46206D01*
G01X31358Y545881D02*
Y541881D01*
X38758D01*
G01X38787Y557153D02*
Y553153D01*
X46187D01*
G01X31287Y557153D02*
Y553153D01*
X38687D01*
G01X49500Y508017D02*
X47000D01*
Y509058D01*
X47125Y509392D01*
X47292Y509600D01*
X47625Y509683D01*
X47958Y509600D01*
X48167Y509350D01*
X48292Y509058D01*
Y508017D01*
G01Y509058D02*
X49500Y509683D01*
G01X47417Y511158D02*
X47167Y511408D01*
X47042Y511700D01*
X47000Y512033D01*
X47083Y512450D01*
X47292Y512742D01*
X47542Y512825D01*
X47792Y512783D01*
X48000Y512617D01*
X48417Y511783D01*
X48708Y511408D01*
X49125Y511158D01*
X49500Y511075D01*
Y512825D01*
G01X47417Y514258D02*
X47167Y514508D01*
X47042Y514800D01*
X47000Y515133D01*
X47083Y515550D01*
X47292Y515842D01*
X47542Y515925D01*
X47792Y515883D01*
X48000Y515717D01*
X48417Y514883D01*
X48708Y514508D01*
X49125Y514258D01*
X49500Y514175D01*
Y515925D01*
G01X48458Y517358D02*
X48167Y517650D01*
X48000Y517900D01*
X47917Y518233D01*
X48000Y518525D01*
X48167Y518733D01*
X48417Y518900D01*
X48708Y518942D01*
X48958Y518900D01*
X49208Y518733D01*
X49417Y518483D01*
X49500Y518192D01*
X49417Y517858D01*
X49167Y517567D01*
X48792Y517400D01*
X48375Y517358D01*
X47833Y517442D01*
X47542Y517567D01*
X47250Y517775D01*
X47042Y518067D01*
X47000Y518358D01*
X47083Y518650D01*
X47292Y518858D01*
G01X49500Y495017D02*
X47000D01*
Y496058D01*
X47125Y496392D01*
X47292Y496600D01*
X47625Y496683D01*
X47958Y496600D01*
X48167Y496350D01*
X48292Y496058D01*
Y495017D01*
G01Y496058D02*
X49500Y496683D01*
G01X47417Y498158D02*
X47167Y498408D01*
X47042Y498700D01*
X47000Y499033D01*
X47083Y499450D01*
X47292Y499742D01*
X47542Y499825D01*
X47792Y499783D01*
X48000Y499617D01*
X48417Y498783D01*
X48708Y498408D01*
X49125Y498158D01*
X49500Y498075D01*
Y499825D01*
G01X47417Y501258D02*
X47167Y501508D01*
X47042Y501800D01*
X47000Y502133D01*
X47083Y502550D01*
X47292Y502842D01*
X47542Y502925D01*
X47792Y502883D01*
X48000Y502717D01*
X48417Y501883D01*
X48708Y501508D01*
X49125Y501258D01*
X49500Y501175D01*
Y502925D01*
G01X49125Y504233D02*
X49333Y504483D01*
X49458Y504775D01*
X49500Y505150D01*
X49417Y505525D01*
X49250Y505817D01*
X48958Y506025D01*
X48625Y506067D01*
X48292Y505983D01*
X48083Y505775D01*
X47917Y505483D01*
X47875Y505192D01*
X47917Y504900D01*
X48083Y504525D01*
X47000Y504650D01*
Y505775D01*
G01X41000Y508017D02*
X38500D01*
Y509058D01*
X38625Y509392D01*
X38792Y509600D01*
X39125Y509683D01*
X39458Y509600D01*
X39667Y509350D01*
X39792Y509058D01*
Y508017D01*
G01Y509058D02*
X41000Y509683D01*
G01X38917Y511158D02*
X38667Y511408D01*
X38542Y511700D01*
X38500Y512033D01*
X38583Y512450D01*
X38792Y512742D01*
X39042Y512825D01*
X39292Y512783D01*
X39500Y512617D01*
X39917Y511783D01*
X40208Y511408D01*
X40625Y511158D01*
X41000Y511075D01*
Y512825D01*
G01X38917Y514258D02*
X38667Y514508D01*
X38542Y514800D01*
X38500Y515133D01*
X38583Y515550D01*
X38792Y515842D01*
X39042Y515925D01*
X39292Y515883D01*
X39500Y515717D01*
X39917Y514883D01*
X40208Y514508D01*
X40625Y514258D01*
X41000Y514175D01*
Y515925D01*
G01Y518150D02*
X38500D01*
X39000Y517650D01*
G01X41000D02*
Y518650D01*
G01X67778Y512077D02*
X71778D01*
Y519477D01*
G01X41000Y495017D02*
X38500D01*
Y496058D01*
X38625Y496392D01*
X38792Y496600D01*
X39125Y496683D01*
X39458Y496600D01*
X39667Y496350D01*
X39792Y496058D01*
Y495017D01*
G01Y496058D02*
X41000Y496683D01*
G01X38917Y498158D02*
X38667Y498408D01*
X38542Y498700D01*
X38500Y499033D01*
X38583Y499450D01*
X38792Y499742D01*
X39042Y499825D01*
X39292Y499783D01*
X39500Y499617D01*
X39917Y498783D01*
X40208Y498408D01*
X40625Y498158D01*
X41000Y498075D01*
Y499825D01*
G01X38917Y501258D02*
X38667Y501508D01*
X38542Y501800D01*
X38500Y502133D01*
X38583Y502550D01*
X38792Y502842D01*
X39042Y502925D01*
X39292Y502883D01*
X39500Y502717D01*
X39917Y501883D01*
X40208Y501508D01*
X40625Y501258D01*
X41000Y501175D01*
Y502925D01*
G01X38500Y505150D02*
X38583Y504817D01*
X38792Y504567D01*
X39042Y504400D01*
X39375Y504275D01*
X39750Y504233D01*
X40125Y504275D01*
X40458Y504400D01*
X40708Y504567D01*
X40917Y504817D01*
X41000Y505150D01*
X40917Y505483D01*
X40708Y505733D01*
X40458Y505900D01*
X40125Y506025D01*
X39750Y506067D01*
X39375Y506025D01*
X39042Y505900D01*
X38792Y505733D01*
X38583Y505483D01*
X38500Y505150D01*
G01X67900Y504600D02*
X71900D01*
Y512000D01*
G01X38600Y551500D02*
Y547500D01*
X46000D01*
G01X31100Y551500D02*
Y547500D01*
X38500D01*
G01X45500Y508017D02*
X43000D01*
Y509058D01*
X43125Y509392D01*
X43292Y509600D01*
X43625Y509683D01*
X43958Y509600D01*
X44167Y509350D01*
X44292Y509058D01*
Y508017D01*
G01Y509058D02*
X45500Y509683D01*
G01X43417Y511158D02*
X43167Y511408D01*
X43042Y511700D01*
X43000Y512033D01*
X43083Y512450D01*
X43292Y512742D01*
X43542Y512825D01*
X43792Y512783D01*
X44000Y512617D01*
X44417Y511783D01*
X44708Y511408D01*
X45125Y511158D01*
X45500Y511075D01*
Y512825D01*
G01Y515050D02*
X43000D01*
X43500Y514550D01*
G01X45500D02*
Y515550D01*
G01X44458Y517358D02*
X44167Y517650D01*
X44000Y517900D01*
X43917Y518233D01*
X44000Y518525D01*
X44167Y518733D01*
X44417Y518900D01*
X44708Y518942D01*
X44958Y518900D01*
X45208Y518733D01*
X45417Y518483D01*
X45500Y518192D01*
X45417Y517858D01*
X45167Y517567D01*
X44792Y517400D01*
X44375Y517358D01*
X43833Y517442D01*
X43542Y517567D01*
X43250Y517775D01*
X43042Y518067D01*
X43000Y518358D01*
X43083Y518650D01*
X43292Y518858D01*
G01X45500Y495017D02*
X43000D01*
Y496058D01*
X43125Y496392D01*
X43292Y496600D01*
X43625Y496683D01*
X43958Y496600D01*
X44167Y496350D01*
X44292Y496058D01*
Y495017D01*
G01Y496058D02*
X45500Y496683D01*
G01X43417Y498158D02*
X43167Y498408D01*
X43042Y498700D01*
X43000Y499033D01*
X43083Y499450D01*
X43292Y499742D01*
X43542Y499825D01*
X43792Y499783D01*
X44000Y499617D01*
X44417Y498783D01*
X44708Y498408D01*
X45125Y498158D01*
X45500Y498075D01*
Y499825D01*
G01Y502050D02*
X43000D01*
X43500Y501550D01*
G01X45500D02*
Y502550D01*
G01X45125Y504233D02*
X45333Y504483D01*
X45458Y504775D01*
X45500Y505150D01*
X45417Y505525D01*
X45250Y505817D01*
X44958Y506025D01*
X44625Y506067D01*
X44292Y505983D01*
X44083Y505775D01*
X43917Y505483D01*
X43875Y505192D01*
X43917Y504900D01*
X44083Y504525D01*
X43000Y504650D01*
Y505775D01*
G01X53500Y495017D02*
X51000D01*
Y496058D01*
X51125Y496392D01*
X51292Y496600D01*
X51625Y496683D01*
X51958Y496600D01*
X52167Y496350D01*
X52292Y496058D01*
Y495017D01*
G01Y496058D02*
X53500Y496683D01*
G01X51417Y498158D02*
X51167Y498408D01*
X51042Y498700D01*
X51000Y499033D01*
X51083Y499450D01*
X51292Y499742D01*
X51542Y499825D01*
X51792Y499783D01*
X52000Y499617D01*
X52417Y498783D01*
X52708Y498408D01*
X53125Y498158D01*
X53500Y498075D01*
Y499825D01*
G01Y502050D02*
X51000D01*
X51500Y501550D01*
G01X53500D02*
Y502550D01*
G01X53000Y504233D02*
X53292Y504483D01*
X53458Y504817D01*
X53500Y505192D01*
X53458Y505525D01*
X53250Y505858D01*
X53000Y506067D01*
X52750Y506108D01*
X52458Y506025D01*
X52250Y505733D01*
X52167Y505442D01*
Y505067D01*
G01Y505442D02*
X52042Y505692D01*
X51833Y505900D01*
X51583Y505983D01*
X51333Y505900D01*
X51125Y505692D01*
X51000Y505317D01*
X51042Y504942D01*
X51208Y504567D01*
G01X39090Y566188D02*
Y568688D01*
X40131D01*
X40465Y568563D01*
X40673Y568396D01*
X40756Y568063D01*
X40673Y567730D01*
X40423Y567521D01*
X40131Y567396D01*
X39090D01*
G01X40131D02*
X40756Y566188D01*
G01X42231Y568271D02*
X42481Y568521D01*
X42773Y568646D01*
X43106Y568688D01*
X43523Y568605D01*
X43815Y568396D01*
X43898Y568146D01*
X43856Y567896D01*
X43690Y567688D01*
X42856Y567271D01*
X42481Y566980D01*
X42231Y566563D01*
X42148Y566188D01*
X43898D01*
G01X46123Y568688D02*
X45790Y568605D01*
X45540Y568396D01*
X45373Y568146D01*
X45248Y567813D01*
X45206Y567438D01*
X45248Y567063D01*
X45373Y566730D01*
X45540Y566480D01*
X45790Y566271D01*
X46123Y566188D01*
X46456Y566271D01*
X46706Y566480D01*
X46873Y566730D01*
X46998Y567063D01*
X47040Y567438D01*
X46998Y567813D01*
X46873Y568146D01*
X46706Y568396D01*
X46456Y568605D01*
X46123Y568688D01*
G01X49223Y566188D02*
X49515Y566230D01*
X49848Y566355D01*
X50056Y566563D01*
X50140Y566855D01*
X50056Y567146D01*
X49806Y567396D01*
X49431Y567521D01*
X49015D01*
X48765Y567605D01*
X48556Y567813D01*
X48473Y568105D01*
X48598Y568396D01*
X48890Y568605D01*
X49223Y568688D01*
X49556Y568605D01*
X49848Y568396D01*
X49973Y568105D01*
X49890Y567813D01*
X49681Y567605D01*
X49431Y567521D01*
X49015D01*
X48640Y567396D01*
X48390Y567146D01*
X48306Y566855D01*
X48390Y566563D01*
X48598Y566355D01*
X48931Y566230D01*
X49223Y566188D01*
G01X38806Y540249D02*
Y536249D01*
X46206D01*
G01X25906Y566419D02*
Y568919D01*
X26947D01*
X27281Y568794D01*
X27489Y568627D01*
X27572Y568294D01*
X27489Y567961D01*
X27239Y567752D01*
X26947Y567627D01*
X25906D01*
G01X26947D02*
X27572Y566419D01*
G01X29047Y568502D02*
X29297Y568752D01*
X29589Y568877D01*
X29922Y568919D01*
X30339Y568836D01*
X30631Y568627D01*
X30714Y568377D01*
X30672Y568127D01*
X30506Y567919D01*
X29672Y567502D01*
X29297Y567211D01*
X29047Y566794D01*
X28964Y566419D01*
X30714D01*
G01X32939Y568919D02*
X32606Y568836D01*
X32356Y568627D01*
X32189Y568377D01*
X32064Y568044D01*
X32022Y567669D01*
X32064Y567294D01*
X32189Y566961D01*
X32356Y566711D01*
X32606Y566502D01*
X32939Y566419D01*
X33272Y566502D01*
X33522Y566711D01*
X33689Y566961D01*
X33814Y567294D01*
X33856Y567669D01*
X33814Y568044D01*
X33689Y568377D01*
X33522Y568627D01*
X33272Y568836D01*
X32939Y568919D01*
G01X35956Y566419D02*
X36039Y566961D01*
X36164Y567419D01*
X36331Y567836D01*
X36539Y568294D01*
X36872Y568919D01*
X35206D01*
G01X31258Y540254D02*
Y536254D01*
X38658D01*
G01X57500Y508017D02*
X55000D01*
Y509058D01*
X55125Y509392D01*
X55292Y509600D01*
X55625Y509683D01*
X55958Y509600D01*
X56167Y509350D01*
X56292Y509058D01*
Y508017D01*
G01Y509058D02*
X57500Y509683D01*
G01X55417Y511158D02*
X55167Y511408D01*
X55042Y511700D01*
X55000Y512033D01*
X55083Y512450D01*
X55292Y512742D01*
X55542Y512825D01*
X55792Y512783D01*
X56000Y512617D01*
X56417Y511783D01*
X56708Y511408D01*
X57125Y511158D01*
X57500Y511075D01*
Y512825D01*
G01Y515050D02*
X55000D01*
X55500Y514550D01*
G01X57500D02*
Y515550D01*
G01Y518650D02*
X55000D01*
X56792Y517108D01*
Y519192D01*
G01X39090Y562188D02*
Y564688D01*
X40131D01*
X40465Y564563D01*
X40673Y564396D01*
X40756Y564063D01*
X40673Y563730D01*
X40423Y563521D01*
X40131Y563396D01*
X39090D01*
G01X40131D02*
X40756Y562188D01*
G01X42231Y564271D02*
X42481Y564521D01*
X42773Y564646D01*
X43106Y564688D01*
X43523Y564605D01*
X43815Y564396D01*
X43898Y564146D01*
X43856Y563896D01*
X43690Y563688D01*
X42856Y563271D01*
X42481Y562980D01*
X42231Y562563D01*
X42148Y562188D01*
X43898D01*
G01X45331Y564271D02*
X45581Y564521D01*
X45873Y564646D01*
X46206Y564688D01*
X46623Y564605D01*
X46915Y564396D01*
X46998Y564146D01*
X46956Y563896D01*
X46790Y563688D01*
X45956Y563271D01*
X45581Y562980D01*
X45331Y562563D01*
X45248Y562188D01*
X46998D01*
G01X49723D02*
Y564688D01*
X48181Y562896D01*
X50265D01*
G01X38706Y534622D02*
Y530622D01*
X46106D01*
G01X53500Y508017D02*
X51000D01*
Y509058D01*
X51125Y509392D01*
X51292Y509600D01*
X51625Y509683D01*
X51958Y509600D01*
X52167Y509350D01*
X52292Y509058D01*
Y508017D01*
G01Y509058D02*
X53500Y509683D01*
G01Y511950D02*
X51000D01*
X51500Y511450D01*
G01X53500D02*
Y512450D01*
G01Y515550D02*
X51000D01*
X52792Y514008D01*
Y516092D01*
G01X53500Y518650D02*
X51000D01*
X52792Y517108D01*
Y519192D01*
G01X25906Y562419D02*
Y564919D01*
X26947D01*
X27281Y564794D01*
X27489Y564627D01*
X27572Y564294D01*
X27489Y563961D01*
X27239Y563752D01*
X26947Y563627D01*
X25906D01*
G01X26947D02*
X27572Y562419D01*
G01X29047Y564502D02*
X29297Y564752D01*
X29589Y564877D01*
X29922Y564919D01*
X30339Y564836D01*
X30631Y564627D01*
X30714Y564377D01*
X30672Y564127D01*
X30506Y563919D01*
X29672Y563502D01*
X29297Y563211D01*
X29047Y562794D01*
X28964Y562419D01*
X30714D01*
G01X32022Y562919D02*
X32272Y562627D01*
X32606Y562461D01*
X32981Y562419D01*
X33314Y562461D01*
X33647Y562669D01*
X33856Y562919D01*
X33897Y563169D01*
X33814Y563461D01*
X33522Y563669D01*
X33231Y563752D01*
X32856D01*
G01X33231D02*
X33481Y563877D01*
X33689Y564086D01*
X33772Y564336D01*
X33689Y564586D01*
X33481Y564794D01*
X33106Y564919D01*
X32731Y564877D01*
X32356Y564711D01*
G01X35331Y562711D02*
X35622Y562502D01*
X35956Y562419D01*
X36289Y562502D01*
X36581Y562752D01*
X36789Y563127D01*
X36872Y563502D01*
Y563961D01*
X36789Y564336D01*
X36581Y564669D01*
X36331Y564836D01*
X36039Y564919D01*
X35706Y564836D01*
X35456Y564669D01*
X35289Y564419D01*
X35206Y564086D01*
X35289Y563794D01*
X35497Y563502D01*
X35747Y563336D01*
X36039Y563294D01*
X36372Y563377D01*
X36622Y563586D01*
X36872Y563961D01*
G01X38665Y530638D02*
Y534638D01*
X31265D01*
G01X64112Y535675D02*
X93640D01*
Y586857D01*
X64112D01*
Y535675D01*
G01X11756Y590037D02*
X11645D01*
G01X90100Y623286D02*
Y595172D01*
X44363D01*
Y590037D01*
X11756D01*
Y613657D01*
X52226D01*
Y629319D01*
X74177D01*
Y628242D01*
G01X63947Y618367D02*
X63822Y618117D01*
X63739Y617825D01*
Y617492D01*
X63864Y617117D01*
X64072Y616825D01*
X64322Y616617D01*
X64739Y616450D01*
X65114Y616408D01*
X65489Y616492D01*
X65739Y616617D01*
X65989Y616867D01*
X66156Y617158D01*
X66239Y617450D01*
Y617742D01*
X66156Y618033D01*
X66031Y618283D01*
X65864Y618492D01*
G01X66239Y620550D02*
X63739D01*
X64239Y620050D01*
G01X66239D02*
Y621050D01*
G01X64156Y622858D02*
X63906Y623108D01*
X63781Y623400D01*
X63739Y623733D01*
X63822Y624150D01*
X64031Y624442D01*
X64281Y624525D01*
X64531Y624483D01*
X64739Y624317D01*
X65156Y623483D01*
X65447Y623108D01*
X65864Y622858D01*
X66239Y622775D01*
Y624525D01*
G01X63739Y626750D02*
X63822Y626417D01*
X64031Y626167D01*
X64281Y626000D01*
X64614Y625875D01*
X64989Y625833D01*
X65364Y625875D01*
X65697Y626000D01*
X65947Y626167D01*
X66156Y626417D01*
X66239Y626750D01*
X66156Y627083D01*
X65947Y627333D01*
X65697Y627500D01*
X65364Y627625D01*
X64989Y627667D01*
X64614Y627625D01*
X64281Y627500D01*
X64031Y627333D01*
X63822Y627083D01*
X63739Y626750D01*
G01X56317Y623388D02*
X56067Y623513D01*
X55775Y623596D01*
X55442D01*
X55067Y623471D01*
X54775Y623263D01*
X54567Y623013D01*
X54400Y622596D01*
X54358Y622221D01*
X54442Y621846D01*
X54567Y621596D01*
X54817Y621346D01*
X55108Y621179D01*
X55400Y621096D01*
X55692D01*
X55983Y621179D01*
X56233Y621304D01*
X56442Y621471D01*
G01X58500Y621096D02*
X58792Y621138D01*
X59125Y621263D01*
X59333Y621471D01*
X59417Y621763D01*
X59333Y622054D01*
X59083Y622304D01*
X58708Y622429D01*
X58292D01*
X58042Y622513D01*
X57833Y622721D01*
X57750Y623013D01*
X57875Y623304D01*
X58167Y623513D01*
X58500Y623596D01*
X58833Y623513D01*
X59125Y623304D01*
X59250Y623013D01*
X59167Y622721D01*
X58958Y622513D01*
X58708Y622429D01*
X58292D01*
X57917Y622304D01*
X57667Y622054D01*
X57583Y621763D01*
X57667Y621471D01*
X57875Y621263D01*
X58208Y621138D01*
X58500Y621096D01*
G01X62100D02*
Y623596D01*
X60558Y621804D01*
X62642D01*
G01X56317Y619688D02*
X56067Y619813D01*
X55775Y619896D01*
X55442D01*
X55067Y619771D01*
X54775Y619563D01*
X54567Y619313D01*
X54400Y618896D01*
X54358Y618521D01*
X54442Y618146D01*
X54567Y617896D01*
X54817Y617646D01*
X55108Y617479D01*
X55400Y617396D01*
X55692D01*
X55983Y617479D01*
X56233Y617604D01*
X56442Y617771D01*
G01X58500Y617396D02*
X58792Y617438D01*
X59125Y617563D01*
X59333Y617771D01*
X59417Y618063D01*
X59333Y618354D01*
X59083Y618604D01*
X58708Y618729D01*
X58292D01*
X58042Y618813D01*
X57833Y619021D01*
X57750Y619313D01*
X57875Y619604D01*
X58167Y619813D01*
X58500Y619896D01*
X58833Y619813D01*
X59125Y619604D01*
X59250Y619313D01*
X59167Y619021D01*
X58958Y618813D01*
X58708Y618729D01*
X58292D01*
X57917Y618604D01*
X57667Y618354D01*
X57583Y618063D01*
X57667Y617771D01*
X57875Y617563D01*
X58208Y617438D01*
X58500Y617396D01*
G01X60808Y618438D02*
X61100Y618729D01*
X61350Y618896D01*
X61683Y618979D01*
X61975Y618896D01*
X62183Y618729D01*
X62350Y618479D01*
X62392Y618188D01*
X62350Y617938D01*
X62183Y617688D01*
X61933Y617479D01*
X61642Y617396D01*
X61308Y617479D01*
X61017Y617729D01*
X60850Y618104D01*
X60808Y618521D01*
X60892Y619063D01*
X61017Y619354D01*
X61225Y619646D01*
X61517Y619854D01*
X61808Y619896D01*
X62100Y619813D01*
X62308Y619604D01*
G01X56317Y615988D02*
X56067Y616113D01*
X55775Y616196D01*
X55442D01*
X55067Y616071D01*
X54775Y615863D01*
X54567Y615613D01*
X54400Y615196D01*
X54358Y614821D01*
X54442Y614446D01*
X54567Y614196D01*
X54817Y613946D01*
X55108Y613779D01*
X55400Y613696D01*
X55692D01*
X55983Y613779D01*
X56233Y613904D01*
X56442Y614071D01*
G01X58500Y613696D02*
X58792Y613738D01*
X59125Y613863D01*
X59333Y614071D01*
X59417Y614363D01*
X59333Y614654D01*
X59083Y614904D01*
X58708Y615029D01*
X58292D01*
X58042Y615113D01*
X57833Y615321D01*
X57750Y615613D01*
X57875Y615904D01*
X58167Y616113D01*
X58500Y616196D01*
X58833Y616113D01*
X59125Y615904D01*
X59250Y615613D01*
X59167Y615321D01*
X58958Y615113D01*
X58708Y615029D01*
X58292D01*
X57917Y614904D01*
X57667Y614654D01*
X57583Y614363D01*
X57667Y614071D01*
X57875Y613863D01*
X58208Y613738D01*
X58500Y613696D01*
G01X60683Y614071D02*
X60933Y613863D01*
X61225Y613738D01*
X61600Y613696D01*
X61975Y613779D01*
X62267Y613946D01*
X62475Y614238D01*
X62517Y614571D01*
X62433Y614904D01*
X62225Y615113D01*
X61933Y615279D01*
X61642Y615321D01*
X61350Y615279D01*
X60975Y615113D01*
X61100Y616196D01*
X62225D01*
G01X70039Y616617D02*
X67539D01*
Y617658D01*
X67664Y617992D01*
X67831Y618200D01*
X68164Y618283D01*
X68497Y618200D01*
X68706Y617950D01*
X68831Y617658D01*
Y616617D01*
G01Y617658D02*
X70039Y618283D01*
G01Y621050D02*
X67539D01*
X69331Y619508D01*
Y621592D01*
G01X70039Y623650D02*
X67539D01*
X68039Y623150D01*
G01X70039D02*
Y624150D01*
G01X67539Y626750D02*
X67622Y626417D01*
X67831Y626167D01*
X68081Y626000D01*
X68414Y625875D01*
X68789Y625833D01*
X69164Y625875D01*
X69497Y626000D01*
X69747Y626167D01*
X69956Y626417D01*
X70039Y626750D01*
X69956Y627083D01*
X69747Y627333D01*
X69497Y627500D01*
X69164Y627625D01*
X68789Y627667D01*
X68414Y627625D01*
X68081Y627500D01*
X67831Y627333D01*
X67622Y627083D01*
X67539Y626750D01*
G01X66200Y599213D02*
X63700D01*
Y600254D01*
X63825Y600588D01*
X63992Y600796D01*
X64325Y600879D01*
X64658Y600796D01*
X64867Y600546D01*
X64992Y600254D01*
Y599213D01*
G01Y600254D02*
X66200Y600879D01*
G01X65700Y602229D02*
X65992Y602479D01*
X66158Y602813D01*
X66200Y603188D01*
X66158Y603521D01*
X65950Y603854D01*
X65700Y604063D01*
X65450Y604104D01*
X65158Y604021D01*
X64950Y603729D01*
X64867Y603438D01*
Y603063D01*
G01Y603438D02*
X64742Y603688D01*
X64533Y603896D01*
X64283Y603979D01*
X64033Y603896D01*
X63825Y603688D01*
X63700Y603313D01*
X63742Y602938D01*
X63908Y602563D01*
G01X65908Y605538D02*
X66117Y605829D01*
X66200Y606163D01*
X66117Y606496D01*
X65867Y606788D01*
X65492Y606996D01*
X65117Y607079D01*
X64658D01*
X64283Y606996D01*
X63950Y606788D01*
X63783Y606538D01*
X63700Y606246D01*
X63783Y605913D01*
X63950Y605663D01*
X64200Y605496D01*
X64533Y605413D01*
X64825Y605496D01*
X65117Y605704D01*
X65283Y605954D01*
X65325Y606246D01*
X65242Y606579D01*
X65033Y606829D01*
X64658Y607079D01*
G01X65825Y608429D02*
X66033Y608679D01*
X66158Y608971D01*
X66200Y609346D01*
X66117Y609721D01*
X65950Y610013D01*
X65658Y610221D01*
X65325Y610263D01*
X64992Y610179D01*
X64783Y609971D01*
X64617Y609679D01*
X64575Y609388D01*
X64617Y609096D01*
X64783Y608721D01*
X63700Y608846D01*
Y609971D01*
G01X70227Y598302D02*
X67727D01*
Y599343D01*
X67852Y599677D01*
X68019Y599885D01*
X68352Y599968D01*
X68685Y599885D01*
X68894Y599635D01*
X69019Y599343D01*
Y598302D01*
G01Y599343D02*
X70227Y599968D01*
G01X69727Y601318D02*
X70019Y601568D01*
X70185Y601902D01*
X70227Y602277D01*
X70185Y602610D01*
X69977Y602943D01*
X69727Y603152D01*
X69477Y603193D01*
X69185Y603110D01*
X68977Y602818D01*
X68894Y602527D01*
Y602152D01*
G01Y602527D02*
X68769Y602777D01*
X68560Y602985D01*
X68310Y603068D01*
X68060Y602985D01*
X67852Y602777D01*
X67727Y602402D01*
X67769Y602027D01*
X67935Y601652D01*
G01X69935Y604627D02*
X70144Y604918D01*
X70227Y605252D01*
X70144Y605585D01*
X69894Y605877D01*
X69519Y606085D01*
X69144Y606168D01*
X68685D01*
X68310Y606085D01*
X67977Y605877D01*
X67810Y605627D01*
X67727Y605335D01*
X67810Y605002D01*
X67977Y604752D01*
X68227Y604585D01*
X68560Y604502D01*
X68852Y604585D01*
X69144Y604793D01*
X69310Y605043D01*
X69352Y605335D01*
X69269Y605668D01*
X69060Y605918D01*
X68685Y606168D01*
G01X67727Y608435D02*
X67810Y608102D01*
X68019Y607852D01*
X68269Y607685D01*
X68602Y607560D01*
X68977Y607518D01*
X69352Y607560D01*
X69685Y607685D01*
X69935Y607852D01*
X70144Y608102D01*
X70227Y608435D01*
X70144Y608768D01*
X69935Y609018D01*
X69685Y609185D01*
X69352Y609310D01*
X68977Y609352D01*
X68602Y609310D01*
X68269Y609185D01*
X68019Y609018D01*
X67810Y608768D01*
X67727Y608435D01*
G01X16228Y591909D02*
X13728D01*
Y592950D01*
X13853Y593284D01*
X14020Y593492D01*
X14353Y593575D01*
X14686Y593492D01*
X14895Y593242D01*
X15020Y592950D01*
Y591909D01*
G01Y592950D02*
X16228Y593575D01*
G01Y595759D02*
X15686Y595842D01*
X15228Y595967D01*
X14811Y596134D01*
X14353Y596342D01*
X13728Y596675D01*
Y595009D01*
G01X16228Y598942D02*
X13728D01*
X14228Y598442D01*
G01X16228D02*
Y599442D01*
G01Y602542D02*
X13728D01*
X15520Y601000D01*
Y603084D01*
G01X43800Y597317D02*
X41300D01*
Y598358D01*
X41425Y598692D01*
X41592Y598900D01*
X41925Y598983D01*
X42258Y598900D01*
X42467Y598650D01*
X42592Y598358D01*
Y597317D01*
G01Y598358D02*
X43800Y598983D01*
G01Y601250D02*
X41300D01*
X41800Y600750D01*
G01X43800D02*
Y601750D01*
G01Y604267D02*
X43258Y604350D01*
X42800Y604475D01*
X42383Y604642D01*
X41925Y604850D01*
X41300Y605183D01*
Y603517D01*
G01X43800Y607950D02*
X41300D01*
X43092Y606408D01*
Y608492D01*
G01X47500Y597317D02*
X45000D01*
Y598358D01*
X45125Y598692D01*
X45292Y598900D01*
X45625Y598983D01*
X45958Y598900D01*
X46167Y598650D01*
X46292Y598358D01*
Y597317D01*
G01Y598358D02*
X47500Y598983D01*
G01Y601250D02*
X45000D01*
X45500Y600750D01*
G01X47500D02*
Y601750D01*
G01Y604267D02*
X46958Y604350D01*
X46500Y604475D01*
X46083Y604642D01*
X45625Y604850D01*
X45000Y605183D01*
Y603517D01*
G01X47000Y606533D02*
X47292Y606783D01*
X47458Y607117D01*
X47500Y607492D01*
X47458Y607825D01*
X47250Y608158D01*
X47000Y608367D01*
X46750Y608408D01*
X46458Y608325D01*
X46250Y608033D01*
X46167Y607742D01*
Y607367D01*
G01Y607742D02*
X46042Y607992D01*
X45833Y608200D01*
X45583Y608283D01*
X45333Y608200D01*
X45125Y607992D01*
X45000Y607617D01*
X45042Y607242D01*
X45208Y606867D01*
G01X51200Y597317D02*
X48700D01*
Y598358D01*
X48825Y598692D01*
X48992Y598900D01*
X49325Y598983D01*
X49658Y598900D01*
X49867Y598650D01*
X49992Y598358D01*
Y597317D01*
G01Y598358D02*
X51200Y598983D01*
G01Y601250D02*
X48700D01*
X49200Y600750D01*
G01X51200D02*
Y601750D01*
G01Y604267D02*
X50658Y604350D01*
X50200Y604475D01*
X49783Y604642D01*
X49325Y604850D01*
X48700Y605183D01*
Y603517D01*
G01X49117Y606658D02*
X48867Y606908D01*
X48742Y607200D01*
X48700Y607533D01*
X48783Y607950D01*
X48992Y608242D01*
X49242Y608325D01*
X49492Y608283D01*
X49700Y608117D01*
X50117Y607283D01*
X50408Y606908D01*
X50825Y606658D01*
X51200Y606575D01*
Y608325D01*
G01X54900Y597317D02*
X52400D01*
Y598358D01*
X52525Y598692D01*
X52692Y598900D01*
X53025Y598983D01*
X53358Y598900D01*
X53567Y598650D01*
X53692Y598358D01*
Y597317D01*
G01Y598358D02*
X54900Y598983D01*
G01Y601250D02*
X52400D01*
X52900Y600750D01*
G01X54900D02*
Y601750D01*
G01Y604267D02*
X54358Y604350D01*
X53900Y604475D01*
X53483Y604642D01*
X53025Y604850D01*
X52400Y605183D01*
Y603517D01*
G01X54900Y607450D02*
X52400D01*
X52900Y606950D01*
G01X54900D02*
Y607950D01*
G01X58600Y597287D02*
X56100D01*
Y598328D01*
X56225Y598662D01*
X56392Y598870D01*
X56725Y598953D01*
X57058Y598870D01*
X57267Y598620D01*
X57392Y598328D01*
Y597287D01*
G01Y598328D02*
X58600Y598953D01*
G01Y601220D02*
X56100D01*
X56600Y600720D01*
G01X58600D02*
Y601720D01*
G01Y604237D02*
X58058Y604320D01*
X57600Y604445D01*
X57183Y604612D01*
X56725Y604820D01*
X56100Y605153D01*
Y603487D01*
G01Y607420D02*
X56183Y607087D01*
X56392Y606837D01*
X56642Y606670D01*
X56975Y606545D01*
X57350Y606503D01*
X57725Y606545D01*
X58058Y606670D01*
X58308Y606837D01*
X58517Y607087D01*
X58600Y607420D01*
X58517Y607753D01*
X58308Y608003D01*
X58058Y608170D01*
X57725Y608295D01*
X57350Y608337D01*
X56975Y608295D01*
X56642Y608170D01*
X56392Y608003D01*
X56183Y607753D01*
X56100Y607420D01*
G01X62300Y597387D02*
X59800D01*
Y598428D01*
X59925Y598762D01*
X60092Y598970D01*
X60425Y599053D01*
X60758Y598970D01*
X60967Y598720D01*
X61092Y598428D01*
Y597387D01*
G01Y598428D02*
X62300Y599053D01*
G01Y601320D02*
X59800D01*
X60300Y600820D01*
G01X62300D02*
Y601820D01*
G01X61258Y603628D02*
X60967Y603920D01*
X60800Y604170D01*
X60717Y604503D01*
X60800Y604795D01*
X60967Y605003D01*
X61217Y605170D01*
X61508Y605212D01*
X61758Y605170D01*
X62008Y605003D01*
X62217Y604753D01*
X62300Y604462D01*
X62217Y604128D01*
X61967Y603837D01*
X61592Y603670D01*
X61175Y603628D01*
X60633Y603712D01*
X60342Y603837D01*
X60050Y604045D01*
X59842Y604337D01*
X59800Y604628D01*
X59883Y604920D01*
X60092Y605128D01*
G01X62300Y607520D02*
X62258Y607812D01*
X62133Y608145D01*
X61925Y608353D01*
X61633Y608437D01*
X61342Y608353D01*
X61092Y608103D01*
X60967Y607728D01*
Y607312D01*
X60883Y607062D01*
X60675Y606853D01*
X60383Y606770D01*
X60092Y606895D01*
X59883Y607187D01*
X59800Y607520D01*
X59883Y607853D01*
X60092Y608145D01*
X60383Y608270D01*
X60675Y608187D01*
X60883Y607978D01*
X60967Y607728D01*
Y607312D01*
X61092Y606937D01*
X61342Y606687D01*
X61633Y606603D01*
X61925Y606687D01*
X62133Y606895D01*
X62258Y607228D01*
X62300Y607520D01*
G01X23649Y595539D02*
X21149D01*
Y596580D01*
X21274Y596914D01*
X21441Y597122D01*
X21774Y597205D01*
X22107Y597122D01*
X22316Y596872D01*
X22441Y596580D01*
Y595539D01*
G01Y596580D02*
X23649Y597205D01*
G01X23149Y598555D02*
X23441Y598805D01*
X23607Y599139D01*
X23649Y599514D01*
X23607Y599847D01*
X23399Y600180D01*
X23149Y600389D01*
X22899Y600430D01*
X22607Y600347D01*
X22399Y600055D01*
X22316Y599764D01*
Y599389D01*
G01Y599764D02*
X22191Y600014D01*
X21982Y600222D01*
X21732Y600305D01*
X21482Y600222D01*
X21274Y600014D01*
X21149Y599639D01*
X21191Y599264D01*
X21357Y598889D01*
G01X21566Y601780D02*
X21316Y602030D01*
X21191Y602322D01*
X21149Y602655D01*
X21232Y603072D01*
X21441Y603364D01*
X21691Y603447D01*
X21941Y603405D01*
X22149Y603239D01*
X22566Y602405D01*
X22857Y602030D01*
X23274Y601780D01*
X23649Y601697D01*
Y603447D01*
G01Y605672D02*
X23607Y605964D01*
X23482Y606297D01*
X23274Y606505D01*
X22982Y606589D01*
X22691Y606505D01*
X22441Y606255D01*
X22316Y605880D01*
Y605464D01*
X22232Y605214D01*
X22024Y605005D01*
X21732Y604922D01*
X21441Y605047D01*
X21232Y605339D01*
X21149Y605672D01*
X21232Y606005D01*
X21441Y606297D01*
X21732Y606422D01*
X22024Y606339D01*
X22232Y606130D01*
X22316Y605880D01*
Y605464D01*
X22441Y605089D01*
X22691Y604839D01*
X22982Y604755D01*
X23274Y604839D01*
X23482Y605047D01*
X23607Y605380D01*
X23649Y605672D01*
G01X19949Y595939D02*
X17449D01*
Y596980D01*
X17574Y597314D01*
X17741Y597522D01*
X18074Y597605D01*
X18407Y597522D01*
X18616Y597272D01*
X18741Y596980D01*
Y595939D01*
G01Y596980D02*
X19949Y597605D01*
G01X19449Y598955D02*
X19741Y599205D01*
X19907Y599539D01*
X19949Y599914D01*
X19907Y600247D01*
X19699Y600580D01*
X19449Y600789D01*
X19199Y600830D01*
X18907Y600747D01*
X18699Y600455D01*
X18616Y600164D01*
Y599789D01*
G01Y600164D02*
X18491Y600414D01*
X18282Y600622D01*
X18032Y600705D01*
X17782Y600622D01*
X17574Y600414D01*
X17449Y600039D01*
X17491Y599664D01*
X17657Y599289D01*
G01X19949Y602972D02*
X17449D01*
X17949Y602472D01*
G01X19949D02*
Y603472D01*
G01Y605989D02*
X19407Y606072D01*
X18949Y606197D01*
X18532Y606364D01*
X18074Y606572D01*
X17449Y606905D01*
Y605239D01*
G01X39090Y570188D02*
Y572688D01*
X40131D01*
X40465Y572563D01*
X40673Y572396D01*
X40756Y572063D01*
X40673Y571730D01*
X40423Y571521D01*
X40131Y571396D01*
X39090D01*
G01X40131D02*
X40756Y570188D01*
G01X42231Y572271D02*
X42481Y572521D01*
X42773Y572646D01*
X43106Y572688D01*
X43523Y572605D01*
X43815Y572396D01*
X43898Y572146D01*
X43856Y571896D01*
X43690Y571688D01*
X42856Y571271D01*
X42481Y570980D01*
X42231Y570563D01*
X42148Y570188D01*
X43898D01*
G01X45206Y570688D02*
X45456Y570396D01*
X45790Y570230D01*
X46165Y570188D01*
X46498Y570230D01*
X46831Y570438D01*
X47040Y570688D01*
X47081Y570938D01*
X46998Y571230D01*
X46706Y571438D01*
X46415Y571521D01*
X46040D01*
G01X46415D02*
X46665Y571646D01*
X46873Y571855D01*
X46956Y572105D01*
X46873Y572355D01*
X46665Y572563D01*
X46290Y572688D01*
X45915Y572646D01*
X45540Y572480D01*
G01X49223Y572688D02*
X48890Y572605D01*
X48640Y572396D01*
X48473Y572146D01*
X48348Y571813D01*
X48306Y571438D01*
X48348Y571063D01*
X48473Y570730D01*
X48640Y570480D01*
X48890Y570271D01*
X49223Y570188D01*
X49556Y570271D01*
X49806Y570480D01*
X49973Y570730D01*
X50098Y571063D01*
X50140Y571438D01*
X50098Y571813D01*
X49973Y572146D01*
X49806Y572396D01*
X49556Y572605D01*
X49223Y572688D01*
G01X25906Y570419D02*
Y572919D01*
X26947D01*
X27281Y572794D01*
X27489Y572627D01*
X27572Y572294D01*
X27489Y571961D01*
X27239Y571752D01*
X26947Y571627D01*
X25906D01*
G01X26947D02*
X27572Y570419D01*
G01X29047Y572502D02*
X29297Y572752D01*
X29589Y572877D01*
X29922Y572919D01*
X30339Y572836D01*
X30631Y572627D01*
X30714Y572377D01*
X30672Y572127D01*
X30506Y571919D01*
X29672Y571502D01*
X29297Y571211D01*
X29047Y570794D01*
X28964Y570419D01*
X30714D01*
G01X32147Y572502D02*
X32397Y572752D01*
X32689Y572877D01*
X33022Y572919D01*
X33439Y572836D01*
X33731Y572627D01*
X33814Y572377D01*
X33772Y572127D01*
X33606Y571919D01*
X32772Y571502D01*
X32397Y571211D01*
X32147Y570794D01*
X32064Y570419D01*
X33814D01*
G01X35331Y570711D02*
X35622Y570502D01*
X35956Y570419D01*
X36289Y570502D01*
X36581Y570752D01*
X36789Y571127D01*
X36872Y571502D01*
Y571961D01*
X36789Y572336D01*
X36581Y572669D01*
X36331Y572836D01*
X36039Y572919D01*
X35706Y572836D01*
X35456Y572669D01*
X35289Y572419D01*
X35206Y572086D01*
X35289Y571794D01*
X35497Y571502D01*
X35747Y571336D01*
X36039Y571294D01*
X36372Y571377D01*
X36622Y571586D01*
X36872Y571961D01*
G01X39090Y578188D02*
Y580688D01*
X40131D01*
X40465Y580563D01*
X40673Y580396D01*
X40756Y580063D01*
X40673Y579730D01*
X40423Y579521D01*
X40131Y579396D01*
X39090D01*
G01X40131D02*
X40756Y578188D01*
G01X42231Y580271D02*
X42481Y580521D01*
X42773Y580646D01*
X43106Y580688D01*
X43523Y580605D01*
X43815Y580396D01*
X43898Y580146D01*
X43856Y579896D01*
X43690Y579688D01*
X42856Y579271D01*
X42481Y578980D01*
X42231Y578563D01*
X42148Y578188D01*
X43898D01*
G01X45331Y580271D02*
X45581Y580521D01*
X45873Y580646D01*
X46206Y580688D01*
X46623Y580605D01*
X46915Y580396D01*
X46998Y580146D01*
X46956Y579896D01*
X46790Y579688D01*
X45956Y579271D01*
X45581Y578980D01*
X45331Y578563D01*
X45248Y578188D01*
X46998D01*
G01X49223D02*
X49515Y578230D01*
X49848Y578355D01*
X50056Y578563D01*
X50140Y578855D01*
X50056Y579146D01*
X49806Y579396D01*
X49431Y579521D01*
X49015D01*
X48765Y579605D01*
X48556Y579813D01*
X48473Y580105D01*
X48598Y580396D01*
X48890Y580605D01*
X49223Y580688D01*
X49556Y580605D01*
X49848Y580396D01*
X49973Y580105D01*
X49890Y579813D01*
X49681Y579605D01*
X49431Y579521D01*
X49015D01*
X48640Y579396D01*
X48390Y579146D01*
X48306Y578855D01*
X48390Y578563D01*
X48598Y578355D01*
X48931Y578230D01*
X49223Y578188D01*
G01X25906Y578419D02*
Y580919D01*
X26947D01*
X27281Y580794D01*
X27489Y580627D01*
X27572Y580294D01*
X27489Y579961D01*
X27239Y579752D01*
X26947Y579627D01*
X25906D01*
G01X26947D02*
X27572Y578419D01*
G01X29047Y580502D02*
X29297Y580752D01*
X29589Y580877D01*
X29922Y580919D01*
X30339Y580836D01*
X30631Y580627D01*
X30714Y580377D01*
X30672Y580127D01*
X30506Y579919D01*
X29672Y579502D01*
X29297Y579211D01*
X29047Y578794D01*
X28964Y578419D01*
X30714D01*
G01X32147Y580502D02*
X32397Y580752D01*
X32689Y580877D01*
X33022Y580919D01*
X33439Y580836D01*
X33731Y580627D01*
X33814Y580377D01*
X33772Y580127D01*
X33606Y579919D01*
X32772Y579502D01*
X32397Y579211D01*
X32147Y578794D01*
X32064Y578419D01*
X33814D01*
G01X35956D02*
X36039Y578961D01*
X36164Y579419D01*
X36331Y579836D01*
X36539Y580294D01*
X36872Y580919D01*
X35206D01*
G01X39090Y574188D02*
Y576688D01*
X40131D01*
X40465Y576563D01*
X40673Y576396D01*
X40756Y576063D01*
X40673Y575730D01*
X40423Y575521D01*
X40131Y575396D01*
X39090D01*
G01X40131D02*
X40756Y574188D01*
G01X42231Y576271D02*
X42481Y576521D01*
X42773Y576646D01*
X43106Y576688D01*
X43523Y576605D01*
X43815Y576396D01*
X43898Y576146D01*
X43856Y575896D01*
X43690Y575688D01*
X42856Y575271D01*
X42481Y574980D01*
X42231Y574563D01*
X42148Y574188D01*
X43898D01*
G01X46123D02*
Y576688D01*
X45623Y576188D01*
G01Y574188D02*
X46623D01*
G01X49223D02*
X49515Y574230D01*
X49848Y574355D01*
X50056Y574563D01*
X50140Y574855D01*
X50056Y575146D01*
X49806Y575396D01*
X49431Y575521D01*
X49015D01*
X48765Y575605D01*
X48556Y575813D01*
X48473Y576105D01*
X48598Y576396D01*
X48890Y576605D01*
X49223Y576688D01*
X49556Y576605D01*
X49848Y576396D01*
X49973Y576105D01*
X49890Y575813D01*
X49681Y575605D01*
X49431Y575521D01*
X49015D01*
X48640Y575396D01*
X48390Y575146D01*
X48306Y574855D01*
X48390Y574563D01*
X48598Y574355D01*
X48931Y574230D01*
X49223Y574188D01*
G01X25906Y574419D02*
Y576919D01*
X26947D01*
X27281Y576794D01*
X27489Y576627D01*
X27572Y576294D01*
X27489Y575961D01*
X27239Y575752D01*
X26947Y575627D01*
X25906D01*
G01X26947D02*
X27572Y574419D01*
G01X29047Y576502D02*
X29297Y576752D01*
X29589Y576877D01*
X29922Y576919D01*
X30339Y576836D01*
X30631Y576627D01*
X30714Y576377D01*
X30672Y576127D01*
X30506Y575919D01*
X29672Y575502D01*
X29297Y575211D01*
X29047Y574794D01*
X28964Y574419D01*
X30714D01*
G01X32939D02*
Y576919D01*
X32439Y576419D01*
G01Y574419D02*
X33439D01*
G01X35956D02*
X36039Y574961D01*
X36164Y575419D01*
X36331Y575836D01*
X36539Y576294D01*
X36872Y576919D01*
X35206D01*
G01X25000Y596300D02*
X27500D01*
G01X25000Y595342D02*
Y597258D01*
G01X27500Y598567D02*
X25000D01*
Y599567D01*
X25125Y599900D01*
X25417Y600150D01*
X25750Y600233D01*
X26083Y600150D01*
X26333Y599942D01*
X26458Y599567D01*
Y598567D01*
G01X27500Y602500D02*
X25000D01*
X25500Y602000D01*
G01X27500D02*
Y603000D01*
G01Y605600D02*
X27458Y605892D01*
X27333Y606225D01*
X27125Y606433D01*
X26833Y606517D01*
X26542Y606433D01*
X26292Y606183D01*
X26167Y605808D01*
Y605392D01*
X26083Y605142D01*
X25875Y604933D01*
X25583Y604850D01*
X25292Y604975D01*
X25083Y605267D01*
X25000Y605600D01*
X25083Y605933D01*
X25292Y606225D01*
X25583Y606350D01*
X25875Y606267D01*
X26083Y606058D01*
X26167Y605808D01*
Y605392D01*
X26292Y605017D01*
X26542Y604767D01*
X26833Y604683D01*
X27125Y604767D01*
X27333Y604975D01*
X27458Y605308D01*
X27500Y605600D01*
G01X27208Y607992D02*
X27417Y608283D01*
X27500Y608617D01*
X27417Y608950D01*
X27167Y609242D01*
X26792Y609450D01*
X26417Y609533D01*
X25958D01*
X25583Y609450D01*
X25250Y609242D01*
X25083Y608992D01*
X25000Y608700D01*
X25083Y608367D01*
X25250Y608117D01*
X25500Y607950D01*
X25833Y607867D01*
X26125Y607950D01*
X26417Y608158D01*
X26583Y608408D01*
X26625Y608700D01*
X26542Y609033D01*
X26333Y609283D01*
X25958Y609533D01*
G01X29000Y598800D02*
X31500D01*
G01X29000Y597842D02*
Y599758D01*
G01X31500Y601067D02*
X29000D01*
Y602067D01*
X29125Y602400D01*
X29417Y602650D01*
X29750Y602733D01*
X30083Y602650D01*
X30333Y602442D01*
X30458Y602067D01*
Y601067D01*
G01X31500Y605000D02*
X29000D01*
X29500Y604500D01*
G01X31500D02*
Y605500D01*
G01Y608100D02*
X31458Y608392D01*
X31333Y608725D01*
X31125Y608933D01*
X30833Y609017D01*
X30542Y608933D01*
X30292Y608683D01*
X30167Y608308D01*
Y607892D01*
X30083Y607642D01*
X29875Y607433D01*
X29583Y607350D01*
X29292Y607475D01*
X29083Y607767D01*
X29000Y608100D01*
X29083Y608433D01*
X29292Y608725D01*
X29583Y608850D01*
X29875Y608767D01*
X30083Y608558D01*
X30167Y608308D01*
Y607892D01*
X30292Y607517D01*
X30542Y607267D01*
X30833Y607183D01*
X31125Y607267D01*
X31333Y607475D01*
X31458Y607808D01*
X31500Y608100D01*
G01Y611200D02*
X31458Y611492D01*
X31333Y611825D01*
X31125Y612033D01*
X30833Y612117D01*
X30542Y612033D01*
X30292Y611783D01*
X30167Y611408D01*
Y610992D01*
X30083Y610742D01*
X29875Y610533D01*
X29583Y610450D01*
X29292Y610575D01*
X29083Y610867D01*
X29000Y611200D01*
X29083Y611533D01*
X29292Y611825D01*
X29583Y611950D01*
X29875Y611867D01*
X30083Y611658D01*
X30167Y611408D01*
Y610992D01*
X30292Y610617D01*
X30542Y610367D01*
X30833Y610283D01*
X31125Y610367D01*
X31333Y610575D01*
X31458Y610908D01*
X31500Y611200D01*
G01X37000Y593300D02*
X39500D01*
G01X37000Y592342D02*
Y594258D01*
G01X39500Y595567D02*
X37000D01*
Y596567D01*
X37125Y596900D01*
X37417Y597150D01*
X37750Y597233D01*
X38083Y597150D01*
X38333Y596942D01*
X38458Y596567D01*
Y595567D01*
G01X39500Y599500D02*
X37000D01*
X37500Y599000D01*
G01X39500D02*
Y600000D01*
G01Y602600D02*
X39458Y602892D01*
X39333Y603225D01*
X39125Y603433D01*
X38833Y603517D01*
X38542Y603433D01*
X38292Y603183D01*
X38167Y602808D01*
Y602392D01*
X38083Y602142D01*
X37875Y601933D01*
X37583Y601850D01*
X37292Y601975D01*
X37083Y602267D01*
X37000Y602600D01*
X37083Y602933D01*
X37292Y603225D01*
X37583Y603350D01*
X37875Y603267D01*
X38083Y603058D01*
X38167Y602808D01*
Y602392D01*
X38292Y602017D01*
X38542Y601767D01*
X38833Y601683D01*
X39125Y601767D01*
X39333Y601975D01*
X39458Y602308D01*
X39500Y602600D01*
G01Y605617D02*
X38958Y605700D01*
X38500Y605825D01*
X38083Y605992D01*
X37625Y606200D01*
X37000Y606533D01*
Y604867D01*
G01X33000Y596300D02*
X35500D01*
G01X33000Y595342D02*
Y597258D01*
G01X35500Y598567D02*
X33000D01*
Y599567D01*
X33125Y599900D01*
X33417Y600150D01*
X33750Y600233D01*
X34083Y600150D01*
X34333Y599942D01*
X34458Y599567D01*
Y598567D01*
G01X35500Y602500D02*
X33000D01*
X33500Y602000D01*
G01X35500D02*
Y603000D01*
G01Y605600D02*
X35458Y605892D01*
X35333Y606225D01*
X35125Y606433D01*
X34833Y606517D01*
X34542Y606433D01*
X34292Y606183D01*
X34167Y605808D01*
Y605392D01*
X34083Y605142D01*
X33875Y604933D01*
X33583Y604850D01*
X33292Y604975D01*
X33083Y605267D01*
X33000Y605600D01*
X33083Y605933D01*
X33292Y606225D01*
X33583Y606350D01*
X33875Y606267D01*
X34083Y606058D01*
X34167Y605808D01*
Y605392D01*
X34292Y605017D01*
X34542Y604767D01*
X34833Y604683D01*
X35125Y604767D01*
X35333Y604975D01*
X35458Y605308D01*
X35500Y605600D01*
G01X34458Y607908D02*
X34167Y608200D01*
X34000Y608450D01*
X33917Y608783D01*
X34000Y609075D01*
X34167Y609283D01*
X34417Y609450D01*
X34708Y609492D01*
X34958Y609450D01*
X35208Y609283D01*
X35417Y609033D01*
X35500Y608742D01*
X35417Y608408D01*
X35167Y608117D01*
X34792Y607950D01*
X34375Y607908D01*
X33833Y607992D01*
X33542Y608117D01*
X33250Y608325D01*
X33042Y608617D01*
X33000Y608908D01*
X33083Y609200D01*
X33292Y609408D01*
G01X52513Y570022D02*
X54305D01*
X54680Y570189D01*
X54930Y570522D01*
X55013Y570939D01*
X54930Y571356D01*
X54680Y571689D01*
X54305Y571856D01*
X52513D01*
G01X52930Y573247D02*
X52680Y573497D01*
X52555Y573789D01*
X52513Y574122D01*
X52596Y574539D01*
X52805Y574831D01*
X53055Y574914D01*
X53305Y574872D01*
X53513Y574706D01*
X53930Y573872D01*
X54221Y573497D01*
X54638Y573247D01*
X55013Y573164D01*
Y574914D01*
G01Y577139D02*
X54971Y577431D01*
X54846Y577764D01*
X54638Y577972D01*
X54346Y578056D01*
X54055Y577972D01*
X53805Y577722D01*
X53680Y577347D01*
Y576931D01*
X53596Y576681D01*
X53388Y576472D01*
X53096Y576389D01*
X52805Y576514D01*
X52596Y576806D01*
X52513Y577139D01*
X52596Y577472D01*
X52805Y577764D01*
X53096Y577889D01*
X53388Y577806D01*
X53596Y577597D01*
X53680Y577347D01*
Y576931D01*
X53805Y576556D01*
X54055Y576306D01*
X54346Y576222D01*
X54638Y576306D01*
X54846Y576514D01*
X54971Y576847D01*
X55013Y577139D01*
G01X36125Y665008D02*
X35875Y665133D01*
X35583Y665216D01*
X35250D01*
X34875Y665091D01*
X34583Y664883D01*
X34375Y664633D01*
X34208Y664216D01*
X34166Y663841D01*
X34250Y663466D01*
X34375Y663216D01*
X34625Y662966D01*
X34916Y662799D01*
X35208Y662716D01*
X35500D01*
X35791Y662799D01*
X36041Y662924D01*
X36250Y663091D01*
G01X37516Y664799D02*
X37766Y665049D01*
X38058Y665174D01*
X38391Y665216D01*
X38808Y665133D01*
X39100Y664924D01*
X39183Y664674D01*
X39141Y664424D01*
X38975Y664216D01*
X38141Y663799D01*
X37766Y663508D01*
X37516Y663091D01*
X37433Y662716D01*
X39183D01*
G01X40616Y664799D02*
X40866Y665049D01*
X41158Y665174D01*
X41491Y665216D01*
X41908Y665133D01*
X42200Y664924D01*
X42283Y664674D01*
X42241Y664424D01*
X42075Y664216D01*
X41241Y663799D01*
X40866Y663508D01*
X40616Y663091D01*
X40533Y662716D01*
X42283D01*
G01X44508D02*
X44800Y662758D01*
X45133Y662883D01*
X45341Y663091D01*
X45425Y663383D01*
X45341Y663674D01*
X45091Y663924D01*
X44716Y664049D01*
X44300D01*
X44050Y664133D01*
X43841Y664341D01*
X43758Y664633D01*
X43883Y664924D01*
X44175Y665133D01*
X44508Y665216D01*
X44841Y665133D01*
X45133Y664924D01*
X45258Y664633D01*
X45175Y664341D01*
X44966Y664133D01*
X44716Y664049D01*
X44300D01*
X43925Y663924D01*
X43675Y663674D01*
X43591Y663383D01*
X43675Y663091D01*
X43883Y662883D01*
X44216Y662758D01*
X44508Y662716D01*
G01X44967Y646992D02*
X44717Y647117D01*
X44425Y647200D01*
X44092D01*
X43717Y647075D01*
X43425Y646867D01*
X43217Y646617D01*
X43050Y646200D01*
X43008Y645825D01*
X43092Y645450D01*
X43217Y645200D01*
X43467Y644950D01*
X43758Y644783D01*
X44050Y644700D01*
X44342D01*
X44633Y644783D01*
X44883Y644908D01*
X45092Y645075D01*
G01X46358Y646783D02*
X46608Y647033D01*
X46900Y647158D01*
X47233Y647200D01*
X47650Y647117D01*
X47942Y646908D01*
X48025Y646658D01*
X47983Y646408D01*
X47817Y646200D01*
X46983Y645783D01*
X46608Y645492D01*
X46358Y645075D01*
X46275Y644700D01*
X48025D01*
G01X49458Y646783D02*
X49708Y647033D01*
X50000Y647158D01*
X50333Y647200D01*
X50750Y647117D01*
X51042Y646908D01*
X51125Y646658D01*
X51083Y646408D01*
X50917Y646200D01*
X50083Y645783D01*
X49708Y645492D01*
X49458Y645075D01*
X49375Y644700D01*
X51125D01*
G01X52558Y646783D02*
X52808Y647033D01*
X53100Y647158D01*
X53433Y647200D01*
X53850Y647117D01*
X54142Y646908D01*
X54225Y646658D01*
X54183Y646408D01*
X54017Y646200D01*
X53183Y645783D01*
X52808Y645492D01*
X52558Y645075D01*
X52475Y644700D01*
X54225D01*
G01X35989Y669204D02*
X35739Y669329D01*
X35447Y669412D01*
X35114D01*
X34739Y669287D01*
X34447Y669079D01*
X34239Y668829D01*
X34072Y668412D01*
X34030Y668037D01*
X34114Y667662D01*
X34239Y667412D01*
X34489Y667162D01*
X34780Y666995D01*
X35072Y666912D01*
X35364D01*
X35655Y666995D01*
X35905Y667120D01*
X36114Y667287D01*
G01X37380Y668995D02*
X37630Y669245D01*
X37922Y669370D01*
X38255Y669412D01*
X38672Y669329D01*
X38964Y669120D01*
X39047Y668870D01*
X39005Y668620D01*
X38839Y668412D01*
X38005Y667995D01*
X37630Y667704D01*
X37380Y667287D01*
X37297Y666912D01*
X39047D01*
G01X40355Y667412D02*
X40605Y667120D01*
X40939Y666954D01*
X41314Y666912D01*
X41647Y666954D01*
X41980Y667162D01*
X42189Y667412D01*
X42230Y667662D01*
X42147Y667954D01*
X41855Y668162D01*
X41564Y668245D01*
X41189D01*
G01X41564D02*
X41814Y668370D01*
X42022Y668579D01*
X42105Y668829D01*
X42022Y669079D01*
X41814Y669287D01*
X41439Y669412D01*
X41064Y669370D01*
X40689Y669204D01*
G01X43455Y667412D02*
X43705Y667120D01*
X44039Y666954D01*
X44414Y666912D01*
X44747Y666954D01*
X45080Y667162D01*
X45289Y667412D01*
X45330Y667662D01*
X45247Y667954D01*
X44955Y668162D01*
X44664Y668245D01*
X44289D01*
G01X44664D02*
X44914Y668370D01*
X45122Y668579D01*
X45205Y668829D01*
X45122Y669079D01*
X44914Y669287D01*
X44539Y669412D01*
X44164Y669370D01*
X43789Y669204D01*
G01X43217Y648400D02*
Y650900D01*
X44258D01*
X44592Y650775D01*
X44800Y650608D01*
X44883Y650275D01*
X44800Y649942D01*
X44550Y649733D01*
X44258Y649608D01*
X43217D01*
G01X44258D02*
X44883Y648400D01*
G01X46233Y648775D02*
X46483Y648567D01*
X46775Y648442D01*
X47150Y648400D01*
X47525Y648483D01*
X47817Y648650D01*
X48025Y648942D01*
X48067Y649275D01*
X47983Y649608D01*
X47775Y649817D01*
X47483Y649983D01*
X47192Y650025D01*
X46900Y649983D01*
X46525Y649817D01*
X46650Y650900D01*
X47775D01*
G01X49333Y648900D02*
X49583Y648608D01*
X49917Y648442D01*
X50292Y648400D01*
X50625Y648442D01*
X50958Y648650D01*
X51167Y648900D01*
X51208Y649150D01*
X51125Y649442D01*
X50833Y649650D01*
X50542Y649733D01*
X50167D01*
G01X50542D02*
X50792Y649858D01*
X51000Y650067D01*
X51083Y650317D01*
X51000Y650567D01*
X50792Y650775D01*
X50417Y650900D01*
X50042Y650858D01*
X49667Y650692D01*
G01X53350Y648400D02*
Y650900D01*
X52850Y650400D01*
G01Y648400D02*
X53850D01*
G01X59346Y649850D02*
Y645850D01*
X66746D01*
G01X44774Y638368D02*
Y640868D01*
X45815D01*
X46149Y640743D01*
X46357Y640576D01*
X46440Y640243D01*
X46357Y639910D01*
X46107Y639701D01*
X45815Y639576D01*
X44774D01*
G01X45815D02*
X46440Y638368D01*
G01X47790Y638743D02*
X48040Y638535D01*
X48332Y638410D01*
X48707Y638368D01*
X49082Y638451D01*
X49374Y638618D01*
X49582Y638910D01*
X49624Y639243D01*
X49540Y639576D01*
X49332Y639785D01*
X49040Y639951D01*
X48749Y639993D01*
X48457Y639951D01*
X48082Y639785D01*
X48207Y640868D01*
X49332D01*
G01X50890Y638868D02*
X51140Y638576D01*
X51474Y638410D01*
X51849Y638368D01*
X52182Y638410D01*
X52515Y638618D01*
X52724Y638868D01*
X52765Y639118D01*
X52682Y639410D01*
X52390Y639618D01*
X52099Y639701D01*
X51724D01*
G01X52099D02*
X52349Y639826D01*
X52557Y640035D01*
X52640Y640285D01*
X52557Y640535D01*
X52349Y640743D01*
X51974Y640868D01*
X51599Y640826D01*
X51224Y640660D01*
G01X54907Y640868D02*
X54574Y640785D01*
X54324Y640576D01*
X54157Y640326D01*
X54032Y639993D01*
X53990Y639618D01*
X54032Y639243D01*
X54157Y638910D01*
X54324Y638660D01*
X54574Y638451D01*
X54907Y638368D01*
X55240Y638451D01*
X55490Y638660D01*
X55657Y638910D01*
X55782Y639243D01*
X55824Y639618D01*
X55782Y639993D01*
X55657Y640326D01*
X55490Y640576D01*
X55240Y640785D01*
X54907Y640868D01*
G01X66854Y637950D02*
Y641950D01*
X59454D01*
G01X36396Y671374D02*
X33896D01*
Y672415D01*
X34021Y672749D01*
X34188Y672957D01*
X34521Y673040D01*
X34854Y672957D01*
X35063Y672707D01*
X35188Y672415D01*
Y671374D01*
G01Y672415D02*
X36396Y673040D01*
G01X36021Y674390D02*
X36229Y674640D01*
X36354Y674932D01*
X36396Y675307D01*
X36313Y675682D01*
X36146Y675974D01*
X35854Y676182D01*
X35521Y676224D01*
X35188Y676140D01*
X34979Y675932D01*
X34813Y675640D01*
X34771Y675349D01*
X34813Y675057D01*
X34979Y674682D01*
X33896Y674807D01*
Y675932D01*
G01X35896Y677490D02*
X36188Y677740D01*
X36354Y678074D01*
X36396Y678449D01*
X36354Y678782D01*
X36146Y679115D01*
X35896Y679324D01*
X35646Y679365D01*
X35354Y679282D01*
X35146Y678990D01*
X35063Y678699D01*
Y678324D01*
G01Y678699D02*
X34938Y678949D01*
X34729Y679157D01*
X34479Y679240D01*
X34229Y679157D01*
X34021Y678949D01*
X33896Y678574D01*
X33938Y678199D01*
X34104Y677824D01*
G01X36396Y682007D02*
X33896D01*
X35688Y680465D01*
Y682549D01*
G01X50200Y680984D02*
X46200D01*
Y673584D01*
G01X21017Y679500D02*
Y682000D01*
X22058D01*
X22392Y681875D01*
X22600Y681708D01*
X22683Y681375D01*
X22600Y681042D01*
X22350Y680833D01*
X22058Y680708D01*
X21017D01*
G01X22058D02*
X22683Y679500D01*
G01X24033Y679875D02*
X24283Y679667D01*
X24575Y679542D01*
X24950Y679500D01*
X25325Y679583D01*
X25617Y679750D01*
X25825Y680042D01*
X25867Y680375D01*
X25783Y680708D01*
X25575Y680917D01*
X25283Y681083D01*
X24992Y681125D01*
X24700Y681083D01*
X24325Y680917D01*
X24450Y682000D01*
X25575D01*
G01X27133Y680000D02*
X27383Y679708D01*
X27717Y679542D01*
X28092Y679500D01*
X28425Y679542D01*
X28758Y679750D01*
X28967Y680000D01*
X29008Y680250D01*
X28925Y680542D01*
X28633Y680750D01*
X28342Y680833D01*
X27967D01*
G01X28342D02*
X28592Y680958D01*
X28800Y681167D01*
X28883Y681417D01*
X28800Y681667D01*
X28592Y681875D01*
X28217Y682000D01*
X27842Y681958D01*
X27467Y681792D01*
G01X30233Y679875D02*
X30483Y679667D01*
X30775Y679542D01*
X31150Y679500D01*
X31525Y679583D01*
X31817Y679750D01*
X32025Y680042D01*
X32067Y680375D01*
X31983Y680708D01*
X31775Y680917D01*
X31483Y681083D01*
X31192Y681125D01*
X30900Y681083D01*
X30525Y680917D01*
X30650Y682000D01*
X31775D01*
G01X45154Y677750D02*
Y681750D01*
X37754D01*
G01X48517Y682000D02*
Y684500D01*
X49517D01*
X49850Y684375D01*
X50100Y684083D01*
X50183Y683750D01*
X50100Y683417D01*
X49892Y683167D01*
X49517Y683042D01*
X48517D01*
G01X51533Y684500D02*
Y682708D01*
X51700Y682333D01*
X52033Y682083D01*
X52450Y682000D01*
X52867Y682083D01*
X53200Y682333D01*
X53367Y682708D01*
Y684500D01*
G01X55550Y682000D02*
Y684500D01*
X55050Y684000D01*
G01Y682000D02*
X56050D01*
G01X58650Y684500D02*
X58317Y684417D01*
X58067Y684208D01*
X57900Y683958D01*
X57775Y683625D01*
X57733Y683250D01*
X57775Y682875D01*
X57900Y682542D01*
X58067Y682292D01*
X58317Y682083D01*
X58650Y682000D01*
X58983Y682083D01*
X59233Y682292D01*
X59400Y682542D01*
X59525Y682875D01*
X59567Y683250D01*
X59525Y683625D01*
X59400Y683958D01*
X59233Y684208D01*
X58983Y684417D01*
X58650Y684500D01*
G01X51864Y657000D02*
Y652000D01*
X56864D01*
G01Y679700D02*
X51864D01*
Y674700D01*
G01X60596Y678293D02*
Y681293D01*
G01X53271Y660732D02*
X51271D01*
G01X89017Y45166D02*
Y47666D01*
X90017D01*
X90350Y47541D01*
X90600Y47249D01*
X90683Y46916D01*
X90600Y46583D01*
X90392Y46333D01*
X90017Y46208D01*
X89017D01*
G01X91700Y47666D02*
X92283Y45166D01*
X92950Y47666D01*
X93617Y45166D01*
X94200Y47666D01*
G01X95217Y45166D02*
Y47666D01*
X96258D01*
X96592Y47541D01*
X96800Y47374D01*
X96883Y47041D01*
X96800Y46708D01*
X96550Y46499D01*
X96258Y46374D01*
X95217D01*
G01X96258D02*
X96883Y45166D01*
G01X99150D02*
Y47666D01*
X98650Y47166D01*
G01Y45166D02*
X99650D01*
G01X86588Y549D02*
Y21849D01*
X78938D01*
Y40499D01*
X76788D01*
Y51149D01*
X84488D01*
Y42549D01*
X104488D01*
Y51149D01*
X112188D01*
Y40499D01*
X110038D01*
Y21849D01*
X102388D01*
Y549D01*
X86588D01*
G01X80268Y65455D02*
X76268D01*
Y58055D01*
G01X101642Y54017D02*
Y56517D01*
X102683D01*
X103017Y56392D01*
X103225Y56225D01*
X103308Y55892D01*
X103225Y55559D01*
X102975Y55350D01*
X102683Y55225D01*
X101642D01*
G01X102683D02*
X103308Y54017D01*
G01X106075D02*
Y56517D01*
X104533Y54725D01*
X106617D01*
G01X107758Y54392D02*
X108008Y54184D01*
X108300Y54059D01*
X108675Y54017D01*
X109050Y54100D01*
X109342Y54267D01*
X109550Y54559D01*
X109592Y54892D01*
X109508Y55225D01*
X109300Y55434D01*
X109008Y55600D01*
X108717Y55642D01*
X108425Y55600D01*
X108050Y55434D01*
X108175Y56517D01*
X109300D01*
G01X100468Y53255D02*
Y57255D01*
X93068D01*
G01X84868Y55755D02*
X80668D01*
G01X84868Y67455D02*
Y55755D01*
G01X80668D02*
Y67455D01*
G01X92968Y58255D02*
X87468D01*
Y66255D01*
X93068D01*
G01X105068Y58255D02*
X99568D01*
G01X105068D02*
Y66255D01*
X99568D01*
G01X80301Y72422D02*
Y74922D01*
X81135D01*
X81468Y74797D01*
X81718Y74630D01*
X81926Y74380D01*
X82093Y74089D01*
X82135Y73672D01*
X82093Y73255D01*
X81926Y72964D01*
X81718Y72714D01*
X81468Y72547D01*
X81135Y72422D01*
X80301D01*
G01X83526Y74505D02*
X83776Y74755D01*
X84068Y74880D01*
X84401Y74922D01*
X84818Y74839D01*
X85110Y74630D01*
X85193Y74380D01*
X85151Y74130D01*
X84985Y73922D01*
X84151Y73505D01*
X83776Y73214D01*
X83526Y72797D01*
X83443Y72422D01*
X85193D01*
G01X80668Y67455D02*
X84868D01*
G01X95140Y70280D02*
X94890Y70405D01*
X94598Y70488D01*
X94265D01*
X93890Y70363D01*
X93598Y70155D01*
X93390Y69905D01*
X93223Y69488D01*
X93181Y69113D01*
X93265Y68738D01*
X93390Y68488D01*
X93640Y68238D01*
X93931Y68071D01*
X94223Y67988D01*
X94515D01*
X94806Y68071D01*
X95056Y68196D01*
X95265Y68363D01*
G01X96406D02*
X96656Y68155D01*
X96948Y68030D01*
X97323Y67988D01*
X97698Y68071D01*
X97990Y68238D01*
X98198Y68530D01*
X98240Y68863D01*
X98156Y69196D01*
X97948Y69405D01*
X97656Y69571D01*
X97365Y69613D01*
X97073Y69571D01*
X96698Y69405D01*
X96823Y70488D01*
X97948D01*
G01X99631Y70071D02*
X99881Y70321D01*
X100173Y70446D01*
X100506Y70488D01*
X100923Y70405D01*
X101215Y70196D01*
X101298Y69946D01*
X101256Y69696D01*
X101090Y69488D01*
X100256Y69071D01*
X99881Y68780D01*
X99631Y68363D01*
X99548Y67988D01*
X101298D01*
G01X103523D02*
X103815Y68030D01*
X104148Y68155D01*
X104356Y68363D01*
X104440Y68655D01*
X104356Y68946D01*
X104106Y69196D01*
X103731Y69321D01*
X103315D01*
X103065Y69405D01*
X102856Y69613D01*
X102773Y69905D01*
X102898Y70196D01*
X103190Y70405D01*
X103523Y70488D01*
X103856Y70405D01*
X104148Y70196D01*
X104273Y69905D01*
X104190Y69613D01*
X103981Y69405D01*
X103731Y69321D01*
X103315D01*
X102940Y69196D01*
X102690Y68946D01*
X102606Y68655D01*
X102690Y68363D01*
X102898Y68155D01*
X103231Y68030D01*
X103523Y67988D01*
G01X99500Y416669D02*
X114500D01*
G01X77772Y422199D02*
X80272D01*
G01X77772Y421241D02*
Y423157D01*
G01X80272Y424466D02*
X77772D01*
Y425466D01*
X77897Y425799D01*
X78189Y426049D01*
X78522Y426132D01*
X78855Y426049D01*
X79105Y425841D01*
X79230Y425466D01*
Y424466D01*
G01X80272Y428399D02*
X77772D01*
X78272Y427899D01*
G01X80272D02*
Y428899D01*
G01X78189Y430707D02*
X77939Y430957D01*
X77814Y431249D01*
X77772Y431582D01*
X77855Y431999D01*
X78064Y432291D01*
X78314Y432374D01*
X78564Y432332D01*
X78772Y432166D01*
X79189Y431332D01*
X79480Y430957D01*
X79897Y430707D01*
X80272Y430624D01*
Y432374D01*
G01X115000Y476467D02*
X112500D01*
Y477508D01*
X112625Y477842D01*
X112792Y478050D01*
X113125Y478133D01*
X113458Y478050D01*
X113667Y477800D01*
X113792Y477508D01*
Y476467D01*
G01Y477508D02*
X115000Y478133D01*
G01Y480400D02*
X114958Y480692D01*
X114833Y481025D01*
X114625Y481233D01*
X114333Y481317D01*
X114042Y481233D01*
X113792Y480983D01*
X113667Y480608D01*
Y480192D01*
X113583Y479942D01*
X113375Y479733D01*
X113083Y479650D01*
X112792Y479775D01*
X112583Y480067D01*
X112500Y480400D01*
X112583Y480733D01*
X112792Y481025D01*
X113083Y481150D01*
X113375Y481067D01*
X113583Y480858D01*
X113667Y480608D01*
Y480192D01*
X113792Y479817D01*
X114042Y479567D01*
X114333Y479483D01*
X114625Y479567D01*
X114833Y479775D01*
X114958Y480108D01*
X115000Y480400D01*
G01Y484000D02*
X112500D01*
X114292Y482458D01*
Y484542D01*
G01X106500Y476800D02*
X110500D01*
Y484200D01*
G01X90117Y453730D02*
Y456230D01*
X91158D01*
X91492Y456105D01*
X91700Y455938D01*
X91783Y455605D01*
X91700Y455272D01*
X91450Y455063D01*
X91158Y454938D01*
X90117D01*
G01X91158D02*
X91783Y453730D01*
G01X93133Y454230D02*
X93383Y453938D01*
X93717Y453772D01*
X94092Y453730D01*
X94425Y453772D01*
X94758Y453980D01*
X94967Y454230D01*
X95008Y454480D01*
X94925Y454772D01*
X94633Y454980D01*
X94342Y455063D01*
X93967D01*
G01X94342D02*
X94592Y455188D01*
X94800Y455397D01*
X94883Y455647D01*
X94800Y455897D01*
X94592Y456105D01*
X94217Y456230D01*
X93842Y456188D01*
X93467Y456022D01*
G01X96233Y454105D02*
X96483Y453897D01*
X96775Y453772D01*
X97150Y453730D01*
X97525Y453813D01*
X97817Y453980D01*
X98025Y454272D01*
X98067Y454605D01*
X97983Y454938D01*
X97775Y455147D01*
X97483Y455313D01*
X97192Y455355D01*
X96900Y455313D01*
X96525Y455147D01*
X96650Y456230D01*
X97775D01*
G01X100750Y453730D02*
Y456230D01*
X99208Y454438D01*
X101292D01*
G01X100000Y476367D02*
X97500D01*
Y477408D01*
X97625Y477742D01*
X97792Y477950D01*
X98125Y478033D01*
X98458Y477950D01*
X98667Y477700D01*
X98792Y477408D01*
Y476367D01*
G01Y477408D02*
X100000Y478033D01*
G01Y480300D02*
X99958Y480592D01*
X99833Y480925D01*
X99625Y481133D01*
X99333Y481217D01*
X99042Y481133D01*
X98792Y480883D01*
X98667Y480508D01*
Y480092D01*
X98583Y479842D01*
X98375Y479633D01*
X98083Y479550D01*
X97792Y479675D01*
X97583Y479967D01*
X97500Y480300D01*
X97583Y480633D01*
X97792Y480925D01*
X98083Y481050D01*
X98375Y480967D01*
X98583Y480758D01*
X98667Y480508D01*
Y480092D01*
X98792Y479717D01*
X99042Y479467D01*
X99333Y479383D01*
X99625Y479467D01*
X99833Y479675D01*
X99958Y480008D01*
X100000Y480300D01*
G01X99625Y482483D02*
X99833Y482733D01*
X99958Y483025D01*
X100000Y483400D01*
X99917Y483775D01*
X99750Y484067D01*
X99458Y484275D01*
X99125Y484317D01*
X98792Y484233D01*
X98583Y484025D01*
X98417Y483733D01*
X98375Y483442D01*
X98417Y483150D01*
X98583Y482775D01*
X97500Y482900D01*
Y484025D01*
G01X106000Y484200D02*
X102000D01*
Y476800D01*
G01X103649Y453741D02*
Y456241D01*
X104690D01*
X105024Y456116D01*
X105232Y455949D01*
X105315Y455616D01*
X105232Y455283D01*
X104982Y455074D01*
X104690Y454949D01*
X103649D01*
G01X104690D02*
X105315Y453741D01*
G01X106665Y454241D02*
X106915Y453949D01*
X107249Y453783D01*
X107624Y453741D01*
X107957Y453783D01*
X108290Y453991D01*
X108499Y454241D01*
X108540Y454491D01*
X108457Y454783D01*
X108165Y454991D01*
X107874Y455074D01*
X107499D01*
G01X107874D02*
X108124Y455199D01*
X108332Y455408D01*
X108415Y455658D01*
X108332Y455908D01*
X108124Y456116D01*
X107749Y456241D01*
X107374Y456199D01*
X106999Y456033D01*
G01X109765Y454116D02*
X110015Y453908D01*
X110307Y453783D01*
X110682Y453741D01*
X111057Y453824D01*
X111349Y453991D01*
X111557Y454283D01*
X111599Y454616D01*
X111515Y454949D01*
X111307Y455158D01*
X111015Y455324D01*
X110724Y455366D01*
X110432Y455324D01*
X110057Y455158D01*
X110182Y456241D01*
X111307D01*
G01X112990Y455824D02*
X113240Y456074D01*
X113532Y456199D01*
X113865Y456241D01*
X114282Y456158D01*
X114574Y455949D01*
X114657Y455699D01*
X114615Y455449D01*
X114449Y455241D01*
X113615Y454824D01*
X113240Y454533D01*
X112990Y454116D01*
X112907Y453741D01*
X114657D01*
G01X75872Y434166D02*
X73372D01*
Y435207D01*
X73497Y435541D01*
X73664Y435749D01*
X73997Y435832D01*
X74330Y435749D01*
X74539Y435499D01*
X74664Y435207D01*
Y434166D01*
G01Y435207D02*
X75872Y435832D01*
G01Y438099D02*
X73372D01*
X73872Y437599D01*
G01X75872D02*
Y438599D01*
G01Y441699D02*
X73372D01*
X75164Y440157D01*
Y442241D01*
G01X75872Y444299D02*
X75830Y444591D01*
X75705Y444924D01*
X75497Y445132D01*
X75205Y445216D01*
X74914Y445132D01*
X74664Y444882D01*
X74539Y444507D01*
Y444091D01*
X74455Y443841D01*
X74247Y443632D01*
X73955Y443549D01*
X73664Y443674D01*
X73455Y443966D01*
X73372Y444299D01*
X73455Y444632D01*
X73664Y444924D01*
X73955Y445049D01*
X74247Y444966D01*
X74455Y444757D01*
X74539Y444507D01*
Y444091D01*
X74664Y443716D01*
X74914Y443466D01*
X75205Y443382D01*
X75497Y443466D01*
X75705Y443674D01*
X75830Y444007D01*
X75872Y444299D01*
G01X84372Y433066D02*
X81872D01*
Y434107D01*
X81997Y434441D01*
X82164Y434649D01*
X82497Y434732D01*
X82830Y434649D01*
X83039Y434399D01*
X83164Y434107D01*
Y433066D01*
G01Y434107D02*
X84372Y434732D01*
G01Y436999D02*
X81872D01*
X82372Y436499D01*
G01X84372D02*
Y437499D01*
G01Y440599D02*
X81872D01*
X83664Y439057D01*
Y441141D01*
G01X84372Y443116D02*
X83830Y443199D01*
X83372Y443324D01*
X82955Y443491D01*
X82497Y443699D01*
X81872Y444032D01*
Y442366D01*
G01X85488Y424739D02*
Y427239D01*
X86529D01*
X86863Y427114D01*
X87071Y426947D01*
X87154Y426614D01*
X87071Y426281D01*
X86821Y426072D01*
X86529Y425947D01*
X85488D01*
G01X86529D02*
X87154Y424739D01*
G01X89421D02*
Y427239D01*
X88921Y426739D01*
G01Y424739D02*
X89921D01*
G01X93021D02*
Y427239D01*
X91479Y425447D01*
X93563D01*
G01X94829Y425781D02*
X95121Y426072D01*
X95371Y426239D01*
X95704Y426322D01*
X95996Y426239D01*
X96204Y426072D01*
X96371Y425822D01*
X96413Y425531D01*
X96371Y425281D01*
X96204Y425031D01*
X95954Y424822D01*
X95663Y424739D01*
X95329Y424822D01*
X95038Y425072D01*
X94871Y425447D01*
X94829Y425864D01*
X94913Y426406D01*
X95038Y426697D01*
X95246Y426989D01*
X95538Y427197D01*
X95829Y427239D01*
X96121Y427156D01*
X96329Y426947D01*
G01X102570Y438448D02*
Y440948D01*
X103611D01*
X103945Y440823D01*
X104153Y440656D01*
X104236Y440323D01*
X104153Y439990D01*
X103903Y439781D01*
X103611Y439656D01*
X102570D01*
G01X103611D02*
X104236Y438448D01*
G01X105586Y438948D02*
X105836Y438656D01*
X106170Y438490D01*
X106545Y438448D01*
X106878Y438490D01*
X107211Y438698D01*
X107420Y438948D01*
X107461Y439198D01*
X107378Y439490D01*
X107086Y439698D01*
X106795Y439781D01*
X106420D01*
G01X106795D02*
X107045Y439906D01*
X107253Y440115D01*
X107336Y440365D01*
X107253Y440615D01*
X107045Y440823D01*
X106670Y440948D01*
X106295Y440906D01*
X105920Y440740D01*
G01X110103Y438448D02*
Y440948D01*
X108561Y439156D01*
X110645D01*
G01X111786Y438948D02*
X112036Y438656D01*
X112370Y438490D01*
X112745Y438448D01*
X113078Y438490D01*
X113411Y438698D01*
X113620Y438948D01*
X113661Y439198D01*
X113578Y439490D01*
X113286Y439698D01*
X112995Y439781D01*
X112620D01*
G01X112995D02*
X113245Y439906D01*
X113453Y440115D01*
X113536Y440365D01*
X113453Y440615D01*
X113245Y440823D01*
X112870Y440948D01*
X112495Y440906D01*
X112120Y440740D01*
G01X99292Y433891D02*
Y436391D01*
X100333D01*
X100667Y436266D01*
X100875Y436099D01*
X100958Y435766D01*
X100875Y435433D01*
X100625Y435224D01*
X100333Y435099D01*
X99292D01*
G01X100333D02*
X100958Y433891D01*
G01X102433Y435974D02*
X102683Y436224D01*
X102975Y436349D01*
X103308Y436391D01*
X103725Y436308D01*
X104017Y436099D01*
X104100Y435849D01*
X104058Y435599D01*
X103892Y435391D01*
X103058Y434974D01*
X102683Y434683D01*
X102433Y434266D01*
X102350Y433891D01*
X104100D01*
G01X105617Y434183D02*
X105908Y433974D01*
X106242Y433891D01*
X106575Y433974D01*
X106867Y434224D01*
X107075Y434599D01*
X107158Y434974D01*
Y435433D01*
X107075Y435808D01*
X106867Y436141D01*
X106617Y436308D01*
X106325Y436391D01*
X105992Y436308D01*
X105742Y436141D01*
X105575Y435891D01*
X105492Y435558D01*
X105575Y435266D01*
X105783Y434974D01*
X106033Y434808D01*
X106325Y434766D01*
X106658Y434849D01*
X106908Y435058D01*
X107158Y435433D01*
G01X109425Y436391D02*
X109092Y436308D01*
X108842Y436099D01*
X108675Y435849D01*
X108550Y435516D01*
X108508Y435141D01*
X108550Y434766D01*
X108675Y434433D01*
X108842Y434183D01*
X109092Y433974D01*
X109425Y433891D01*
X109758Y433974D01*
X110008Y434183D01*
X110175Y434433D01*
X110300Y434766D01*
X110342Y435141D01*
X110300Y435516D01*
X110175Y435849D01*
X110008Y436099D01*
X109758Y436308D01*
X109425Y436391D01*
G01X99292Y429891D02*
Y432391D01*
X100333D01*
X100667Y432266D01*
X100875Y432099D01*
X100958Y431766D01*
X100875Y431433D01*
X100625Y431224D01*
X100333Y431099D01*
X99292D01*
G01X100333D02*
X100958Y429891D01*
G01X102433Y431974D02*
X102683Y432224D01*
X102975Y432349D01*
X103308Y432391D01*
X103725Y432308D01*
X104017Y432099D01*
X104100Y431849D01*
X104058Y431599D01*
X103892Y431391D01*
X103058Y430974D01*
X102683Y430683D01*
X102433Y430266D01*
X102350Y429891D01*
X104100D01*
G01X106325D02*
X106617Y429933D01*
X106950Y430058D01*
X107158Y430266D01*
X107242Y430558D01*
X107158Y430849D01*
X106908Y431099D01*
X106533Y431224D01*
X106117D01*
X105867Y431308D01*
X105658Y431516D01*
X105575Y431808D01*
X105700Y432099D01*
X105992Y432308D01*
X106325Y432391D01*
X106658Y432308D01*
X106950Y432099D01*
X107075Y431808D01*
X106992Y431516D01*
X106783Y431308D01*
X106533Y431224D01*
X106117D01*
X105742Y431099D01*
X105492Y430849D01*
X105408Y430558D01*
X105492Y430266D01*
X105700Y430058D01*
X106033Y429933D01*
X106325Y429891D01*
G01X108717Y430183D02*
X109008Y429974D01*
X109342Y429891D01*
X109675Y429974D01*
X109967Y430224D01*
X110175Y430599D01*
X110258Y430974D01*
Y431433D01*
X110175Y431808D01*
X109967Y432141D01*
X109717Y432308D01*
X109425Y432391D01*
X109092Y432308D01*
X108842Y432141D01*
X108675Y431891D01*
X108592Y431558D01*
X108675Y431266D01*
X108883Y430974D01*
X109133Y430808D01*
X109425Y430766D01*
X109758Y430849D01*
X110008Y431058D01*
X110258Y431433D01*
G01X93072Y432566D02*
X90572D01*
Y433607D01*
X90697Y433941D01*
X90864Y434149D01*
X91197Y434232D01*
X91530Y434149D01*
X91739Y433899D01*
X91864Y433607D01*
Y432566D01*
G01Y433607D02*
X93072Y434232D01*
G01X90989Y435707D02*
X90739Y435957D01*
X90614Y436249D01*
X90572Y436582D01*
X90655Y436999D01*
X90864Y437291D01*
X91114Y437374D01*
X91364Y437332D01*
X91572Y437166D01*
X91989Y436332D01*
X92280Y435957D01*
X92697Y435707D01*
X93072Y435624D01*
Y437374D01*
G01Y439599D02*
X93030Y439891D01*
X92905Y440224D01*
X92697Y440432D01*
X92405Y440516D01*
X92114Y440432D01*
X91864Y440182D01*
X91739Y439807D01*
Y439391D01*
X91655Y439141D01*
X91447Y438932D01*
X91155Y438849D01*
X90864Y438974D01*
X90655Y439266D01*
X90572Y439599D01*
X90655Y439932D01*
X90864Y440224D01*
X91155Y440349D01*
X91447Y440266D01*
X91655Y440057D01*
X91739Y439807D01*
Y439391D01*
X91864Y439016D01*
X92114Y438766D01*
X92405Y438682D01*
X92697Y438766D01*
X92905Y438974D01*
X93030Y439307D01*
X93072Y439599D01*
G01Y442699D02*
X93030Y442991D01*
X92905Y443324D01*
X92697Y443532D01*
X92405Y443616D01*
X92114Y443532D01*
X91864Y443282D01*
X91739Y442907D01*
Y442491D01*
X91655Y442241D01*
X91447Y442032D01*
X91155Y441949D01*
X90864Y442074D01*
X90655Y442366D01*
X90572Y442699D01*
X90655Y443032D01*
X90864Y443324D01*
X91155Y443449D01*
X91447Y443366D01*
X91655Y443157D01*
X91739Y442907D01*
Y442491D01*
X91864Y442116D01*
X92114Y441866D01*
X92405Y441782D01*
X92697Y441866D01*
X92905Y442074D01*
X93030Y442407D01*
X93072Y442699D01*
G01X97072Y432566D02*
X94572D01*
Y433607D01*
X94697Y433941D01*
X94864Y434149D01*
X95197Y434232D01*
X95530Y434149D01*
X95739Y433899D01*
X95864Y433607D01*
Y432566D01*
G01Y433607D02*
X97072Y434232D01*
G01X94989Y435707D02*
X94739Y435957D01*
X94614Y436249D01*
X94572Y436582D01*
X94655Y436999D01*
X94864Y437291D01*
X95114Y437374D01*
X95364Y437332D01*
X95572Y437166D01*
X95989Y436332D01*
X96280Y435957D01*
X96697Y435707D01*
X97072Y435624D01*
Y437374D01*
G01Y439516D02*
X96530Y439599D01*
X96072Y439724D01*
X95655Y439891D01*
X95197Y440099D01*
X94572Y440432D01*
Y438766D01*
G01X97072Y442699D02*
X97030Y442991D01*
X96905Y443324D01*
X96697Y443532D01*
X96405Y443616D01*
X96114Y443532D01*
X95864Y443282D01*
X95739Y442907D01*
Y442491D01*
X95655Y442241D01*
X95447Y442032D01*
X95155Y441949D01*
X94864Y442074D01*
X94655Y442366D01*
X94572Y442699D01*
X94655Y443032D01*
X94864Y443324D01*
X95155Y443449D01*
X95447Y443366D01*
X95655Y443157D01*
X95739Y442907D01*
Y442491D01*
X95864Y442116D01*
X96114Y441866D01*
X96405Y441782D01*
X96697Y441866D01*
X96905Y442074D01*
X97030Y442407D01*
X97072Y442699D01*
G01X100500Y487017D02*
X98000D01*
Y488058D01*
X98125Y488392D01*
X98292Y488600D01*
X98625Y488683D01*
X98958Y488600D01*
X99167Y488350D01*
X99292Y488058D01*
Y487017D01*
G01Y488058D02*
X100500Y488683D01*
G01X100000Y490033D02*
X100292Y490283D01*
X100458Y490617D01*
X100500Y490992D01*
X100458Y491325D01*
X100250Y491658D01*
X100000Y491867D01*
X99750Y491908D01*
X99458Y491825D01*
X99250Y491533D01*
X99167Y491242D01*
Y490867D01*
G01Y491242D02*
X99042Y491492D01*
X98833Y491700D01*
X98583Y491783D01*
X98333Y491700D01*
X98125Y491492D01*
X98000Y491117D01*
X98042Y490742D01*
X98208Y490367D01*
G01X100500Y494550D02*
X98000D01*
X99792Y493008D01*
Y495092D01*
G01X99458Y496358D02*
X99167Y496650D01*
X99000Y496900D01*
X98917Y497233D01*
X99000Y497525D01*
X99167Y497733D01*
X99417Y497900D01*
X99708Y497942D01*
X99958Y497900D01*
X100208Y497733D01*
X100417Y497483D01*
X100500Y497192D01*
X100417Y496858D01*
X100167Y496567D01*
X99792Y496400D01*
X99375Y496358D01*
X98833Y496442D01*
X98542Y496567D01*
X98250Y496775D01*
X98042Y497067D01*
X98000Y497358D01*
X98083Y497650D01*
X98292Y497858D01*
G01X91531Y490941D02*
X95531D01*
Y498341D01*
G01X110500Y492700D02*
X106500D01*
Y485300D01*
G01X106000Y492700D02*
X102000D01*
Y485300D01*
G01X73372Y423649D02*
X75872D01*
G01X73372Y422691D02*
Y424607D01*
G01X75872Y425916D02*
X73372D01*
Y426916D01*
X73497Y427249D01*
X73789Y427499D01*
X74122Y427582D01*
X74455Y427499D01*
X74705Y427291D01*
X74830Y426916D01*
Y425916D01*
G01X75580Y429141D02*
X75789Y429432D01*
X75872Y429766D01*
X75789Y430099D01*
X75539Y430391D01*
X75164Y430599D01*
X74789Y430682D01*
X74330D01*
X73955Y430599D01*
X73622Y430391D01*
X73455Y430141D01*
X73372Y429849D01*
X73455Y429516D01*
X73622Y429266D01*
X73872Y429099D01*
X74205Y429016D01*
X74497Y429099D01*
X74789Y429307D01*
X74955Y429557D01*
X74997Y429849D01*
X74914Y430182D01*
X74705Y430432D01*
X74330Y430682D01*
G01X102200Y458750D02*
X104700D01*
G01X102200Y457792D02*
Y459708D01*
G01X104700Y461017D02*
X102200D01*
Y462017D01*
X102325Y462350D01*
X102617Y462600D01*
X102950Y462683D01*
X103283Y462600D01*
X103533Y462392D01*
X103658Y462017D01*
Y461017D01*
G01X104700Y464867D02*
X104158Y464950D01*
X103700Y465075D01*
X103283Y465242D01*
X102825Y465450D01*
X102200Y465783D01*
Y464117D01*
G01X104700Y467967D02*
X104158Y468050D01*
X103700Y468175D01*
X103283Y468342D01*
X102825Y468550D01*
X102200Y468883D01*
Y467217D01*
G01X107100Y458950D02*
X109600D01*
G01X107100Y457992D02*
Y459908D01*
G01X109600Y461217D02*
X107100D01*
Y462217D01*
X107225Y462550D01*
X107517Y462800D01*
X107850Y462883D01*
X108183Y462800D01*
X108433Y462592D01*
X108558Y462217D01*
Y461217D01*
G01X109600Y465067D02*
X109058Y465150D01*
X108600Y465275D01*
X108183Y465442D01*
X107725Y465650D01*
X107100Y465983D01*
Y464317D01*
G01X109600Y468750D02*
X107100D01*
X108892Y467208D01*
Y469292D01*
G01X97300Y458850D02*
X99800D01*
G01X97300Y457892D02*
Y459808D01*
G01X99800Y461117D02*
X97300D01*
Y462117D01*
X97425Y462450D01*
X97717Y462700D01*
X98050Y462783D01*
X98383Y462700D01*
X98633Y462492D01*
X98758Y462117D01*
Y461117D01*
G01X99800Y464967D02*
X99258Y465050D01*
X98800Y465175D01*
X98383Y465342D01*
X97925Y465550D01*
X97300Y465883D01*
Y464217D01*
G01X99800Y468150D02*
X97300D01*
X97800Y467650D01*
G01X99800D02*
Y468650D01*
G01X86127Y436187D02*
X88627D01*
G01X86127Y435229D02*
Y437145D01*
G01X88627Y438454D02*
X86127D01*
Y439454D01*
X86252Y439787D01*
X86544Y440037D01*
X86877Y440120D01*
X87210Y440037D01*
X87460Y439829D01*
X87585Y439454D01*
Y438454D01*
G01X88627Y442387D02*
X86127D01*
X86627Y441887D01*
G01X88627D02*
Y442887D01*
G01Y445487D02*
X86127D01*
X86627Y444987D01*
G01X88627D02*
Y445987D01*
G01X77772Y434999D02*
X80272D01*
G01X77772Y434041D02*
Y435957D01*
G01X80272Y437266D02*
X77772D01*
Y438266D01*
X77897Y438599D01*
X78189Y438849D01*
X78522Y438932D01*
X78855Y438849D01*
X79105Y438641D01*
X79230Y438266D01*
Y437266D01*
G01X80272Y441199D02*
X77772D01*
X78272Y440699D01*
G01X80272D02*
Y441699D01*
G01X77772Y444299D02*
X77855Y443966D01*
X78064Y443716D01*
X78314Y443549D01*
X78647Y443424D01*
X79022Y443382D01*
X79397Y443424D01*
X79730Y443549D01*
X79980Y443716D01*
X80189Y443966D01*
X80272Y444299D01*
X80189Y444632D01*
X79980Y444882D01*
X79730Y445049D01*
X79397Y445174D01*
X79022Y445216D01*
X78647Y445174D01*
X78314Y445049D01*
X78064Y444882D01*
X77855Y444632D01*
X77772Y444299D01*
G01X100364Y445926D02*
Y443426D01*
G01X99406Y445926D02*
X101322D01*
G01X102631Y443426D02*
Y445926D01*
X103631D01*
X103964Y445801D01*
X104214Y445509D01*
X104297Y445176D01*
X104214Y444843D01*
X104006Y444593D01*
X103631Y444468D01*
X102631D01*
G01X105772Y445509D02*
X106022Y445759D01*
X106314Y445884D01*
X106647Y445926D01*
X107064Y445843D01*
X107356Y445634D01*
X107439Y445384D01*
X107397Y445134D01*
X107231Y444926D01*
X106397Y444509D01*
X106022Y444218D01*
X105772Y443801D01*
X105689Y443426D01*
X107439D01*
G01X109664Y445926D02*
X109331Y445843D01*
X109081Y445634D01*
X108914Y445384D01*
X108789Y445051D01*
X108747Y444676D01*
X108789Y444301D01*
X108914Y443968D01*
X109081Y443718D01*
X109331Y443509D01*
X109664Y443426D01*
X109997Y443509D01*
X110247Y443718D01*
X110414Y443968D01*
X110539Y444301D01*
X110581Y444676D01*
X110539Y445051D01*
X110414Y445384D01*
X110247Y445634D01*
X109997Y445843D01*
X109664Y445926D01*
G01X112681Y443426D02*
X112764Y443968D01*
X112889Y444426D01*
X113056Y444843D01*
X113264Y445301D01*
X113597Y445926D01*
X111931D01*
G01X100003Y450016D02*
Y447516D01*
G01X99045Y450016D02*
X100961D01*
G01X102270Y447516D02*
Y450016D01*
X103270D01*
X103603Y449891D01*
X103853Y449599D01*
X103936Y449266D01*
X103853Y448933D01*
X103645Y448683D01*
X103270Y448558D01*
X102270D01*
G01X105411Y449599D02*
X105661Y449849D01*
X105953Y449974D01*
X106286Y450016D01*
X106703Y449933D01*
X106995Y449724D01*
X107078Y449474D01*
X107036Y449224D01*
X106870Y449016D01*
X106036Y448599D01*
X105661Y448308D01*
X105411Y447891D01*
X105328Y447516D01*
X107078D01*
G01X109303Y450016D02*
X108970Y449933D01*
X108720Y449724D01*
X108553Y449474D01*
X108428Y449141D01*
X108386Y448766D01*
X108428Y448391D01*
X108553Y448058D01*
X108720Y447808D01*
X108970Y447599D01*
X109303Y447516D01*
X109636Y447599D01*
X109886Y447808D01*
X110053Y448058D01*
X110178Y448391D01*
X110220Y448766D01*
X110178Y449141D01*
X110053Y449474D01*
X109886Y449724D01*
X109636Y449933D01*
X109303Y450016D01*
G01X112403Y447516D02*
X112695Y447558D01*
X113028Y447683D01*
X113236Y447891D01*
X113320Y448183D01*
X113236Y448474D01*
X112986Y448724D01*
X112611Y448849D01*
X112195D01*
X111945Y448933D01*
X111736Y449141D01*
X111653Y449433D01*
X111778Y449724D01*
X112070Y449933D01*
X112403Y450016D01*
X112736Y449933D01*
X113028Y449724D01*
X113153Y449433D01*
X113070Y449141D01*
X112861Y448933D01*
X112611Y448849D01*
X112195D01*
X111820Y448724D01*
X111570Y448474D01*
X111486Y448183D01*
X111570Y447891D01*
X111778Y447683D01*
X112111Y447558D01*
X112403Y447516D01*
G01X119661Y439918D02*
Y438126D01*
X119828Y437751D01*
X120161Y437501D01*
X120578Y437418D01*
X120995Y437501D01*
X121328Y437751D01*
X121495Y438126D01*
Y439918D01*
G01X123678Y437418D02*
Y439918D01*
X123178Y439418D01*
G01Y437418D02*
X124178D01*
G01X126778D02*
Y439918D01*
X126278Y439418D01*
G01Y437418D02*
X127278D01*
G01X130165Y455800D02*
Y496500D01*
G01X155565Y455800D02*
X130165D01*
G01X119071Y441740D02*
X119404Y441532D01*
X119779Y441407D01*
X120113D01*
X120446Y441532D01*
X120696Y441740D01*
X120821Y442032D01*
X120738Y442324D01*
X120529Y442574D01*
X120154Y442740D01*
X119654Y442824D01*
X119363Y442990D01*
X119238Y443282D01*
X119321Y443574D01*
X119529Y443782D01*
X119821Y443907D01*
X120113D01*
X120404Y443824D01*
X120654Y443615D01*
G01X122129Y441407D02*
Y443907D01*
G01X123713D02*
X122129Y442365D01*
G01X123963Y441407D02*
X122838Y443074D01*
G01X126146Y443907D02*
Y441407D01*
G01X125188Y443907D02*
X127104D01*
G01X129246Y441407D02*
Y443907D01*
X128746Y443407D01*
G01Y441407D02*
X129746D01*
G01X117665Y508900D02*
Y446700D01*
X168065D01*
Y508900D01*
X117665D01*
G01X147165Y446750D02*
X142565Y451350D01*
X137915Y446700D01*
G01X139500Y516000D02*
Y511000D01*
G01Y525820D02*
Y526500D01*
X144500D01*
Y531500D01*
X156500D01*
Y523500D01*
X178908D01*
G01X112208Y510317D02*
X112083Y510067D01*
X112000Y509775D01*
Y509442D01*
X112125Y509067D01*
X112333Y508775D01*
X112583Y508567D01*
X113000Y508400D01*
X113375Y508358D01*
X113750Y508442D01*
X114000Y508567D01*
X114250Y508817D01*
X114417Y509108D01*
X114500Y509400D01*
Y509692D01*
X114417Y509983D01*
X114292Y510233D01*
X114125Y510442D01*
G01X114500Y512417D02*
X113958Y512500D01*
X113500Y512625D01*
X113083Y512792D01*
X112625Y513000D01*
X112000Y513333D01*
Y511667D01*
G01X114208Y514892D02*
X114417Y515183D01*
X114500Y515517D01*
X114417Y515850D01*
X114167Y516142D01*
X113792Y516350D01*
X113417Y516433D01*
X112958D01*
X112583Y516350D01*
X112250Y516142D01*
X112083Y515892D01*
X112000Y515600D01*
X112083Y515267D01*
X112250Y515017D01*
X112500Y514850D01*
X112833Y514767D01*
X113125Y514850D01*
X113417Y515058D01*
X113583Y515308D01*
X113625Y515600D01*
X113542Y515933D01*
X113333Y516183D01*
X112958Y516433D01*
G01X109584Y531944D02*
Y534444D01*
X110625D01*
X110959Y534319D01*
X111167Y534152D01*
X111250Y533819D01*
X111167Y533486D01*
X110917Y533277D01*
X110625Y533152D01*
X109584D01*
G01X110625D02*
X111250Y531944D01*
G01X112725Y534027D02*
X112975Y534277D01*
X113267Y534402D01*
X113600Y534444D01*
X114017Y534361D01*
X114309Y534152D01*
X114392Y533902D01*
X114350Y533652D01*
X114184Y533444D01*
X113350Y533027D01*
X112975Y532736D01*
X112725Y532319D01*
X112642Y531944D01*
X114392D01*
G01X116617D02*
X116909Y531986D01*
X117242Y532111D01*
X117450Y532319D01*
X117534Y532611D01*
X117450Y532902D01*
X117200Y533152D01*
X116825Y533277D01*
X116409D01*
X116159Y533361D01*
X115950Y533569D01*
X115867Y533861D01*
X115992Y534152D01*
X116284Y534361D01*
X116617Y534444D01*
X116950Y534361D01*
X117242Y534152D01*
X117367Y533861D01*
X117284Y533569D01*
X117075Y533361D01*
X116825Y533277D01*
X116409D01*
X116034Y533152D01*
X115784Y532902D01*
X115700Y532611D01*
X115784Y532319D01*
X115992Y532111D01*
X116325Y531986D01*
X116617Y531944D01*
G01X118800Y532444D02*
X119050Y532152D01*
X119384Y531986D01*
X119759Y531944D01*
X120092Y531986D01*
X120425Y532194D01*
X120634Y532444D01*
X120675Y532694D01*
X120592Y532986D01*
X120300Y533194D01*
X120009Y533277D01*
X119634D01*
G01X120009D02*
X120259Y533402D01*
X120467Y533611D01*
X120550Y533861D01*
X120467Y534111D01*
X120259Y534319D01*
X119884Y534444D01*
X119509Y534402D01*
X119134Y534236D01*
G01X125000Y536600D02*
Y532600D01*
X132400D01*
G01X134485Y532447D02*
Y534947D01*
X135526D01*
X135860Y534822D01*
X136068Y534655D01*
X136151Y534322D01*
X136068Y533989D01*
X135818Y533780D01*
X135526Y533655D01*
X134485D01*
G01X135526D02*
X136151Y532447D01*
G01X137626Y534530D02*
X137876Y534780D01*
X138168Y534905D01*
X138501Y534947D01*
X138918Y534864D01*
X139210Y534655D01*
X139293Y534405D01*
X139251Y534155D01*
X139085Y533947D01*
X138251Y533530D01*
X137876Y533239D01*
X137626Y532822D01*
X137543Y532447D01*
X139293D01*
G01X141518D02*
X141810Y532489D01*
X142143Y532614D01*
X142351Y532822D01*
X142435Y533114D01*
X142351Y533405D01*
X142101Y533655D01*
X141726Y533780D01*
X141310D01*
X141060Y533864D01*
X140851Y534072D01*
X140768Y534364D01*
X140893Y534655D01*
X141185Y534864D01*
X141518Y534947D01*
X141851Y534864D01*
X142143Y534655D01*
X142268Y534364D01*
X142185Y534072D01*
X141976Y533864D01*
X141726Y533780D01*
X141310D01*
X140935Y533655D01*
X140685Y533405D01*
X140601Y533114D01*
X140685Y532822D01*
X140893Y532614D01*
X141226Y532489D01*
X141518Y532447D01*
G01X144618Y534947D02*
X144285Y534864D01*
X144035Y534655D01*
X143868Y534405D01*
X143743Y534072D01*
X143701Y533697D01*
X143743Y533322D01*
X143868Y532989D01*
X144035Y532739D01*
X144285Y532530D01*
X144618Y532447D01*
X144951Y532530D01*
X145201Y532739D01*
X145368Y532989D01*
X145493Y533322D01*
X145535Y533697D01*
X145493Y534072D01*
X145368Y534405D01*
X145201Y534655D01*
X144951Y534864D01*
X144618Y534947D01*
G01X134900Y531700D02*
Y527700D01*
X142300D01*
G01X109584Y527944D02*
Y530444D01*
X110625D01*
X110959Y530319D01*
X111167Y530152D01*
X111250Y529819D01*
X111167Y529486D01*
X110917Y529277D01*
X110625Y529152D01*
X109584D01*
G01X110625D02*
X111250Y527944D01*
G01X112600Y528444D02*
X112850Y528152D01*
X113184Y527986D01*
X113559Y527944D01*
X113892Y527986D01*
X114225Y528194D01*
X114434Y528444D01*
X114475Y528694D01*
X114392Y528986D01*
X114100Y529194D01*
X113809Y529277D01*
X113434D01*
G01X113809D02*
X114059Y529402D01*
X114267Y529611D01*
X114350Y529861D01*
X114267Y530111D01*
X114059Y530319D01*
X113684Y530444D01*
X113309Y530402D01*
X112934Y530236D01*
G01X115825Y528986D02*
X116117Y529277D01*
X116367Y529444D01*
X116700Y529527D01*
X116992Y529444D01*
X117200Y529277D01*
X117367Y529027D01*
X117409Y528736D01*
X117367Y528486D01*
X117200Y528236D01*
X116950Y528027D01*
X116659Y527944D01*
X116325Y528027D01*
X116034Y528277D01*
X115867Y528652D01*
X115825Y529069D01*
X115909Y529611D01*
X116034Y529902D01*
X116242Y530194D01*
X116534Y530402D01*
X116825Y530444D01*
X117117Y530361D01*
X117325Y530152D01*
G01X119009Y528236D02*
X119300Y528027D01*
X119634Y527944D01*
X119967Y528027D01*
X120259Y528277D01*
X120467Y528652D01*
X120550Y529027D01*
Y529486D01*
X120467Y529861D01*
X120259Y530194D01*
X120009Y530361D01*
X119717Y530444D01*
X119384Y530361D01*
X119134Y530194D01*
X118967Y529944D01*
X118884Y529611D01*
X118967Y529319D01*
X119175Y529027D01*
X119425Y528861D01*
X119717Y528819D01*
X120050Y528902D01*
X120300Y529111D01*
X120550Y529486D01*
G01X125000Y532300D02*
Y528300D01*
X132400D01*
G01X140000Y510100D02*
X144000D01*
Y517500D01*
G01X135067Y539795D02*
Y535795D01*
X142467D01*
G01X143914Y525238D02*
X139914D01*
Y517838D01*
G01X99113Y517377D02*
X103113D01*
Y524777D01*
G01X99100Y509900D02*
X103100D01*
Y517300D01*
G01X79032Y512077D02*
X83032D01*
Y519477D01*
G01X79068Y504466D02*
X83068D01*
Y511866D01*
G01X73405Y512077D02*
X77405D01*
Y519477D01*
G01X73373Y504479D02*
X77373D01*
Y511879D01*
G01X84673Y504600D02*
X88673D01*
Y512000D01*
G01X90000D02*
X94000D01*
Y519400D01*
G01X84659Y512077D02*
X88659D01*
Y519477D01*
G01X109200Y494617D02*
X106700D01*
Y495658D01*
X106825Y495992D01*
X106992Y496200D01*
X107325Y496283D01*
X107658Y496200D01*
X107867Y495950D01*
X107992Y495658D01*
Y494617D01*
G01Y495658D02*
X109200Y496283D01*
G01Y498467D02*
X108658Y498550D01*
X108200Y498675D01*
X107783Y498842D01*
X107325Y499050D01*
X106700Y499383D01*
Y497717D01*
G01X109200Y501650D02*
X109158Y501942D01*
X109033Y502275D01*
X108825Y502483D01*
X108533Y502567D01*
X108242Y502483D01*
X107992Y502233D01*
X107867Y501858D01*
Y501442D01*
X107783Y501192D01*
X107575Y500983D01*
X107283Y500900D01*
X106992Y501025D01*
X106783Y501317D01*
X106700Y501650D01*
X106783Y501983D01*
X106992Y502275D01*
X107283Y502400D01*
X107575Y502317D01*
X107783Y502108D01*
X107867Y501858D01*
Y501442D01*
X107992Y501067D01*
X108242Y500817D01*
X108533Y500733D01*
X108825Y500817D01*
X109033Y501025D01*
X109158Y501358D01*
X109200Y501650D01*
G01Y504667D02*
X108658Y504750D01*
X108200Y504875D01*
X107783Y505042D01*
X107325Y505250D01*
X106700Y505583D01*
Y503917D01*
G01X105500Y494617D02*
X103000D01*
Y495658D01*
X103125Y495992D01*
X103292Y496200D01*
X103625Y496283D01*
X103958Y496200D01*
X104167Y495950D01*
X104292Y495658D01*
Y494617D01*
G01Y495658D02*
X105500Y496283D01*
G01Y498467D02*
X104958Y498550D01*
X104500Y498675D01*
X104083Y498842D01*
X103625Y499050D01*
X103000Y499383D01*
Y497717D01*
G01X105500Y501650D02*
X105458Y501942D01*
X105333Y502275D01*
X105125Y502483D01*
X104833Y502567D01*
X104542Y502483D01*
X104292Y502233D01*
X104167Y501858D01*
Y501442D01*
X104083Y501192D01*
X103875Y500983D01*
X103583Y500900D01*
X103292Y501025D01*
X103083Y501317D01*
X103000Y501650D01*
X103083Y501983D01*
X103292Y502275D01*
X103583Y502400D01*
X103875Y502317D01*
X104083Y502108D01*
X104167Y501858D01*
Y501442D01*
X104292Y501067D01*
X104542Y500817D01*
X104833Y500733D01*
X105125Y500817D01*
X105333Y501025D01*
X105458Y501358D01*
X105500Y501650D01*
G01Y504750D02*
X103000D01*
X103500Y504250D01*
G01X105500D02*
Y505250D01*
G01X121850Y525000D02*
X121517Y525042D01*
X121225Y525208D01*
X120975Y525458D01*
X120808Y525750D01*
X120725Y526083D01*
Y526417D01*
X120808Y526750D01*
X120975Y527042D01*
X121225Y527292D01*
X121517Y527458D01*
X121850Y527500D01*
X122183Y527458D01*
X122475Y527292D01*
X122725Y527042D01*
X122892Y526750D01*
X122975Y526417D01*
Y526083D01*
X122892Y525750D01*
X122725Y525458D01*
X122475Y525208D01*
X122183Y525042D01*
X121850Y525000D01*
G01X124075Y525333D02*
X124408Y525125D01*
X124783Y525000D01*
X125117D01*
X125450Y525125D01*
X125700Y525333D01*
X125825Y525625D01*
X125742Y525917D01*
X125533Y526167D01*
X125158Y526333D01*
X124658Y526417D01*
X124367Y526583D01*
X124242Y526875D01*
X124325Y527167D01*
X124533Y527375D01*
X124825Y527500D01*
X125117D01*
X125408Y527417D01*
X125658Y527208D01*
G01X128967Y527292D02*
X128717Y527417D01*
X128425Y527500D01*
X128092D01*
X127717Y527375D01*
X127425Y527167D01*
X127217Y526917D01*
X127050Y526500D01*
X127008Y526125D01*
X127092Y525750D01*
X127217Y525500D01*
X127467Y525250D01*
X127758Y525083D01*
X128050Y525000D01*
X128342D01*
X128633Y525083D01*
X128883Y525208D01*
X129092Y525375D01*
G01X131150Y525000D02*
Y527500D01*
X130650Y527000D01*
G01Y525000D02*
X131650D01*
G01X122050Y523850D02*
X138750D01*
Y511750D01*
X122050D01*
Y523850D01*
G01X130165Y496500D02*
X155565D01*
G01X79017Y500500D02*
Y498000D01*
X80683D01*
G01X83783D02*
X82117D01*
Y500500D01*
X83783D01*
G01X83117Y499292D02*
X82117D01*
G01X85133Y498000D02*
Y500500D01*
X85967D01*
X86300Y500375D01*
X86550Y500208D01*
X86758Y499958D01*
X86925Y499667D01*
X86967Y499250D01*
X86925Y498833D01*
X86758Y498542D01*
X86550Y498292D01*
X86300Y498125D01*
X85967Y498000D01*
X85133D01*
G01X88358Y499042D02*
X88650Y499333D01*
X88900Y499500D01*
X89233Y499583D01*
X89525Y499500D01*
X89733Y499333D01*
X89900Y499083D01*
X89942Y498792D01*
X89900Y498542D01*
X89733Y498292D01*
X89483Y498083D01*
X89192Y498000D01*
X88858Y498083D01*
X88567Y498333D01*
X88400Y498708D01*
X88358Y499125D01*
X88442Y499667D01*
X88567Y499958D01*
X88775Y500250D01*
X89067Y500458D01*
X89358Y500500D01*
X89650Y500417D01*
X89858Y500208D01*
G01X96214Y509752D02*
Y498952D01*
X91014D01*
Y509752D01*
X96214D01*
G01X141800Y625700D02*
X140300Y624200D01*
Y627200D01*
X141800Y625700D01*
G01X76314Y623286D02*
X90100D01*
G01X116299Y617529D02*
X129000D01*
Y621500D01*
X137900D01*
Y625700D01*
X141800D01*
G01X114875Y630267D02*
X114750Y630017D01*
X114667Y629725D01*
Y629392D01*
X114792Y629017D01*
X115000Y628725D01*
X115250Y628517D01*
X115667Y628350D01*
X116042Y628308D01*
X116417Y628392D01*
X116667Y628517D01*
X116917Y628767D01*
X117084Y629058D01*
X117167Y629350D01*
Y629642D01*
X117084Y629933D01*
X116959Y630183D01*
X116792Y630392D01*
G01X116875Y631742D02*
X117084Y632033D01*
X117167Y632367D01*
X117084Y632700D01*
X116834Y632992D01*
X116459Y633200D01*
X116084Y633283D01*
X115625D01*
X115250Y633200D01*
X114917Y632992D01*
X114750Y632742D01*
X114667Y632450D01*
X114750Y632117D01*
X114917Y631867D01*
X115167Y631700D01*
X115500Y631617D01*
X115792Y631700D01*
X116084Y631908D01*
X116250Y632158D01*
X116292Y632450D01*
X116209Y632783D01*
X116000Y633033D01*
X115625Y633283D01*
G01X117167Y635550D02*
X114667D01*
X115167Y635050D01*
G01X117167D02*
Y636050D01*
G01X72208Y632767D02*
X72083Y632517D01*
X72000Y632225D01*
Y631892D01*
X72125Y631517D01*
X72333Y631225D01*
X72583Y631017D01*
X73000Y630850D01*
X73375Y630808D01*
X73750Y630892D01*
X74000Y631017D01*
X74250Y631267D01*
X74417Y631558D01*
X74500Y631850D01*
Y632142D01*
X74417Y632433D01*
X74292Y632683D01*
X74125Y632892D01*
G01X72417Y634158D02*
X72167Y634408D01*
X72042Y634700D01*
X72000Y635033D01*
X72083Y635450D01*
X72292Y635742D01*
X72542Y635825D01*
X72792Y635783D01*
X73000Y635617D01*
X73417Y634783D01*
X73708Y634408D01*
X74125Y634158D01*
X74500Y634075D01*
Y635825D01*
G01X72417Y637258D02*
X72167Y637508D01*
X72042Y637800D01*
X72000Y638133D01*
X72083Y638550D01*
X72292Y638842D01*
X72542Y638925D01*
X72792Y638883D01*
X73000Y638717D01*
X73417Y637883D01*
X73708Y637508D01*
X74125Y637258D01*
X74500Y637175D01*
Y638925D01*
G01Y641067D02*
X73958Y641150D01*
X73500Y641275D01*
X73083Y641442D01*
X72625Y641650D01*
X72000Y641983D01*
Y640317D01*
G01X107475Y630267D02*
X107350Y630017D01*
X107267Y629725D01*
Y629392D01*
X107392Y629017D01*
X107600Y628725D01*
X107850Y628517D01*
X108267Y628350D01*
X108642Y628308D01*
X109017Y628392D01*
X109267Y628517D01*
X109517Y628767D01*
X109684Y629058D01*
X109767Y629350D01*
Y629642D01*
X109684Y629933D01*
X109559Y630183D01*
X109392Y630392D01*
G01X109767Y632450D02*
X109725Y632742D01*
X109600Y633075D01*
X109392Y633283D01*
X109100Y633367D01*
X108809Y633283D01*
X108559Y633033D01*
X108434Y632658D01*
Y632242D01*
X108350Y631992D01*
X108142Y631783D01*
X107850Y631700D01*
X107559Y631825D01*
X107350Y632117D01*
X107267Y632450D01*
X107350Y632783D01*
X107559Y633075D01*
X107850Y633200D01*
X108142Y633117D01*
X108350Y632908D01*
X108434Y632658D01*
Y632242D01*
X108559Y631867D01*
X108809Y631617D01*
X109100Y631533D01*
X109392Y631617D01*
X109600Y631825D01*
X109725Y632158D01*
X109767Y632450D01*
G01X109475Y634842D02*
X109684Y635133D01*
X109767Y635467D01*
X109684Y635800D01*
X109434Y636092D01*
X109059Y636300D01*
X108684Y636383D01*
X108225D01*
X107850Y636300D01*
X107517Y636092D01*
X107350Y635842D01*
X107267Y635550D01*
X107350Y635217D01*
X107517Y634967D01*
X107767Y634800D01*
X108100Y634717D01*
X108392Y634800D01*
X108684Y635008D01*
X108850Y635258D01*
X108892Y635550D01*
X108809Y635883D01*
X108600Y636133D01*
X108225Y636383D01*
G01X89914Y634568D02*
X89664Y634693D01*
X89372Y634776D01*
X89039D01*
X88664Y634651D01*
X88372Y634443D01*
X88164Y634193D01*
X87997Y633776D01*
X87955Y633401D01*
X88039Y633026D01*
X88164Y632776D01*
X88414Y632526D01*
X88705Y632359D01*
X88997Y632276D01*
X89289D01*
X89580Y632359D01*
X89830Y632484D01*
X90039Y632651D01*
G01X91305Y634359D02*
X91555Y634609D01*
X91847Y634734D01*
X92180Y634776D01*
X92597Y634693D01*
X92889Y634484D01*
X92972Y634234D01*
X92930Y633984D01*
X92764Y633776D01*
X91930Y633359D01*
X91555Y633068D01*
X91305Y632651D01*
X91222Y632276D01*
X92972D01*
G01X94405Y634359D02*
X94655Y634609D01*
X94947Y634734D01*
X95280Y634776D01*
X95697Y634693D01*
X95989Y634484D01*
X96072Y634234D01*
X96030Y633984D01*
X95864Y633776D01*
X95030Y633359D01*
X94655Y633068D01*
X94405Y632651D01*
X94322Y632276D01*
X96072D01*
G01X97505Y633318D02*
X97797Y633609D01*
X98047Y633776D01*
X98380Y633859D01*
X98672Y633776D01*
X98880Y633609D01*
X99047Y633359D01*
X99089Y633068D01*
X99047Y632818D01*
X98880Y632568D01*
X98630Y632359D01*
X98339Y632276D01*
X98005Y632359D01*
X97714Y632609D01*
X97547Y632984D01*
X97505Y633401D01*
X97589Y633943D01*
X97714Y634234D01*
X97922Y634526D01*
X98214Y634734D01*
X98505Y634776D01*
X98797Y634693D01*
X99005Y634484D01*
G01X89914Y630460D02*
X89664Y630585D01*
X89372Y630668D01*
X89039D01*
X88664Y630543D01*
X88372Y630335D01*
X88164Y630085D01*
X87997Y629668D01*
X87955Y629293D01*
X88039Y628918D01*
X88164Y628668D01*
X88414Y628418D01*
X88705Y628251D01*
X88997Y628168D01*
X89289D01*
X89580Y628251D01*
X89830Y628376D01*
X90039Y628543D01*
G01X91305Y630251D02*
X91555Y630501D01*
X91847Y630626D01*
X92180Y630668D01*
X92597Y630585D01*
X92889Y630376D01*
X92972Y630126D01*
X92930Y629876D01*
X92764Y629668D01*
X91930Y629251D01*
X91555Y628960D01*
X91305Y628543D01*
X91222Y628168D01*
X92972D01*
G01X94405Y630251D02*
X94655Y630501D01*
X94947Y630626D01*
X95280Y630668D01*
X95697Y630585D01*
X95989Y630376D01*
X96072Y630126D01*
X96030Y629876D01*
X95864Y629668D01*
X95030Y629251D01*
X94655Y628960D01*
X94405Y628543D01*
X94322Y628168D01*
X96072D01*
G01X97380Y628543D02*
X97630Y628335D01*
X97922Y628210D01*
X98297Y628168D01*
X98672Y628251D01*
X98964Y628418D01*
X99172Y628710D01*
X99214Y629043D01*
X99130Y629376D01*
X98922Y629585D01*
X98630Y629751D01*
X98339Y629793D01*
X98047Y629751D01*
X97672Y629585D01*
X97797Y630668D01*
X98922D01*
G01X74039Y616617D02*
X71539D01*
Y617658D01*
X71664Y617992D01*
X71831Y618200D01*
X72164Y618283D01*
X72497Y618200D01*
X72706Y617950D01*
X72831Y617658D01*
Y616617D01*
G01Y617658D02*
X74039Y618283D01*
G01Y621050D02*
X71539D01*
X73331Y619508D01*
Y621592D01*
G01X71539Y623650D02*
X71622Y623317D01*
X71831Y623067D01*
X72081Y622900D01*
X72414Y622775D01*
X72789Y622733D01*
X73164Y622775D01*
X73497Y622900D01*
X73747Y623067D01*
X73956Y623317D01*
X74039Y623650D01*
X73956Y623983D01*
X73747Y624233D01*
X73497Y624400D01*
X73164Y624525D01*
X72789Y624567D01*
X72414Y624525D01*
X72081Y624400D01*
X71831Y624233D01*
X71622Y623983D01*
X71539Y623650D01*
G01X74039Y626667D02*
X73497Y626750D01*
X73039Y626875D01*
X72622Y627042D01*
X72164Y627250D01*
X71539Y627583D01*
Y625917D01*
G01X104991Y572598D02*
X102491D01*
Y573639D01*
X102616Y573973D01*
X102783Y574181D01*
X103116Y574264D01*
X103449Y574181D01*
X103658Y573931D01*
X103783Y573639D01*
Y572598D01*
G01Y573639D02*
X104991Y574264D01*
G01X102908Y575739D02*
X102658Y575989D01*
X102533Y576281D01*
X102491Y576614D01*
X102574Y577031D01*
X102783Y577323D01*
X103033Y577406D01*
X103283Y577364D01*
X103491Y577198D01*
X103908Y576364D01*
X104199Y575989D01*
X104616Y575739D01*
X104991Y575656D01*
Y577406D01*
G01Y579631D02*
X102491D01*
X102991Y579131D01*
G01X104991D02*
Y580131D01*
G01X104699Y582023D02*
X104908Y582314D01*
X104991Y582648D01*
X104908Y582981D01*
X104658Y583273D01*
X104283Y583481D01*
X103908Y583564D01*
X103449D01*
X103074Y583481D01*
X102741Y583273D01*
X102574Y583023D01*
X102491Y582731D01*
X102574Y582398D01*
X102741Y582148D01*
X102991Y581981D01*
X103324Y581898D01*
X103616Y581981D01*
X103908Y582189D01*
X104074Y582439D01*
X104116Y582731D01*
X104033Y583064D01*
X103824Y583314D01*
X103449Y583564D01*
G01X110277Y576051D02*
X106277D01*
Y568651D01*
G01X82132Y604500D02*
X79632D01*
Y605541D01*
X79757Y605875D01*
X79924Y606083D01*
X80257Y606166D01*
X80590Y606083D01*
X80799Y605833D01*
X80924Y605541D01*
Y604500D01*
G01Y605541D02*
X82132Y606166D01*
G01X81632Y607516D02*
X81924Y607766D01*
X82090Y608100D01*
X82132Y608475D01*
X82090Y608808D01*
X81882Y609141D01*
X81632Y609350D01*
X81382Y609391D01*
X81090Y609308D01*
X80882Y609016D01*
X80799Y608725D01*
Y608350D01*
G01Y608725D02*
X80674Y608975D01*
X80465Y609183D01*
X80215Y609266D01*
X79965Y609183D01*
X79757Y608975D01*
X79632Y608600D01*
X79674Y608225D01*
X79840Y607850D01*
G01X81840Y610825D02*
X82049Y611116D01*
X82132Y611450D01*
X82049Y611783D01*
X81799Y612075D01*
X81424Y612283D01*
X81049Y612366D01*
X80590D01*
X80215Y612283D01*
X79882Y612075D01*
X79715Y611825D01*
X79632Y611533D01*
X79715Y611200D01*
X79882Y610950D01*
X80132Y610783D01*
X80465Y610700D01*
X80757Y610783D01*
X81049Y610991D01*
X81215Y611241D01*
X81257Y611533D01*
X81174Y611866D01*
X80965Y612116D01*
X80590Y612366D01*
G01X82132Y614550D02*
X81590Y614633D01*
X81132Y614758D01*
X80715Y614925D01*
X80257Y615133D01*
X79632Y615466D01*
Y613800D01*
G01X78032Y604600D02*
X75532D01*
Y605641D01*
X75657Y605975D01*
X75824Y606183D01*
X76157Y606266D01*
X76490Y606183D01*
X76699Y605933D01*
X76824Y605641D01*
Y604600D01*
G01Y605641D02*
X78032Y606266D01*
G01X77532Y607616D02*
X77824Y607866D01*
X77990Y608200D01*
X78032Y608575D01*
X77990Y608908D01*
X77782Y609241D01*
X77532Y609450D01*
X77282Y609491D01*
X76990Y609408D01*
X76782Y609116D01*
X76699Y608825D01*
Y608450D01*
G01Y608825D02*
X76574Y609075D01*
X76365Y609283D01*
X76115Y609366D01*
X75865Y609283D01*
X75657Y609075D01*
X75532Y608700D01*
X75574Y608325D01*
X75740Y607950D01*
G01X77740Y610925D02*
X77949Y611216D01*
X78032Y611550D01*
X77949Y611883D01*
X77699Y612175D01*
X77324Y612383D01*
X76949Y612466D01*
X76490D01*
X76115Y612383D01*
X75782Y612175D01*
X75615Y611925D01*
X75532Y611633D01*
X75615Y611300D01*
X75782Y611050D01*
X76032Y610883D01*
X76365Y610800D01*
X76657Y610883D01*
X76949Y611091D01*
X77115Y611341D01*
X77157Y611633D01*
X77074Y611966D01*
X76865Y612216D01*
X76490Y612466D01*
G01X76990Y613941D02*
X76699Y614233D01*
X76532Y614483D01*
X76449Y614816D01*
X76532Y615108D01*
X76699Y615316D01*
X76949Y615483D01*
X77240Y615525D01*
X77490Y615483D01*
X77740Y615316D01*
X77949Y615066D01*
X78032Y614775D01*
X77949Y614441D01*
X77699Y614150D01*
X77324Y613983D01*
X76907Y613941D01*
X76365Y614025D01*
X76074Y614150D01*
X75782Y614358D01*
X75574Y614650D01*
X75532Y614941D01*
X75615Y615233D01*
X75824Y615441D01*
G01X75949Y616983D02*
Y619483D01*
X76990D01*
X77324Y619358D01*
X77532Y619191D01*
X77615Y618858D01*
X77532Y618525D01*
X77282Y618316D01*
X76990Y618191D01*
X75949D01*
G01X76990D02*
X77615Y616983D01*
G01X78965Y617483D02*
X79215Y617191D01*
X79549Y617025D01*
X79924Y616983D01*
X80257Y617025D01*
X80590Y617233D01*
X80799Y617483D01*
X80840Y617733D01*
X80757Y618025D01*
X80465Y618233D01*
X80174Y618316D01*
X79799D01*
G01X80174D02*
X80424Y618441D01*
X80632Y618650D01*
X80715Y618900D01*
X80632Y619150D01*
X80424Y619358D01*
X80049Y619483D01*
X79674Y619441D01*
X79299Y619275D01*
G01X82274Y617275D02*
X82565Y617066D01*
X82899Y616983D01*
X83232Y617066D01*
X83524Y617316D01*
X83732Y617691D01*
X83815Y618066D01*
Y618525D01*
X83732Y618900D01*
X83524Y619233D01*
X83274Y619400D01*
X82982Y619483D01*
X82649Y619400D01*
X82399Y619233D01*
X82232Y618983D01*
X82149Y618650D01*
X82232Y618358D01*
X82440Y618066D01*
X82690Y617900D01*
X82982Y617858D01*
X83315Y617941D01*
X83565Y618150D01*
X83815Y618525D01*
G01X85290Y619066D02*
X85540Y619316D01*
X85832Y619441D01*
X86165Y619483D01*
X86582Y619400D01*
X86874Y619191D01*
X86957Y618941D01*
X86915Y618691D01*
X86749Y618483D01*
X85915Y618066D01*
X85540Y617775D01*
X85290Y617358D01*
X85207Y616983D01*
X86957D01*
G01X115417Y608300D02*
Y610800D01*
X116458D01*
X116792Y610675D01*
X117000Y610508D01*
X117083Y610175D01*
X117000Y609842D01*
X116750Y609633D01*
X116458Y609508D01*
X115417D01*
G01X116458D02*
X117083Y608300D01*
G01X118433Y608800D02*
X118683Y608508D01*
X119017Y608342D01*
X119392Y608300D01*
X119725Y608342D01*
X120058Y608550D01*
X120267Y608800D01*
X120308Y609050D01*
X120225Y609342D01*
X119933Y609550D01*
X119642Y609633D01*
X119267D01*
G01X119642D02*
X119892Y609758D01*
X120100Y609967D01*
X120183Y610217D01*
X120100Y610467D01*
X119892Y610675D01*
X119517Y610800D01*
X119142Y610758D01*
X118767Y610592D01*
G01X121533Y608800D02*
X121783Y608508D01*
X122117Y608342D01*
X122492Y608300D01*
X122825Y608342D01*
X123158Y608550D01*
X123367Y608800D01*
X123408Y609050D01*
X123325Y609342D01*
X123033Y609550D01*
X122742Y609633D01*
X122367D01*
G01X122742D02*
X122992Y609758D01*
X123200Y609967D01*
X123283Y610217D01*
X123200Y610467D01*
X122992Y610675D01*
X122617Y610800D01*
X122242Y610758D01*
X121867Y610592D01*
G01X125550Y608300D02*
Y610800D01*
X125050Y610300D01*
G01Y608300D02*
X126050D01*
G01X116403Y615818D02*
Y611818D01*
X123803D01*
G01X74000Y601517D02*
X71500D01*
Y602558D01*
X71625Y602892D01*
X71792Y603100D01*
X72125Y603183D01*
X72458Y603100D01*
X72667Y602850D01*
X72792Y602558D01*
Y601517D01*
G01Y602558D02*
X74000Y603183D01*
G01X73500Y604533D02*
X73792Y604783D01*
X73958Y605117D01*
X74000Y605492D01*
X73958Y605825D01*
X73750Y606158D01*
X73500Y606367D01*
X73250Y606408D01*
X72958Y606325D01*
X72750Y606033D01*
X72667Y605742D01*
Y605367D01*
G01Y605742D02*
X72542Y605992D01*
X72333Y606200D01*
X72083Y606283D01*
X71833Y606200D01*
X71625Y605992D01*
X71500Y605617D01*
X71542Y605242D01*
X71708Y604867D01*
G01X73708Y607842D02*
X73917Y608133D01*
X74000Y608467D01*
X73917Y608800D01*
X73667Y609092D01*
X73292Y609300D01*
X72917Y609383D01*
X72458D01*
X72083Y609300D01*
X71750Y609092D01*
X71583Y608842D01*
X71500Y608550D01*
X71583Y608217D01*
X71750Y607967D01*
X72000Y607800D01*
X72333Y607717D01*
X72625Y607800D01*
X72917Y608008D01*
X73083Y608258D01*
X73125Y608550D01*
X73042Y608883D01*
X72833Y609133D01*
X72458Y609383D01*
G01X74000Y611650D02*
X71500D01*
X72000Y611150D01*
G01X74000D02*
Y612150D01*
G01X138677Y611060D02*
Y615060D01*
X131277D01*
G01X135517Y606500D02*
Y609000D01*
X136558D01*
X136892Y608875D01*
X137100Y608708D01*
X137183Y608375D01*
X137100Y608042D01*
X136850Y607833D01*
X136558Y607708D01*
X135517D01*
G01X136558D02*
X137183Y606500D01*
G01X138533Y607000D02*
X138783Y606708D01*
X139117Y606542D01*
X139492Y606500D01*
X139825Y606542D01*
X140158Y606750D01*
X140367Y607000D01*
X140408Y607250D01*
X140325Y607542D01*
X140033Y607750D01*
X139742Y607833D01*
X139367D01*
G01X139742D02*
X139992Y607958D01*
X140200Y608167D01*
X140283Y608417D01*
X140200Y608667D01*
X139992Y608875D01*
X139617Y609000D01*
X139242Y608958D01*
X138867Y608792D01*
G01X142550Y606500D02*
Y609000D01*
X142050Y608500D01*
G01Y606500D02*
X143050D01*
G01X144942Y606792D02*
X145233Y606583D01*
X145567Y606500D01*
X145900Y606583D01*
X146192Y606833D01*
X146400Y607208D01*
X146483Y607583D01*
Y608042D01*
X146400Y608417D01*
X146192Y608750D01*
X145942Y608917D01*
X145650Y609000D01*
X145317Y608917D01*
X145067Y608750D01*
X144900Y608500D01*
X144817Y608167D01*
X144900Y607875D01*
X145108Y607583D01*
X145358Y607417D01*
X145650Y607375D01*
X145983Y607458D01*
X146233Y607667D01*
X146483Y608042D01*
G01X136662Y601311D02*
Y605311D01*
X129262D01*
G01X132017Y593500D02*
Y596000D01*
X133058D01*
X133392Y595875D01*
X133600Y595708D01*
X133683Y595375D01*
X133600Y595042D01*
X133350Y594833D01*
X133058Y594708D01*
X132017D01*
G01X133058D02*
X133683Y593500D01*
G01X135033Y594000D02*
X135283Y593708D01*
X135617Y593542D01*
X135992Y593500D01*
X136325Y593542D01*
X136658Y593750D01*
X136867Y594000D01*
X136908Y594250D01*
X136825Y594542D01*
X136533Y594750D01*
X136242Y594833D01*
X135867D01*
G01X136242D02*
X136492Y594958D01*
X136700Y595167D01*
X136783Y595417D01*
X136700Y595667D01*
X136492Y595875D01*
X136117Y596000D01*
X135742Y595958D01*
X135367Y595792D01*
G01X138133Y594000D02*
X138383Y593708D01*
X138717Y593542D01*
X139092Y593500D01*
X139425Y593542D01*
X139758Y593750D01*
X139967Y594000D01*
X140008Y594250D01*
X139925Y594542D01*
X139633Y594750D01*
X139342Y594833D01*
X138967D01*
G01X139342D02*
X139592Y594958D01*
X139800Y595167D01*
X139883Y595417D01*
X139800Y595667D01*
X139592Y595875D01*
X139217Y596000D01*
X138842Y595958D01*
X138467Y595792D01*
G01X141233Y594000D02*
X141483Y593708D01*
X141817Y593542D01*
X142192Y593500D01*
X142525Y593542D01*
X142858Y593750D01*
X143067Y594000D01*
X143108Y594250D01*
X143025Y594542D01*
X142733Y594750D01*
X142442Y594833D01*
X142067D01*
G01X142442D02*
X142692Y594958D01*
X142900Y595167D01*
X142983Y595417D01*
X142900Y595667D01*
X142692Y595875D01*
X142317Y596000D01*
X141942Y595958D01*
X141567Y595792D01*
G01X139649Y597062D02*
Y601062D01*
X132249D01*
G01X137695Y615354D02*
Y619354D01*
X130295D01*
G01X117600Y623400D02*
X121600D01*
Y630800D01*
G01X118599Y589519D02*
Y592019D01*
X119640D01*
X119974Y591894D01*
X120182Y591727D01*
X120265Y591394D01*
X120182Y591061D01*
X119932Y590852D01*
X119640Y590727D01*
X118599D01*
G01X119640D02*
X120265Y589519D01*
G01X122449D02*
X122532Y590061D01*
X122657Y590519D01*
X122824Y590936D01*
X123032Y591394D01*
X123365Y592019D01*
X121699D01*
G01X125632D02*
X125299Y591936D01*
X125049Y591727D01*
X124882Y591477D01*
X124757Y591144D01*
X124715Y590769D01*
X124757Y590394D01*
X124882Y590061D01*
X125049Y589811D01*
X125299Y589602D01*
X125632Y589519D01*
X125965Y589602D01*
X126215Y589811D01*
X126382Y590061D01*
X126507Y590394D01*
X126549Y590769D01*
X126507Y591144D01*
X126382Y591477D01*
X126215Y591727D01*
X125965Y591936D01*
X125632Y592019D01*
G01X128732Y589519D02*
Y592019D01*
X128232Y591519D01*
G01Y589519D02*
X129232D01*
G01X121300Y601000D02*
Y597000D01*
X128700D01*
G01X105517Y590000D02*
Y592500D01*
X106558D01*
X106892Y592375D01*
X107100Y592208D01*
X107183Y591875D01*
X107100Y591542D01*
X106850Y591333D01*
X106558Y591208D01*
X105517D01*
G01X106558D02*
X107183Y590000D01*
G01X109367D02*
X109450Y590542D01*
X109575Y591000D01*
X109742Y591417D01*
X109950Y591875D01*
X110283Y592500D01*
X108617D01*
G01X111758Y591042D02*
X112050Y591333D01*
X112300Y591500D01*
X112633Y591583D01*
X112925Y591500D01*
X113133Y591333D01*
X113300Y591083D01*
X113342Y590792D01*
X113300Y590542D01*
X113133Y590292D01*
X112883Y590083D01*
X112592Y590000D01*
X112258Y590083D01*
X111967Y590333D01*
X111800Y590708D01*
X111758Y591125D01*
X111842Y591667D01*
X111967Y591958D01*
X112175Y592250D01*
X112467Y592458D01*
X112758Y592500D01*
X113050Y592417D01*
X113258Y592208D01*
G01X115650Y590000D02*
X115942Y590042D01*
X116275Y590167D01*
X116483Y590375D01*
X116567Y590667D01*
X116483Y590958D01*
X116233Y591208D01*
X115858Y591333D01*
X115442D01*
X115192Y591417D01*
X114983Y591625D01*
X114900Y591917D01*
X115025Y592208D01*
X115317Y592417D01*
X115650Y592500D01*
X115983Y592417D01*
X116275Y592208D01*
X116400Y591917D01*
X116317Y591625D01*
X116108Y591417D01*
X115858Y591333D01*
X115442D01*
X115067Y591208D01*
X114817Y590958D01*
X114733Y590667D01*
X114817Y590375D01*
X115025Y590167D01*
X115358Y590042D01*
X115650Y590000D01*
G01X119671Y594454D02*
Y598454D01*
X112271D01*
G01X92117Y601900D02*
Y604400D01*
X93158D01*
X93492Y604275D01*
X93700Y604108D01*
X93783Y603775D01*
X93700Y603442D01*
X93450Y603233D01*
X93158Y603108D01*
X92117D01*
G01X93158D02*
X93783Y601900D01*
G01X95967D02*
X96050Y602442D01*
X96175Y602900D01*
X96342Y603317D01*
X96550Y603775D01*
X96883Y604400D01*
X95217D01*
G01X98358Y602942D02*
X98650Y603233D01*
X98900Y603400D01*
X99233Y603483D01*
X99525Y603400D01*
X99733Y603233D01*
X99900Y602983D01*
X99942Y602692D01*
X99900Y602442D01*
X99733Y602192D01*
X99483Y601983D01*
X99192Y601900D01*
X98858Y601983D01*
X98567Y602233D01*
X98400Y602608D01*
X98358Y603025D01*
X98442Y603567D01*
X98567Y603858D01*
X98775Y604150D01*
X99067Y604358D01*
X99358Y604400D01*
X99650Y604317D01*
X99858Y604108D01*
G01X101542Y602192D02*
X101833Y601983D01*
X102167Y601900D01*
X102500Y601983D01*
X102792Y602233D01*
X103000Y602608D01*
X103083Y602983D01*
Y603442D01*
X103000Y603817D01*
X102792Y604150D01*
X102542Y604317D01*
X102250Y604400D01*
X101917Y604317D01*
X101667Y604150D01*
X101500Y603900D01*
X101417Y603567D01*
X101500Y603275D01*
X101708Y602983D01*
X101958Y602817D01*
X102250Y602775D01*
X102583Y602858D01*
X102833Y603067D01*
X103083Y603442D01*
G01X111649Y597764D02*
Y601764D01*
X104249D01*
G01X92117Y609300D02*
Y611800D01*
X93158D01*
X93492Y611675D01*
X93700Y611508D01*
X93783Y611175D01*
X93700Y610842D01*
X93450Y610633D01*
X93158Y610508D01*
X92117D01*
G01X93158D02*
X93783Y609300D01*
G01X95967D02*
X96050Y609842D01*
X96175Y610300D01*
X96342Y610717D01*
X96550Y611175D01*
X96883Y611800D01*
X95217D01*
G01X99067Y609300D02*
X99150Y609842D01*
X99275Y610300D01*
X99442Y610717D01*
X99650Y611175D01*
X99983Y611800D01*
X98317D01*
G01X102250D02*
X101917Y611717D01*
X101667Y611508D01*
X101500Y611258D01*
X101375Y610925D01*
X101333Y610550D01*
X101375Y610175D01*
X101500Y609842D01*
X101667Y609592D01*
X101917Y609383D01*
X102250Y609300D01*
X102583Y609383D01*
X102833Y609592D01*
X103000Y609842D01*
X103125Y610175D01*
X103167Y610550D01*
X103125Y610925D01*
X103000Y611258D01*
X102833Y611508D01*
X102583Y611717D01*
X102250Y611800D01*
G01X111649Y605964D02*
Y609964D01*
X104249D01*
G01X92117Y605600D02*
Y608100D01*
X93158D01*
X93492Y607975D01*
X93700Y607808D01*
X93783Y607475D01*
X93700Y607142D01*
X93450Y606933D01*
X93158Y606808D01*
X92117D01*
G01X93158D02*
X93783Y605600D01*
G01X95967D02*
X96050Y606142D01*
X96175Y606600D01*
X96342Y607017D01*
X96550Y607475D01*
X96883Y608100D01*
X95217D01*
G01X99067Y605600D02*
X99150Y606142D01*
X99275Y606600D01*
X99442Y607017D01*
X99650Y607475D01*
X99983Y608100D01*
X98317D01*
G01X102250Y605600D02*
Y608100D01*
X101750Y607600D01*
G01Y605600D02*
X102750D01*
G01X111649Y601864D02*
Y605864D01*
X104249D01*
G01X92117Y613000D02*
Y615500D01*
X93158D01*
X93492Y615375D01*
X93700Y615208D01*
X93783Y614875D01*
X93700Y614542D01*
X93450Y614333D01*
X93158Y614208D01*
X92117D01*
G01X93158D02*
X93783Y613000D01*
G01X95967D02*
X96050Y613542D01*
X96175Y614000D01*
X96342Y614417D01*
X96550Y614875D01*
X96883Y615500D01*
X95217D01*
G01X99067Y613000D02*
X99150Y613542D01*
X99275Y614000D01*
X99442Y614417D01*
X99650Y614875D01*
X99983Y615500D01*
X98317D01*
G01X101458Y615083D02*
X101708Y615333D01*
X102000Y615458D01*
X102333Y615500D01*
X102750Y615417D01*
X103042Y615208D01*
X103125Y614958D01*
X103083Y614708D01*
X102917Y614500D01*
X102083Y614083D01*
X101708Y613792D01*
X101458Y613375D01*
X101375Y613000D01*
X103125D01*
G01X111649Y610064D02*
Y614064D01*
X104249D01*
G01X91717Y623000D02*
Y625500D01*
X92758D01*
X93092Y625375D01*
X93300Y625208D01*
X93383Y624875D01*
X93300Y624542D01*
X93050Y624333D01*
X92758Y624208D01*
X91717D01*
G01X92758D02*
X93383Y623000D01*
G01X95567D02*
X95650Y623542D01*
X95775Y624000D01*
X95942Y624417D01*
X96150Y624875D01*
X96483Y625500D01*
X94817D01*
G01X98667Y623000D02*
X98750Y623542D01*
X98875Y624000D01*
X99042Y624417D01*
X99250Y624875D01*
X99583Y625500D01*
X97917D01*
G01X100933Y623500D02*
X101183Y623208D01*
X101517Y623042D01*
X101892Y623000D01*
X102225Y623042D01*
X102558Y623250D01*
X102767Y623500D01*
X102808Y623750D01*
X102725Y624042D01*
X102433Y624250D01*
X102142Y624333D01*
X101767D01*
G01X102142D02*
X102392Y624458D01*
X102600Y624667D01*
X102683Y624917D01*
X102600Y625167D01*
X102392Y625375D01*
X102017Y625500D01*
X101642Y625458D01*
X101267Y625292D01*
G01X111649Y622364D02*
Y626364D01*
X104249D01*
G01X91717Y619300D02*
Y621800D01*
X92758D01*
X93092Y621675D01*
X93300Y621508D01*
X93383Y621175D01*
X93300Y620842D01*
X93050Y620633D01*
X92758Y620508D01*
X91717D01*
G01X92758D02*
X93383Y619300D01*
G01X95567D02*
X95650Y619842D01*
X95775Y620300D01*
X95942Y620717D01*
X96150Y621175D01*
X96483Y621800D01*
X94817D01*
G01X98750Y619300D02*
X99042Y619342D01*
X99375Y619467D01*
X99583Y619675D01*
X99667Y619967D01*
X99583Y620258D01*
X99333Y620508D01*
X98958Y620633D01*
X98542D01*
X98292Y620717D01*
X98083Y620925D01*
X98000Y621217D01*
X98125Y621508D01*
X98417Y621717D01*
X98750Y621800D01*
X99083Y621717D01*
X99375Y621508D01*
X99500Y621217D01*
X99417Y620925D01*
X99208Y620717D01*
X98958Y620633D01*
X98542D01*
X98167Y620508D01*
X97917Y620258D01*
X97833Y619967D01*
X97917Y619675D01*
X98125Y619467D01*
X98458Y619342D01*
X98750Y619300D01*
G01X101058Y620342D02*
X101350Y620633D01*
X101600Y620800D01*
X101933Y620883D01*
X102225Y620800D01*
X102433Y620633D01*
X102600Y620383D01*
X102642Y620092D01*
X102600Y619842D01*
X102433Y619592D01*
X102183Y619383D01*
X101892Y619300D01*
X101558Y619383D01*
X101267Y619633D01*
X101100Y620008D01*
X101058Y620425D01*
X101142Y620967D01*
X101267Y621258D01*
X101475Y621550D01*
X101767Y621758D01*
X102058Y621800D01*
X102350Y621717D01*
X102558Y621508D01*
G01X111649Y618264D02*
Y622264D01*
X104249D01*
G01X111175Y630267D02*
X111050Y630017D01*
X110967Y629725D01*
Y629392D01*
X111092Y629017D01*
X111300Y628725D01*
X111550Y628517D01*
X111967Y628350D01*
X112342Y628308D01*
X112717Y628392D01*
X112967Y628517D01*
X113217Y628767D01*
X113384Y629058D01*
X113467Y629350D01*
Y629642D01*
X113384Y629933D01*
X113259Y630183D01*
X113092Y630392D01*
G01X113175Y631742D02*
X113384Y632033D01*
X113467Y632367D01*
X113384Y632700D01*
X113134Y632992D01*
X112759Y633200D01*
X112384Y633283D01*
X111925D01*
X111550Y633200D01*
X111217Y632992D01*
X111050Y632742D01*
X110967Y632450D01*
X111050Y632117D01*
X111217Y631867D01*
X111467Y631700D01*
X111800Y631617D01*
X112092Y631700D01*
X112384Y631908D01*
X112550Y632158D01*
X112592Y632450D01*
X112509Y632783D01*
X112300Y633033D01*
X111925Y633283D01*
G01X110967Y635550D02*
X111050Y635217D01*
X111259Y634967D01*
X111509Y634800D01*
X111842Y634675D01*
X112217Y634633D01*
X112592Y634675D01*
X112925Y634800D01*
X113175Y634967D01*
X113384Y635217D01*
X113467Y635550D01*
X113384Y635883D01*
X113175Y636133D01*
X112925Y636300D01*
X112592Y636425D01*
X112217Y636467D01*
X111842Y636425D01*
X111509Y636300D01*
X111259Y636133D01*
X111050Y635883D01*
X110967Y635550D01*
G01X71000Y631017D02*
X68500D01*
Y632058D01*
X68625Y632392D01*
X68792Y632600D01*
X69125Y632683D01*
X69458Y632600D01*
X69667Y632350D01*
X69792Y632058D01*
Y631017D01*
G01Y632058D02*
X71000Y632683D01*
G01X70625Y634033D02*
X70833Y634283D01*
X70958Y634575D01*
X71000Y634950D01*
X70917Y635325D01*
X70750Y635617D01*
X70458Y635825D01*
X70125Y635867D01*
X69792Y635783D01*
X69583Y635575D01*
X69417Y635283D01*
X69375Y634992D01*
X69417Y634700D01*
X69583Y634325D01*
X68500Y634450D01*
Y635575D01*
G01X68917Y637258D02*
X68667Y637508D01*
X68542Y637800D01*
X68500Y638133D01*
X68583Y638550D01*
X68792Y638842D01*
X69042Y638925D01*
X69292Y638883D01*
X69500Y638717D01*
X69917Y637883D01*
X70208Y637508D01*
X70625Y637258D01*
X71000Y637175D01*
Y638925D01*
G01X70708Y640442D02*
X70917Y640733D01*
X71000Y641067D01*
X70917Y641400D01*
X70667Y641692D01*
X70292Y641900D01*
X69917Y641983D01*
X69458D01*
X69083Y641900D01*
X68750Y641692D01*
X68583Y641442D01*
X68500Y641150D01*
X68583Y640817D01*
X68750Y640567D01*
X69000Y640400D01*
X69333Y640317D01*
X69625Y640400D01*
X69917Y640608D01*
X70083Y640858D01*
X70125Y641150D01*
X70042Y641483D01*
X69833Y641733D01*
X69458Y641983D01*
G01X75550Y627046D02*
Y632246D01*
G01X82550Y627046D02*
Y634846D01*
G01X75550Y627046D02*
X82550D01*
G01X75550Y640446D02*
Y631746D01*
G01X82550Y634046D02*
Y640446D01*
G01X137033Y572200D02*
Y570408D01*
X137200Y570033D01*
X137533Y569783D01*
X137950Y569700D01*
X138367Y569783D01*
X138700Y570033D01*
X138867Y570408D01*
Y572200D01*
G01X140258Y571783D02*
X140508Y572033D01*
X140800Y572158D01*
X141133Y572200D01*
X141550Y572117D01*
X141842Y571908D01*
X141925Y571658D01*
X141883Y571408D01*
X141717Y571200D01*
X140883Y570783D01*
X140508Y570492D01*
X140258Y570075D01*
X140175Y569700D01*
X141925D01*
G01X130100Y648200D02*
X137100D01*
Y634800D01*
X130100D01*
Y648200D01*
G01X132032Y677863D02*
X131782Y677988D01*
X131490Y678071D01*
X131157D01*
X130782Y677946D01*
X130490Y677738D01*
X130282Y677488D01*
X130115Y677071D01*
X130073Y676696D01*
X130157Y676321D01*
X130282Y676071D01*
X130532Y675821D01*
X130823Y675654D01*
X131115Y675571D01*
X131407D01*
X131698Y675654D01*
X131948Y675779D01*
X132157Y675946D01*
G01X134215Y675571D02*
Y678071D01*
X133715Y677571D01*
G01Y675571D02*
X134715D01*
G01X137315D02*
X137607Y675613D01*
X137940Y675738D01*
X138148Y675946D01*
X138232Y676238D01*
X138148Y676529D01*
X137898Y676779D01*
X137523Y676904D01*
X137107D01*
X136857Y676988D01*
X136648Y677196D01*
X136565Y677488D01*
X136690Y677779D01*
X136982Y677988D01*
X137315Y678071D01*
X137648Y677988D01*
X137940Y677779D01*
X138065Y677488D01*
X137982Y677196D01*
X137773Y676988D01*
X137523Y676904D01*
X137107D01*
X136732Y676779D01*
X136482Y676529D01*
X136398Y676238D01*
X136482Y675946D01*
X136690Y675738D01*
X137023Y675613D01*
X137315Y675571D01*
G01X140915D02*
Y678071D01*
X139373Y676279D01*
X141457D01*
G01X132032Y681863D02*
X131782Y681988D01*
X131490Y682071D01*
X131157D01*
X130782Y681946D01*
X130490Y681738D01*
X130282Y681488D01*
X130115Y681071D01*
X130073Y680696D01*
X130157Y680321D01*
X130282Y680071D01*
X130532Y679821D01*
X130823Y679654D01*
X131115Y679571D01*
X131407D01*
X131698Y679654D01*
X131948Y679779D01*
X132157Y679946D01*
G01X134215Y679571D02*
Y682071D01*
X133715Y681571D01*
G01Y679571D02*
X134715D01*
G01X137315D02*
X137607Y679613D01*
X137940Y679738D01*
X138148Y679946D01*
X138232Y680238D01*
X138148Y680529D01*
X137898Y680779D01*
X137523Y680904D01*
X137107D01*
X136857Y680988D01*
X136648Y681196D01*
X136565Y681488D01*
X136690Y681779D01*
X136982Y681988D01*
X137315Y682071D01*
X137648Y681988D01*
X137940Y681779D01*
X138065Y681488D01*
X137982Y681196D01*
X137773Y680988D01*
X137523Y680904D01*
X137107D01*
X136732Y680779D01*
X136482Y680529D01*
X136398Y680238D01*
X136482Y679946D01*
X136690Y679738D01*
X137023Y679613D01*
X137315Y679571D01*
G01X139498Y680071D02*
X139748Y679779D01*
X140082Y679613D01*
X140457Y679571D01*
X140790Y679613D01*
X141123Y679821D01*
X141332Y680071D01*
X141373Y680321D01*
X141290Y680613D01*
X140998Y680821D01*
X140707Y680904D01*
X140332D01*
G01X140707D02*
X140957Y681029D01*
X141165Y681238D01*
X141248Y681488D01*
X141165Y681738D01*
X140957Y681946D01*
X140582Y682071D01*
X140207Y682029D01*
X139832Y681863D01*
G01X114347Y649811D02*
X114222Y649561D01*
X114139Y649269D01*
Y648936D01*
X114264Y648561D01*
X114472Y648269D01*
X114722Y648061D01*
X115139Y647894D01*
X115514Y647852D01*
X115889Y647936D01*
X116139Y648061D01*
X116389Y648311D01*
X116556Y648602D01*
X116639Y648894D01*
Y649186D01*
X116556Y649477D01*
X116431Y649727D01*
X116264Y649936D01*
G01X116639Y651994D02*
X114139D01*
X114639Y651494D01*
G01X116639D02*
Y652494D01*
G01X114139Y655094D02*
X114222Y654761D01*
X114431Y654511D01*
X114681Y654344D01*
X115014Y654219D01*
X115389Y654177D01*
X115764Y654219D01*
X116097Y654344D01*
X116347Y654511D01*
X116556Y654761D01*
X116639Y655094D01*
X116556Y655427D01*
X116347Y655677D01*
X116097Y655844D01*
X115764Y655969D01*
X115389Y656011D01*
X115014Y655969D01*
X114681Y655844D01*
X114431Y655677D01*
X114222Y655427D01*
X114139Y655094D01*
G01X116264Y657277D02*
X116472Y657527D01*
X116597Y657819D01*
X116639Y658194D01*
X116556Y658569D01*
X116389Y658861D01*
X116097Y659069D01*
X115764Y659111D01*
X115431Y659027D01*
X115222Y658819D01*
X115056Y658527D01*
X115014Y658236D01*
X115056Y657944D01*
X115222Y657569D01*
X114139Y657694D01*
Y658819D01*
G01X102099Y669232D02*
X101974Y668982D01*
X101891Y668690D01*
Y668357D01*
X102016Y667982D01*
X102224Y667690D01*
X102474Y667482D01*
X102891Y667315D01*
X103266Y667273D01*
X103641Y667357D01*
X103891Y667482D01*
X104141Y667732D01*
X104308Y668023D01*
X104391Y668315D01*
Y668607D01*
X104308Y668898D01*
X104183Y669148D01*
X104016Y669357D01*
G01X102308Y670623D02*
X102058Y670873D01*
X101933Y671165D01*
X101891Y671498D01*
X101974Y671915D01*
X102183Y672207D01*
X102433Y672290D01*
X102683Y672248D01*
X102891Y672082D01*
X103308Y671248D01*
X103599Y670873D01*
X104016Y670623D01*
X104391Y670540D01*
Y672290D01*
G01X103891Y673598D02*
X104183Y673848D01*
X104349Y674182D01*
X104391Y674557D01*
X104349Y674890D01*
X104141Y675223D01*
X103891Y675432D01*
X103641Y675473D01*
X103349Y675390D01*
X103141Y675098D01*
X103058Y674807D01*
Y674432D01*
G01Y674807D02*
X102933Y675057D01*
X102724Y675265D01*
X102474Y675348D01*
X102224Y675265D01*
X102016Y675057D01*
X101891Y674682D01*
X101933Y674307D01*
X102099Y673932D01*
G01X101891Y677615D02*
X101974Y677282D01*
X102183Y677032D01*
X102433Y676865D01*
X102766Y676740D01*
X103141Y676698D01*
X103516Y676740D01*
X103849Y676865D01*
X104099Y677032D01*
X104308Y677282D01*
X104391Y677615D01*
X104308Y677948D01*
X104099Y678198D01*
X103849Y678365D01*
X103516Y678490D01*
X103141Y678532D01*
X102766Y678490D01*
X102433Y678365D01*
X102183Y678198D01*
X101974Y677948D01*
X101891Y677615D01*
G01X118047Y649811D02*
X117922Y649561D01*
X117839Y649269D01*
Y648936D01*
X117964Y648561D01*
X118172Y648269D01*
X118422Y648061D01*
X118839Y647894D01*
X119214Y647852D01*
X119589Y647936D01*
X119839Y648061D01*
X120089Y648311D01*
X120256Y648602D01*
X120339Y648894D01*
Y649186D01*
X120256Y649477D01*
X120131Y649727D01*
X119964Y649936D01*
G01X120339Y651994D02*
X117839D01*
X118339Y651494D01*
G01X120339D02*
Y652494D01*
G01X117839Y655094D02*
X117922Y654761D01*
X118131Y654511D01*
X118381Y654344D01*
X118714Y654219D01*
X119089Y654177D01*
X119464Y654219D01*
X119797Y654344D01*
X120047Y654511D01*
X120256Y654761D01*
X120339Y655094D01*
X120256Y655427D01*
X120047Y655677D01*
X119797Y655844D01*
X119464Y655969D01*
X119089Y656011D01*
X118714Y655969D01*
X118381Y655844D01*
X118131Y655677D01*
X117922Y655427D01*
X117839Y655094D01*
G01X119839Y657277D02*
X120131Y657527D01*
X120297Y657861D01*
X120339Y658236D01*
X120297Y658569D01*
X120089Y658902D01*
X119839Y659111D01*
X119589Y659152D01*
X119297Y659069D01*
X119089Y658777D01*
X119006Y658486D01*
Y658111D01*
G01Y658486D02*
X118881Y658736D01*
X118672Y658944D01*
X118422Y659027D01*
X118172Y658944D01*
X117964Y658736D01*
X117839Y658361D01*
X117881Y657986D01*
X118047Y657611D01*
G01X107832Y677979D02*
X107582Y678104D01*
X107290Y678187D01*
X106957D01*
X106582Y678062D01*
X106290Y677854D01*
X106082Y677604D01*
X105915Y677187D01*
X105873Y676812D01*
X105957Y676437D01*
X106082Y676187D01*
X106332Y675937D01*
X106623Y675770D01*
X106915Y675687D01*
X107207D01*
X107498Y675770D01*
X107748Y675895D01*
X107957Y676062D01*
G01X109223Y677770D02*
X109473Y678020D01*
X109765Y678145D01*
X110098Y678187D01*
X110515Y678104D01*
X110807Y677895D01*
X110890Y677645D01*
X110848Y677395D01*
X110682Y677187D01*
X109848Y676770D01*
X109473Y676479D01*
X109223Y676062D01*
X109140Y675687D01*
X110890D01*
G01X112198Y676187D02*
X112448Y675895D01*
X112782Y675729D01*
X113157Y675687D01*
X113490Y675729D01*
X113823Y675937D01*
X114032Y676187D01*
X114073Y676437D01*
X113990Y676729D01*
X113698Y676937D01*
X113407Y677020D01*
X113032D01*
G01X113407D02*
X113657Y677145D01*
X113865Y677354D01*
X113948Y677604D01*
X113865Y677854D01*
X113657Y678062D01*
X113282Y678187D01*
X112907Y678145D01*
X112532Y677979D01*
G01X115423Y677770D02*
X115673Y678020D01*
X115965Y678145D01*
X116298Y678187D01*
X116715Y678104D01*
X117007Y677895D01*
X117090Y677645D01*
X117048Y677395D01*
X116882Y677187D01*
X116048Y676770D01*
X115673Y676479D01*
X115423Y676062D01*
X115340Y675687D01*
X117090D01*
G01X107832Y682979D02*
X107582Y683104D01*
X107290Y683187D01*
X106957D01*
X106582Y683062D01*
X106290Y682854D01*
X106082Y682604D01*
X105915Y682187D01*
X105873Y681812D01*
X105957Y681437D01*
X106082Y681187D01*
X106332Y680937D01*
X106623Y680770D01*
X106915Y680687D01*
X107207D01*
X107498Y680770D01*
X107748Y680895D01*
X107957Y681062D01*
G01X109223Y682770D02*
X109473Y683020D01*
X109765Y683145D01*
X110098Y683187D01*
X110515Y683104D01*
X110807Y682895D01*
X110890Y682645D01*
X110848Y682395D01*
X110682Y682187D01*
X109848Y681770D01*
X109473Y681479D01*
X109223Y681062D01*
X109140Y680687D01*
X110890D01*
G01X112198Y681187D02*
X112448Y680895D01*
X112782Y680729D01*
X113157Y680687D01*
X113490Y680729D01*
X113823Y680937D01*
X114032Y681187D01*
X114073Y681437D01*
X113990Y681729D01*
X113698Y681937D01*
X113407Y682020D01*
X113032D01*
G01X113407D02*
X113657Y682145D01*
X113865Y682354D01*
X113948Y682604D01*
X113865Y682854D01*
X113657Y683062D01*
X113282Y683187D01*
X112907Y683145D01*
X112532Y682979D01*
G01X116215Y680687D02*
Y683187D01*
X115715Y682687D01*
G01Y680687D02*
X116715D01*
G01X101098Y654483D02*
X100973Y654233D01*
X100890Y653941D01*
Y653608D01*
X101015Y653233D01*
X101223Y652941D01*
X101473Y652733D01*
X101890Y652566D01*
X102265Y652524D01*
X102640Y652608D01*
X102890Y652733D01*
X103140Y652983D01*
X103307Y653274D01*
X103390Y653566D01*
Y653858D01*
X103307Y654149D01*
X103182Y654399D01*
X103015Y654608D01*
G01X101307Y655874D02*
X101057Y656124D01*
X100932Y656416D01*
X100890Y656749D01*
X100973Y657166D01*
X101182Y657458D01*
X101432Y657541D01*
X101682Y657499D01*
X101890Y657333D01*
X102307Y656499D01*
X102598Y656124D01*
X103015Y655874D01*
X103390Y655791D01*
Y657541D01*
G01X101307Y658974D02*
X101057Y659224D01*
X100932Y659516D01*
X100890Y659849D01*
X100973Y660266D01*
X101182Y660558D01*
X101432Y660641D01*
X101682Y660599D01*
X101890Y660433D01*
X102307Y659599D01*
X102598Y659224D01*
X103015Y658974D01*
X103390Y658891D01*
Y660641D01*
G01Y663366D02*
X100890D01*
X102682Y661824D01*
Y663908D01*
G01X96967Y654594D02*
X96842Y654344D01*
X96759Y654052D01*
Y653719D01*
X96884Y653344D01*
X97092Y653052D01*
X97342Y652844D01*
X97759Y652677D01*
X98134Y652635D01*
X98509Y652719D01*
X98759Y652844D01*
X99009Y653094D01*
X99176Y653385D01*
X99259Y653677D01*
Y653969D01*
X99176Y654260D01*
X99051Y654510D01*
X98884Y654719D01*
G01X97176Y655985D02*
X96926Y656235D01*
X96801Y656527D01*
X96759Y656860D01*
X96842Y657277D01*
X97051Y657569D01*
X97301Y657652D01*
X97551Y657610D01*
X97759Y657444D01*
X98176Y656610D01*
X98467Y656235D01*
X98884Y655985D01*
X99259Y655902D01*
Y657652D01*
G01X97176Y659085D02*
X96926Y659335D01*
X96801Y659627D01*
X96759Y659960D01*
X96842Y660377D01*
X97051Y660669D01*
X97301Y660752D01*
X97551Y660710D01*
X97759Y660544D01*
X98176Y659710D01*
X98467Y659335D01*
X98884Y659085D01*
X99259Y659002D01*
Y660752D01*
G01X98759Y662060D02*
X99051Y662310D01*
X99217Y662644D01*
X99259Y663019D01*
X99217Y663352D01*
X99009Y663685D01*
X98759Y663894D01*
X98509Y663935D01*
X98217Y663852D01*
X98009Y663560D01*
X97926Y663269D01*
Y662894D01*
G01Y663269D02*
X97801Y663519D01*
X97592Y663727D01*
X97342Y663810D01*
X97092Y663727D01*
X96884Y663519D01*
X96759Y663144D01*
X96801Y662769D01*
X96967Y662394D01*
G01X103334Y687517D02*
X100834D01*
Y688558D01*
X100959Y688892D01*
X101126Y689100D01*
X101459Y689183D01*
X101792Y689100D01*
X102001Y688850D01*
X102126Y688558D01*
Y687517D01*
G01Y688558D02*
X103334Y689183D01*
G01Y691950D02*
X100834D01*
X102626Y690408D01*
Y692492D01*
G01X103042Y693842D02*
X103251Y694133D01*
X103334Y694467D01*
X103251Y694800D01*
X103001Y695092D01*
X102626Y695300D01*
X102251Y695383D01*
X101792D01*
X101417Y695300D01*
X101084Y695092D01*
X100917Y694842D01*
X100834Y694550D01*
X100917Y694217D01*
X101084Y693967D01*
X101334Y693800D01*
X101667Y693717D01*
X101959Y693800D01*
X102251Y694008D01*
X102417Y694258D01*
X102459Y694550D01*
X102376Y694883D01*
X102167Y695133D01*
X101792Y695383D01*
G01X103334Y698150D02*
X100834D01*
X102626Y696608D01*
Y698692D01*
G01X115349Y691647D02*
X119349D01*
Y699047D01*
G01X130366Y671571D02*
Y674071D01*
X131407D01*
X131741Y673946D01*
X131949Y673779D01*
X132032Y673446D01*
X131949Y673113D01*
X131699Y672904D01*
X131407Y672779D01*
X130366D01*
G01X131407D02*
X132032Y671571D01*
G01X134799D02*
Y674071D01*
X133257Y672279D01*
X135341D01*
G01X136691Y671863D02*
X136982Y671654D01*
X137316Y671571D01*
X137649Y671654D01*
X137941Y671904D01*
X138149Y672279D01*
X138232Y672654D01*
Y673113D01*
X138149Y673488D01*
X137941Y673821D01*
X137691Y673988D01*
X137399Y674071D01*
X137066Y673988D01*
X136816Y673821D01*
X136649Y673571D01*
X136566Y673238D01*
X136649Y672946D01*
X136857Y672654D01*
X137107Y672488D01*
X137399Y672446D01*
X137732Y672529D01*
X137982Y672738D01*
X138232Y673113D01*
G01X139707Y672613D02*
X139999Y672904D01*
X140249Y673071D01*
X140582Y673154D01*
X140874Y673071D01*
X141082Y672904D01*
X141249Y672654D01*
X141291Y672363D01*
X141249Y672113D01*
X141082Y671863D01*
X140832Y671654D01*
X140541Y671571D01*
X140207Y671654D01*
X139916Y671904D01*
X139749Y672279D01*
X139707Y672696D01*
X139791Y673238D01*
X139916Y673529D01*
X140124Y673821D01*
X140416Y674029D01*
X140707Y674071D01*
X140999Y673988D01*
X141207Y673779D01*
G01X138500Y654017D02*
X136000D01*
Y655058D01*
X136125Y655392D01*
X136292Y655600D01*
X136625Y655683D01*
X136958Y655600D01*
X137167Y655350D01*
X137292Y655058D01*
Y654017D01*
G01Y655058D02*
X138500Y655683D01*
G01X138000Y657033D02*
X138292Y657283D01*
X138458Y657617D01*
X138500Y657992D01*
X138458Y658325D01*
X138250Y658658D01*
X138000Y658867D01*
X137750Y658908D01*
X137458Y658825D01*
X137250Y658533D01*
X137167Y658242D01*
Y657867D01*
G01Y658242D02*
X137042Y658492D01*
X136833Y658700D01*
X136583Y658783D01*
X136333Y658700D01*
X136125Y658492D01*
X136000Y658117D01*
X136042Y657742D01*
X136208Y657367D01*
G01X136000Y661050D02*
X136083Y660717D01*
X136292Y660467D01*
X136542Y660300D01*
X136875Y660175D01*
X137250Y660133D01*
X137625Y660175D01*
X137958Y660300D01*
X138208Y660467D01*
X138417Y660717D01*
X138500Y661050D01*
X138417Y661383D01*
X138208Y661633D01*
X137958Y661800D01*
X137625Y661925D01*
X137250Y661967D01*
X136875Y661925D01*
X136542Y661800D01*
X136292Y661633D01*
X136083Y661383D01*
X136000Y661050D01*
G01Y664150D02*
X136083Y663817D01*
X136292Y663567D01*
X136542Y663400D01*
X136875Y663275D01*
X137250Y663233D01*
X137625Y663275D01*
X137958Y663400D01*
X138208Y663567D01*
X138417Y663817D01*
X138500Y664150D01*
X138417Y664483D01*
X138208Y664733D01*
X137958Y664900D01*
X137625Y665025D01*
X137250Y665067D01*
X136875Y665025D01*
X136542Y664900D01*
X136292Y664733D01*
X136083Y664483D01*
X136000Y664150D01*
G01X142500Y654017D02*
X140000D01*
Y655058D01*
X140125Y655392D01*
X140292Y655600D01*
X140625Y655683D01*
X140958Y655600D01*
X141167Y655350D01*
X141292Y655058D01*
Y654017D01*
G01Y655058D02*
X142500Y655683D01*
G01X140417Y657158D02*
X140167Y657408D01*
X140042Y657700D01*
X140000Y658033D01*
X140083Y658450D01*
X140292Y658742D01*
X140542Y658825D01*
X140792Y658783D01*
X141000Y658617D01*
X141417Y657783D01*
X141708Y657408D01*
X142125Y657158D01*
X142500Y657075D01*
Y658825D01*
G01X142208Y660342D02*
X142417Y660633D01*
X142500Y660967D01*
X142417Y661300D01*
X142167Y661592D01*
X141792Y661800D01*
X141417Y661883D01*
X140958D01*
X140583Y661800D01*
X140250Y661592D01*
X140083Y661342D01*
X140000Y661050D01*
X140083Y660717D01*
X140250Y660467D01*
X140500Y660300D01*
X140833Y660217D01*
X141125Y660300D01*
X141417Y660508D01*
X141583Y660758D01*
X141625Y661050D01*
X141542Y661383D01*
X141333Y661633D01*
X140958Y661883D01*
G01X142208Y663442D02*
X142417Y663733D01*
X142500Y664067D01*
X142417Y664400D01*
X142167Y664692D01*
X141792Y664900D01*
X141417Y664983D01*
X140958D01*
X140583Y664900D01*
X140250Y664692D01*
X140083Y664442D01*
X140000Y664150D01*
X140083Y663817D01*
X140250Y663567D01*
X140500Y663400D01*
X140833Y663317D01*
X141125Y663400D01*
X141417Y663608D01*
X141583Y663858D01*
X141625Y664150D01*
X141542Y664483D01*
X141333Y664733D01*
X140958Y664983D01*
G01X107334Y687517D02*
X104834D01*
Y688558D01*
X104959Y688892D01*
X105126Y689100D01*
X105459Y689183D01*
X105792Y689100D01*
X106001Y688850D01*
X106126Y688558D01*
Y687517D01*
G01Y688558D02*
X107334Y689183D01*
G01Y691950D02*
X104834D01*
X106626Y690408D01*
Y692492D01*
G01X107042Y693842D02*
X107251Y694133D01*
X107334Y694467D01*
X107251Y694800D01*
X107001Y695092D01*
X106626Y695300D01*
X106251Y695383D01*
X105792D01*
X105417Y695300D01*
X105084Y695092D01*
X104917Y694842D01*
X104834Y694550D01*
X104917Y694217D01*
X105084Y693967D01*
X105334Y693800D01*
X105667Y693717D01*
X105959Y693800D01*
X106251Y694008D01*
X106417Y694258D01*
X106459Y694550D01*
X106376Y694883D01*
X106167Y695133D01*
X105792Y695383D01*
G01X107334Y697567D02*
X106792Y697650D01*
X106334Y697775D01*
X105917Y697942D01*
X105459Y698150D01*
X104834Y698483D01*
Y696817D01*
G01X119449Y688847D02*
X123449D01*
Y696247D01*
G01X98834Y705517D02*
X96334D01*
Y706558D01*
X96459Y706892D01*
X96626Y707100D01*
X96959Y707183D01*
X97292Y707100D01*
X97501Y706850D01*
X97626Y706558D01*
Y705517D01*
G01Y706558D02*
X98834Y707183D01*
G01Y709950D02*
X96334D01*
X98126Y708408D01*
Y710492D01*
G01X98542Y711842D02*
X98751Y712133D01*
X98834Y712467D01*
X98751Y712800D01*
X98501Y713092D01*
X98126Y713300D01*
X97751Y713383D01*
X97292D01*
X96917Y713300D01*
X96584Y713092D01*
X96417Y712842D01*
X96334Y712550D01*
X96417Y712217D01*
X96584Y711967D01*
X96834Y711800D01*
X97167Y711717D01*
X97459Y711800D01*
X97751Y712008D01*
X97917Y712258D01*
X97959Y712550D01*
X97876Y712883D01*
X97667Y713133D01*
X97292Y713383D01*
G01X98459Y714733D02*
X98667Y714983D01*
X98792Y715275D01*
X98834Y715650D01*
X98751Y716025D01*
X98584Y716317D01*
X98292Y716525D01*
X97959Y716567D01*
X97626Y716483D01*
X97417Y716275D01*
X97251Y715983D01*
X97209Y715692D01*
X97251Y715400D01*
X97417Y715025D01*
X96334Y715150D01*
Y716275D01*
G01X113200Y715300D02*
X109200D01*
Y707900D01*
G01X99834Y687517D02*
X97334D01*
Y688558D01*
X97459Y688892D01*
X97626Y689100D01*
X97959Y689183D01*
X98292Y689100D01*
X98501Y688850D01*
X98626Y688558D01*
Y687517D01*
G01Y688558D02*
X99834Y689183D01*
G01Y691950D02*
X97334D01*
X99126Y690408D01*
Y692492D01*
G01X99542Y693842D02*
X99751Y694133D01*
X99834Y694467D01*
X99751Y694800D01*
X99501Y695092D01*
X99126Y695300D01*
X98751Y695383D01*
X98292D01*
X97917Y695300D01*
X97584Y695092D01*
X97417Y694842D01*
X97334Y694550D01*
X97417Y694217D01*
X97584Y693967D01*
X97834Y693800D01*
X98167Y693717D01*
X98459Y693800D01*
X98751Y694008D01*
X98917Y694258D01*
X98959Y694550D01*
X98876Y694883D01*
X98667Y695133D01*
X98292Y695383D01*
G01X99334Y696733D02*
X99626Y696983D01*
X99792Y697317D01*
X99834Y697692D01*
X99792Y698025D01*
X99584Y698358D01*
X99334Y698567D01*
X99084Y698608D01*
X98792Y698525D01*
X98584Y698233D01*
X98501Y697942D01*
Y697567D01*
G01Y697942D02*
X98376Y698192D01*
X98167Y698400D01*
X97917Y698483D01*
X97667Y698400D01*
X97459Y698192D01*
X97334Y697817D01*
X97376Y697442D01*
X97542Y697067D01*
G01X111349Y691647D02*
X115349D01*
Y699047D01*
G01X91517Y701000D02*
Y703500D01*
X92558D01*
X92892Y703375D01*
X93100Y703208D01*
X93183Y702875D01*
X93100Y702542D01*
X92850Y702333D01*
X92558Y702208D01*
X91517D01*
G01X92558D02*
X93183Y701000D01*
G01X95950D02*
Y703500D01*
X94408Y701708D01*
X96492D01*
G01X97842Y701292D02*
X98133Y701083D01*
X98467Y701000D01*
X98800Y701083D01*
X99092Y701333D01*
X99300Y701708D01*
X99383Y702083D01*
Y702542D01*
X99300Y702917D01*
X99092Y703250D01*
X98842Y703417D01*
X98550Y703500D01*
X98217Y703417D01*
X97967Y703250D01*
X97800Y703000D01*
X97717Y702667D01*
X97800Y702375D01*
X98008Y702083D01*
X98258Y701917D01*
X98550Y701875D01*
X98883Y701958D01*
X99133Y702167D01*
X99383Y702542D01*
G01X100858Y703083D02*
X101108Y703333D01*
X101400Y703458D01*
X101733Y703500D01*
X102150Y703417D01*
X102442Y703208D01*
X102525Y702958D01*
X102483Y702708D01*
X102317Y702500D01*
X101483Y702083D01*
X101108Y701792D01*
X100858Y701375D01*
X100775Y701000D01*
X102525D01*
G01X115299Y699465D02*
Y703465D01*
X107899D01*
G01X84137Y701407D02*
X81637D01*
Y702448D01*
X81762Y702782D01*
X81929Y702990D01*
X82262Y703073D01*
X82595Y702990D01*
X82804Y702740D01*
X82929Y702448D01*
Y701407D01*
G01Y702448D02*
X84137Y703073D01*
G01X83762Y704423D02*
X83970Y704673D01*
X84095Y704965D01*
X84137Y705340D01*
X84054Y705715D01*
X83887Y706007D01*
X83595Y706215D01*
X83262Y706257D01*
X82929Y706173D01*
X82720Y705965D01*
X82554Y705673D01*
X82512Y705382D01*
X82554Y705090D01*
X82720Y704715D01*
X81637Y704840D01*
Y705965D01*
G01X83637Y707523D02*
X83929Y707773D01*
X84095Y708107D01*
X84137Y708482D01*
X84095Y708815D01*
X83887Y709148D01*
X83637Y709357D01*
X83387Y709398D01*
X83095Y709315D01*
X82887Y709023D01*
X82804Y708732D01*
Y708357D01*
G01Y708732D02*
X82679Y708982D01*
X82470Y709190D01*
X82220Y709273D01*
X81970Y709190D01*
X81762Y708982D01*
X81637Y708607D01*
X81679Y708232D01*
X81845Y707857D01*
G01X82054Y710748D02*
X81804Y710998D01*
X81679Y711290D01*
X81637Y711623D01*
X81720Y712040D01*
X81929Y712332D01*
X82179Y712415D01*
X82429Y712373D01*
X82637Y712207D01*
X83054Y711373D01*
X83345Y710998D01*
X83762Y710748D01*
X84137Y710665D01*
Y712415D01*
G01X88028Y695139D02*
X84028D01*
Y687739D01*
G01X123017Y685167D02*
Y687667D01*
X124058D01*
X124392Y687542D01*
X124600Y687375D01*
X124683Y687042D01*
X124600Y686709D01*
X124350Y686500D01*
X124058Y686375D01*
X123017D01*
G01X124058D02*
X124683Y685167D01*
G01X127450D02*
Y687667D01*
X125908Y685875D01*
X127992D01*
G01X129342Y685459D02*
X129633Y685250D01*
X129967Y685167D01*
X130300Y685250D01*
X130592Y685500D01*
X130800Y685875D01*
X130883Y686250D01*
Y686709D01*
X130800Y687084D01*
X130592Y687417D01*
X130342Y687584D01*
X130050Y687667D01*
X129717Y687584D01*
X129467Y687417D01*
X129300Y687167D01*
X129217Y686834D01*
X129300Y686542D01*
X129508Y686250D01*
X129758Y686084D01*
X130050Y686042D01*
X130383Y686125D01*
X130633Y686334D01*
X130883Y686709D01*
G01X132442Y685459D02*
X132733Y685250D01*
X133067Y685167D01*
X133400Y685250D01*
X133692Y685500D01*
X133900Y685875D01*
X133983Y686250D01*
Y686709D01*
X133900Y687084D01*
X133692Y687417D01*
X133442Y687584D01*
X133150Y687667D01*
X132817Y687584D01*
X132567Y687417D01*
X132400Y687167D01*
X132317Y686834D01*
X132400Y686542D01*
X132608Y686250D01*
X132858Y686084D01*
X133150Y686042D01*
X133483Y686125D01*
X133733Y686334D01*
X133983Y686709D01*
G01X143049Y685715D02*
Y689715D01*
X135649D01*
G01X80037Y701507D02*
X77537D01*
Y702548D01*
X77662Y702882D01*
X77829Y703090D01*
X78162Y703173D01*
X78495Y703090D01*
X78704Y702840D01*
X78829Y702548D01*
Y701507D01*
G01Y702548D02*
X80037Y703173D01*
G01X79662Y704523D02*
X79870Y704773D01*
X79995Y705065D01*
X80037Y705440D01*
X79954Y705815D01*
X79787Y706107D01*
X79495Y706315D01*
X79162Y706357D01*
X78829Y706273D01*
X78620Y706065D01*
X78454Y705773D01*
X78412Y705482D01*
X78454Y705190D01*
X78620Y704815D01*
X77537Y704940D01*
Y706065D01*
G01X79537Y707623D02*
X79829Y707873D01*
X79995Y708207D01*
X80037Y708582D01*
X79995Y708915D01*
X79787Y709248D01*
X79537Y709457D01*
X79287Y709498D01*
X78995Y709415D01*
X78787Y709123D01*
X78704Y708832D01*
Y708457D01*
G01Y708832D02*
X78579Y709082D01*
X78370Y709290D01*
X78120Y709373D01*
X77870Y709290D01*
X77662Y709082D01*
X77537Y708707D01*
X77579Y708332D01*
X77745Y707957D01*
G01X79537Y710723D02*
X79829Y710973D01*
X79995Y711307D01*
X80037Y711682D01*
X79995Y712015D01*
X79787Y712348D01*
X79537Y712557D01*
X79287Y712598D01*
X78995Y712515D01*
X78787Y712223D01*
X78704Y711932D01*
Y711557D01*
G01Y711932D02*
X78579Y712182D01*
X78370Y712390D01*
X78120Y712473D01*
X77870Y712390D01*
X77662Y712182D01*
X77537Y711807D01*
X77579Y711432D01*
X77745Y711057D01*
G01X83928Y695239D02*
X79928D01*
Y687839D01*
G01X105620Y638466D02*
X103120D01*
Y639507D01*
X103245Y639841D01*
X103412Y640049D01*
X103745Y640132D01*
X104078Y640049D01*
X104287Y639799D01*
X104412Y639507D01*
Y638466D01*
G01Y639507D02*
X105620Y640132D01*
G01X105120Y641482D02*
X105412Y641732D01*
X105578Y642066D01*
X105620Y642441D01*
X105578Y642774D01*
X105370Y643107D01*
X105120Y643316D01*
X104870Y643357D01*
X104578Y643274D01*
X104370Y642982D01*
X104287Y642691D01*
Y642316D01*
G01Y642691D02*
X104162Y642941D01*
X103953Y643149D01*
X103703Y643232D01*
X103453Y643149D01*
X103245Y642941D01*
X103120Y642566D01*
X103162Y642191D01*
X103328Y641816D01*
G01X104578Y644707D02*
X104287Y644999D01*
X104120Y645249D01*
X104037Y645582D01*
X104120Y645874D01*
X104287Y646082D01*
X104537Y646249D01*
X104828Y646291D01*
X105078Y646249D01*
X105328Y646082D01*
X105537Y645832D01*
X105620Y645541D01*
X105537Y645207D01*
X105287Y644916D01*
X104912Y644749D01*
X104495Y644707D01*
X103953Y644791D01*
X103662Y644916D01*
X103370Y645124D01*
X103162Y645416D01*
X103120Y645707D01*
X103203Y645999D01*
X103412Y646207D01*
G01X105620Y648599D02*
X105578Y648891D01*
X105453Y649224D01*
X105245Y649432D01*
X104953Y649516D01*
X104662Y649432D01*
X104412Y649182D01*
X104287Y648807D01*
Y648391D01*
X104203Y648141D01*
X103995Y647932D01*
X103703Y647849D01*
X103412Y647974D01*
X103203Y648266D01*
X103120Y648599D01*
X103203Y648932D01*
X103412Y649224D01*
X103703Y649349D01*
X103995Y649266D01*
X104203Y649057D01*
X104287Y648807D01*
Y648391D01*
X104412Y648016D01*
X104662Y647766D01*
X104953Y647682D01*
X105245Y647766D01*
X105453Y647974D01*
X105578Y648307D01*
X105620Y648599D01*
G01X71873Y703112D02*
X71748Y702862D01*
X71665Y702570D01*
Y702237D01*
X71790Y701862D01*
X71998Y701570D01*
X72248Y701362D01*
X72665Y701195D01*
X73040Y701153D01*
X73415Y701237D01*
X73665Y701362D01*
X73915Y701612D01*
X74082Y701903D01*
X74165Y702195D01*
Y702487D01*
X74082Y702778D01*
X73957Y703028D01*
X73790Y703237D01*
G01X72082Y704503D02*
X71832Y704753D01*
X71707Y705045D01*
X71665Y705378D01*
X71748Y705795D01*
X71957Y706087D01*
X72207Y706170D01*
X72457Y706128D01*
X72665Y705962D01*
X73082Y705128D01*
X73373Y704753D01*
X73790Y704503D01*
X74165Y704420D01*
Y706170D01*
G01X72082Y707603D02*
X71832Y707853D01*
X71707Y708145D01*
X71665Y708478D01*
X71748Y708895D01*
X71957Y709187D01*
X72207Y709270D01*
X72457Y709228D01*
X72665Y709062D01*
X73082Y708228D01*
X73373Y707853D01*
X73790Y707603D01*
X74165Y707520D01*
Y709270D01*
G01X73873Y710787D02*
X74082Y711078D01*
X74165Y711412D01*
X74082Y711745D01*
X73832Y712037D01*
X73457Y712245D01*
X73082Y712328D01*
X72623D01*
X72248Y712245D01*
X71915Y712037D01*
X71748Y711787D01*
X71665Y711495D01*
X71748Y711162D01*
X71915Y710912D01*
X72165Y710745D01*
X72498Y710662D01*
X72790Y710745D01*
X73082Y710953D01*
X73248Y711203D01*
X73290Y711495D01*
X73207Y711828D01*
X72998Y712078D01*
X72623Y712328D01*
G01X100542Y707267D02*
X100417Y707017D01*
X100334Y706725D01*
Y706392D01*
X100459Y706017D01*
X100667Y705725D01*
X100917Y705517D01*
X101334Y705350D01*
X101709Y705308D01*
X102084Y705392D01*
X102334Y705517D01*
X102584Y705767D01*
X102751Y706058D01*
X102834Y706350D01*
Y706642D01*
X102751Y706933D01*
X102626Y707183D01*
X102459Y707392D01*
G01X102834Y709450D02*
X100334D01*
X100834Y708950D01*
G01X102834D02*
Y709950D01*
G01Y712550D02*
X102792Y712842D01*
X102667Y713175D01*
X102459Y713383D01*
X102167Y713467D01*
X101876Y713383D01*
X101626Y713133D01*
X101501Y712758D01*
Y712342D01*
X101417Y712092D01*
X101209Y711883D01*
X100917Y711800D01*
X100626Y711925D01*
X100417Y712217D01*
X100334Y712550D01*
X100417Y712883D01*
X100626Y713175D01*
X100917Y713300D01*
X101209Y713217D01*
X101417Y713008D01*
X101501Y712758D01*
Y712342D01*
X101626Y711967D01*
X101876Y711717D01*
X102167Y711633D01*
X102459Y711717D01*
X102667Y711925D01*
X102792Y712258D01*
X102834Y712550D01*
G01X100751Y714858D02*
X100501Y715108D01*
X100376Y715400D01*
X100334Y715733D01*
X100417Y716150D01*
X100626Y716442D01*
X100876Y716525D01*
X101126Y716483D01*
X101334Y716317D01*
X101751Y715483D01*
X102042Y715108D01*
X102459Y714858D01*
X102834Y714775D01*
Y716525D01*
G01X125564Y649898D02*
X125439Y649648D01*
X125356Y649356D01*
Y649023D01*
X125481Y648648D01*
X125689Y648356D01*
X125939Y648148D01*
X126356Y647981D01*
X126731Y647939D01*
X127106Y648023D01*
X127356Y648148D01*
X127606Y648398D01*
X127773Y648689D01*
X127856Y648981D01*
Y649273D01*
X127773Y649564D01*
X127648Y649814D01*
X127481Y650023D01*
G01X127856Y652081D02*
X125356D01*
X125856Y651581D01*
G01X127856D02*
Y652581D01*
G01X125356Y655181D02*
X125439Y654848D01*
X125648Y654598D01*
X125898Y654431D01*
X126231Y654306D01*
X126606Y654264D01*
X126981Y654306D01*
X127314Y654431D01*
X127564Y654598D01*
X127773Y654848D01*
X127856Y655181D01*
X127773Y655514D01*
X127564Y655764D01*
X127314Y655931D01*
X126981Y656056D01*
X126606Y656098D01*
X126231Y656056D01*
X125898Y655931D01*
X125648Y655764D01*
X125439Y655514D01*
X125356Y655181D01*
G01X125773Y657489D02*
X125523Y657739D01*
X125398Y658031D01*
X125356Y658364D01*
X125439Y658781D01*
X125648Y659073D01*
X125898Y659156D01*
X126148Y659114D01*
X126356Y658948D01*
X126773Y658114D01*
X127064Y657739D01*
X127481Y657489D01*
X127856Y657406D01*
Y659156D01*
G01X82550Y640446D02*
X75550D01*
G01X121169Y706045D02*
Y701045D01*
X126169D01*
G01X122176Y708939D02*
X119176D01*
G01X126700Y698250D02*
X127533D01*
Y697500D01*
X127283Y697250D01*
X126992Y697083D01*
X126575Y697000D01*
X126158Y697083D01*
X125867Y697250D01*
X125617Y697500D01*
X125450Y697792D01*
X125367Y698125D01*
Y698417D01*
X125450Y698667D01*
X125617Y698958D01*
X125867Y699208D01*
X126117Y699375D01*
X126450Y699500D01*
X126742D01*
X127075Y699417D01*
X127325Y699250D01*
G01X128633Y697500D02*
X128883Y697208D01*
X129217Y697042D01*
X129592Y697000D01*
X129925Y697042D01*
X130258Y697250D01*
X130467Y697500D01*
X130508Y697750D01*
X130425Y698042D01*
X130133Y698250D01*
X129842Y698333D01*
X129467D01*
G01X129842D02*
X130092Y698458D01*
X130300Y698667D01*
X130383Y698917D01*
X130300Y699167D01*
X130092Y699375D01*
X129717Y699500D01*
X129342Y699458D01*
X128967Y699292D01*
G01X79564Y674700D02*
Y679700D01*
X74564D01*
G01X70832Y653407D02*
Y650407D01*
G01X78157Y670968D02*
X80157D01*
G01X132000Y652617D02*
X134500D01*
Y654283D01*
G01X134125Y655633D02*
X134333Y655883D01*
X134458Y656175D01*
X134500Y656550D01*
X134417Y656925D01*
X134250Y657217D01*
X133958Y657425D01*
X133625Y657467D01*
X133292Y657383D01*
X133083Y657175D01*
X132917Y656883D01*
X132875Y656592D01*
X132917Y656300D01*
X133083Y655925D01*
X132000Y656050D01*
Y657175D01*
G01X141867Y745559D02*
X141617Y745684D01*
X141325Y745767D01*
X140992D01*
X140617Y745642D01*
X140325Y745434D01*
X140117Y745184D01*
X139950Y744767D01*
X139908Y744392D01*
X139992Y744017D01*
X140117Y743767D01*
X140367Y743517D01*
X140658Y743350D01*
X140950Y743267D01*
X141242D01*
X141533Y743350D01*
X141783Y743475D01*
X141992Y743642D01*
G01X144050Y743267D02*
Y745767D01*
X143550Y745267D01*
G01Y743267D02*
X144550D01*
G01X147150D02*
X147442Y743309D01*
X147775Y743434D01*
X147983Y743642D01*
X148067Y743934D01*
X147983Y744225D01*
X147733Y744475D01*
X147358Y744600D01*
X146942D01*
X146692Y744684D01*
X146483Y744892D01*
X146400Y745184D01*
X146525Y745475D01*
X146817Y745684D01*
X147150Y745767D01*
X147483Y745684D01*
X147775Y745475D01*
X147900Y745184D01*
X147817Y744892D01*
X147608Y744684D01*
X147358Y744600D01*
X146942D01*
X146567Y744475D01*
X146317Y744225D01*
X146233Y743934D01*
X146317Y743642D01*
X146525Y743434D01*
X146858Y743309D01*
X147150Y743267D01*
G01X150250Y745767D02*
X149917Y745684D01*
X149667Y745475D01*
X149500Y745225D01*
X149375Y744892D01*
X149333Y744517D01*
X149375Y744142D01*
X149500Y743809D01*
X149667Y743559D01*
X149917Y743350D01*
X150250Y743267D01*
X150583Y743350D01*
X150833Y743559D01*
X151000Y743809D01*
X151125Y744142D01*
X151167Y744517D01*
X151125Y744892D01*
X151000Y745225D01*
X150833Y745475D01*
X150583Y745684D01*
X150250Y745767D01*
G01X107027Y749022D02*
X106777Y749147D01*
X106485Y749230D01*
X106152D01*
X105777Y749105D01*
X105485Y748897D01*
X105277Y748647D01*
X105110Y748230D01*
X105068Y747855D01*
X105152Y747480D01*
X105277Y747230D01*
X105527Y746980D01*
X105818Y746813D01*
X106110Y746730D01*
X106402D01*
X106693Y746813D01*
X106943Y746938D01*
X107152Y747105D01*
G01X109210Y746730D02*
Y749230D01*
X108710Y748730D01*
G01Y746730D02*
X109710D01*
G01X112227D02*
X112310Y747272D01*
X112435Y747730D01*
X112602Y748147D01*
X112810Y748605D01*
X113143Y749230D01*
X111477D01*
G01X115327Y746730D02*
X115410Y747272D01*
X115535Y747730D01*
X115702Y748147D01*
X115910Y748605D01*
X116243Y749230D01*
X114577D01*
G01X103957Y752792D02*
X103707Y752917D01*
X103415Y753000D01*
X103082D01*
X102707Y752875D01*
X102415Y752667D01*
X102207Y752417D01*
X102040Y752000D01*
X101998Y751625D01*
X102082Y751250D01*
X102207Y751000D01*
X102457Y750750D01*
X102748Y750583D01*
X103040Y750500D01*
X103332D01*
X103623Y750583D01*
X103873Y750708D01*
X104082Y750875D01*
G01X106140Y750500D02*
Y753000D01*
X105640Y752500D01*
G01Y750500D02*
X106640D01*
G01X109157D02*
X109240Y751042D01*
X109365Y751500D01*
X109532Y751917D01*
X109740Y752375D01*
X110073Y753000D01*
X108407D01*
G01X111548Y751542D02*
X111840Y751833D01*
X112090Y752000D01*
X112423Y752083D01*
X112715Y752000D01*
X112923Y751833D01*
X113090Y751583D01*
X113132Y751292D01*
X113090Y751042D01*
X112923Y750792D01*
X112673Y750583D01*
X112382Y750500D01*
X112048Y750583D01*
X111757Y750833D01*
X111590Y751208D01*
X111548Y751625D01*
X111632Y752167D01*
X111757Y752458D01*
X111965Y752750D01*
X112257Y752958D01*
X112548Y753000D01*
X112840Y752917D01*
X113048Y752708D01*
G01X120477Y752342D02*
X120227Y752467D01*
X119935Y752550D01*
X119602D01*
X119227Y752425D01*
X118935Y752217D01*
X118727Y751967D01*
X118560Y751550D01*
X118518Y751175D01*
X118602Y750800D01*
X118727Y750550D01*
X118977Y750300D01*
X119268Y750133D01*
X119560Y750050D01*
X119852D01*
X120143Y750133D01*
X120393Y750258D01*
X120602Y750425D01*
G01X122660Y750050D02*
Y752550D01*
X122160Y752050D01*
G01Y750050D02*
X123160D01*
G01X125677D02*
X125760Y750592D01*
X125885Y751050D01*
X126052Y751467D01*
X126260Y751925D01*
X126593Y752550D01*
X124927D01*
G01X127943Y750550D02*
X128193Y750258D01*
X128527Y750092D01*
X128902Y750050D01*
X129235Y750092D01*
X129568Y750300D01*
X129777Y750550D01*
X129818Y750800D01*
X129735Y751092D01*
X129443Y751300D01*
X129152Y751383D01*
X128777D01*
G01X129152D02*
X129402Y751508D01*
X129610Y751717D01*
X129693Y751967D01*
X129610Y752217D01*
X129402Y752425D01*
X129027Y752550D01*
X128652Y752508D01*
X128277Y752342D01*
G01X88267Y752792D02*
X88017Y752917D01*
X87725Y753000D01*
X87392D01*
X87017Y752875D01*
X86725Y752667D01*
X86517Y752417D01*
X86350Y752000D01*
X86308Y751625D01*
X86392Y751250D01*
X86517Y751000D01*
X86767Y750750D01*
X87058Y750583D01*
X87350Y750500D01*
X87642D01*
X87933Y750583D01*
X88183Y750708D01*
X88392Y750875D01*
G01X90450Y750500D02*
Y753000D01*
X89950Y752500D01*
G01Y750500D02*
X90950D01*
G01X93467D02*
X93550Y751042D01*
X93675Y751500D01*
X93842Y751917D01*
X94050Y752375D01*
X94383Y753000D01*
X92717D01*
G01X96650Y750500D02*
Y753000D01*
X96150Y752500D01*
G01Y750500D02*
X97150D01*
G01X91767Y749292D02*
X91517Y749417D01*
X91225Y749500D01*
X90892D01*
X90517Y749375D01*
X90225Y749167D01*
X90017Y748917D01*
X89850Y748500D01*
X89808Y748125D01*
X89892Y747750D01*
X90017Y747500D01*
X90267Y747250D01*
X90558Y747083D01*
X90850Y747000D01*
X91142D01*
X91433Y747083D01*
X91683Y747208D01*
X91892Y747375D01*
G01X93950Y747000D02*
Y749500D01*
X93450Y749000D01*
G01Y747000D02*
X94450D01*
G01X96967D02*
X97050Y747542D01*
X97175Y748000D01*
X97342Y748417D01*
X97550Y748875D01*
X97883Y749500D01*
X96217D01*
G01X100150D02*
X99817Y749417D01*
X99567Y749208D01*
X99400Y748958D01*
X99275Y748625D01*
X99233Y748250D01*
X99275Y747875D01*
X99400Y747542D01*
X99567Y747292D01*
X99817Y747083D01*
X100150Y747000D01*
X100483Y747083D01*
X100733Y747292D01*
X100900Y747542D01*
X101025Y747875D01*
X101067Y748250D01*
X101025Y748625D01*
X100900Y748958D01*
X100733Y749208D01*
X100483Y749417D01*
X100150Y749500D01*
G01X76617Y723000D02*
Y720500D01*
X78283D01*
G01X80550D02*
X80842Y720542D01*
X81175Y720667D01*
X81383Y720875D01*
X81467Y721167D01*
X81383Y721458D01*
X81133Y721708D01*
X80758Y721833D01*
X80342D01*
X80092Y721917D01*
X79883Y722125D01*
X79800Y722417D01*
X79925Y722708D01*
X80217Y722917D01*
X80550Y723000D01*
X80883Y722917D01*
X81175Y722708D01*
X81300Y722417D01*
X81217Y722125D01*
X81008Y721917D01*
X80758Y721833D01*
X80342D01*
X79967Y721708D01*
X79717Y721458D01*
X79633Y721167D01*
X79717Y720875D01*
X79925Y720667D01*
X80258Y720542D01*
X80550Y720500D01*
G01X98400Y726300D02*
X85000D01*
G01X98400Y719100D02*
Y726300D01*
G01X85000Y719100D02*
X98400D01*
G01X85000Y726300D02*
Y719100D01*
G01X126017Y746070D02*
Y748570D01*
X127058D01*
X127392Y748445D01*
X127600Y748278D01*
X127683Y747945D01*
X127600Y747612D01*
X127350Y747403D01*
X127058Y747278D01*
X126017D01*
G01X127058D02*
X127683Y746070D01*
G01X130450D02*
Y748570D01*
X128908Y746778D01*
X130992D01*
G01X132342Y746362D02*
X132633Y746153D01*
X132967Y746070D01*
X133300Y746153D01*
X133592Y746403D01*
X133800Y746778D01*
X133883Y747153D01*
Y747612D01*
X133800Y747987D01*
X133592Y748320D01*
X133342Y748487D01*
X133050Y748570D01*
X132717Y748487D01*
X132467Y748320D01*
X132300Y748070D01*
X132217Y747737D01*
X132300Y747445D01*
X132508Y747153D01*
X132758Y746987D01*
X133050Y746945D01*
X133383Y747028D01*
X133633Y747237D01*
X133883Y747612D01*
G01X136150Y748570D02*
X135817Y748487D01*
X135567Y748278D01*
X135400Y748028D01*
X135275Y747695D01*
X135233Y747320D01*
X135275Y746945D01*
X135400Y746612D01*
X135567Y746362D01*
X135817Y746153D01*
X136150Y746070D01*
X136483Y746153D01*
X136733Y746362D01*
X136900Y746612D01*
X137025Y746945D01*
X137067Y747320D01*
X137025Y747695D01*
X136900Y748028D01*
X136733Y748278D01*
X136483Y748487D01*
X136150Y748570D01*
G01X136151Y742915D02*
Y737715D01*
G01X129151Y742915D02*
Y735115D01*
G01X136151Y742915D02*
X129151D01*
G01X136151Y729515D02*
Y738215D01*
G01X129151Y729515D02*
X136151D01*
G01X129151Y735915D02*
Y729515D01*
G01X139567Y729500D02*
Y732000D01*
X140567D01*
X140900Y731875D01*
X141150Y731583D01*
X141233Y731250D01*
X141150Y730917D01*
X140942Y730667D01*
X140567Y730542D01*
X139567D01*
G01X142583Y732000D02*
Y730208D01*
X142750Y729833D01*
X143083Y729583D01*
X143500Y729500D01*
X143917Y729583D01*
X144250Y729833D01*
X144417Y730208D01*
Y732000D01*
G01X145808Y731583D02*
X146058Y731833D01*
X146350Y731958D01*
X146683Y732000D01*
X147100Y731917D01*
X147392Y731708D01*
X147475Y731458D01*
X147433Y731208D01*
X147267Y731000D01*
X146433Y730583D01*
X146058Y730292D01*
X145808Y729875D01*
X145725Y729500D01*
X147475D01*
G01X126169Y728645D02*
X121169D01*
Y723645D01*
G01X122176Y718782D02*
X120176D01*
G01X189541Y459538D02*
X189291Y459663D01*
X188999Y459746D01*
X188666D01*
X188291Y459621D01*
X187999Y459413D01*
X187791Y459163D01*
X187624Y458746D01*
X187582Y458371D01*
X187666Y457996D01*
X187791Y457746D01*
X188041Y457496D01*
X188332Y457329D01*
X188624Y457246D01*
X188916D01*
X189207Y457329D01*
X189457Y457454D01*
X189666Y457621D01*
G01X190807Y457746D02*
X191057Y457454D01*
X191391Y457288D01*
X191766Y457246D01*
X192099Y457288D01*
X192432Y457496D01*
X192641Y457746D01*
X192682Y457996D01*
X192599Y458288D01*
X192307Y458496D01*
X192016Y458579D01*
X191641D01*
G01X192016D02*
X192266Y458704D01*
X192474Y458913D01*
X192557Y459163D01*
X192474Y459413D01*
X192266Y459621D01*
X191891Y459746D01*
X191516Y459704D01*
X191141Y459538D01*
G01X194032Y458288D02*
X194324Y458579D01*
X194574Y458746D01*
X194907Y458829D01*
X195199Y458746D01*
X195407Y458579D01*
X195574Y458329D01*
X195616Y458038D01*
X195574Y457788D01*
X195407Y457538D01*
X195157Y457329D01*
X194866Y457246D01*
X194532Y457329D01*
X194241Y457579D01*
X194074Y457954D01*
X194032Y458371D01*
X194116Y458913D01*
X194241Y459204D01*
X194449Y459496D01*
X194741Y459704D01*
X195032Y459746D01*
X195324Y459663D01*
X195532Y459454D01*
G01X176588Y495113D02*
X172588D01*
Y487713D01*
G01X187791Y453246D02*
Y455746D01*
X188832D01*
X189166Y455621D01*
X189374Y455454D01*
X189457Y455121D01*
X189374Y454788D01*
X189124Y454579D01*
X188832Y454454D01*
X187791D01*
G01X188832D02*
X189457Y453246D01*
G01X191724D02*
X192016Y453288D01*
X192349Y453413D01*
X192557Y453621D01*
X192641Y453913D01*
X192557Y454204D01*
X192307Y454454D01*
X191932Y454579D01*
X191516D01*
X191266Y454663D01*
X191057Y454871D01*
X190974Y455163D01*
X191099Y455454D01*
X191391Y455663D01*
X191724Y455746D01*
X192057Y455663D01*
X192349Y455454D01*
X192474Y455163D01*
X192391Y454871D01*
X192182Y454663D01*
X191932Y454579D01*
X191516D01*
X191141Y454454D01*
X190891Y454204D01*
X190807Y453913D01*
X190891Y453621D01*
X191099Y453413D01*
X191432Y453288D01*
X191724Y453246D01*
G01X194032Y454288D02*
X194324Y454579D01*
X194574Y454746D01*
X194907Y454829D01*
X195199Y454746D01*
X195407Y454579D01*
X195574Y454329D01*
X195616Y454038D01*
X195574Y453788D01*
X195407Y453538D01*
X195157Y453329D01*
X194866Y453246D01*
X194532Y453329D01*
X194241Y453579D01*
X194074Y453954D01*
X194032Y454371D01*
X194116Y454913D01*
X194241Y455204D01*
X194449Y455496D01*
X194741Y455704D01*
X195032Y455746D01*
X195324Y455663D01*
X195532Y455454D01*
G01X184463Y457780D02*
Y461780D01*
X177063D01*
G01X186528Y468821D02*
Y471321D01*
X187569D01*
X187903Y471196D01*
X188111Y471029D01*
X188194Y470696D01*
X188111Y470363D01*
X187861Y470154D01*
X187569Y470029D01*
X186528D01*
G01X187569D02*
X188194Y468821D01*
G01X190461D02*
X190753Y468863D01*
X191086Y468988D01*
X191294Y469196D01*
X191378Y469488D01*
X191294Y469779D01*
X191044Y470029D01*
X190669Y470154D01*
X190253D01*
X190003Y470238D01*
X189794Y470446D01*
X189711Y470738D01*
X189836Y471029D01*
X190128Y471238D01*
X190461Y471321D01*
X190794Y471238D01*
X191086Y471029D01*
X191211Y470738D01*
X191128Y470446D01*
X190919Y470238D01*
X190669Y470154D01*
X190253D01*
X189878Y470029D01*
X189628Y469779D01*
X189544Y469488D01*
X189628Y469196D01*
X189836Y468988D01*
X190169Y468863D01*
X190461Y468821D01*
G01X192644Y469321D02*
X192894Y469029D01*
X193228Y468863D01*
X193603Y468821D01*
X193936Y468863D01*
X194269Y469071D01*
X194478Y469321D01*
X194519Y469571D01*
X194436Y469863D01*
X194144Y470071D01*
X193853Y470154D01*
X193478D01*
G01X193853D02*
X194103Y470279D01*
X194311Y470488D01*
X194394Y470738D01*
X194311Y470988D01*
X194103Y471196D01*
X193728Y471321D01*
X193353Y471279D01*
X192978Y471113D01*
G01X184463Y467880D02*
Y471880D01*
X177063D01*
G01X202017Y476500D02*
Y479000D01*
X203058D01*
X203392Y478875D01*
X203600Y478708D01*
X203683Y478375D01*
X203600Y478042D01*
X203350Y477833D01*
X203058Y477708D01*
X202017D01*
G01X203058D02*
X203683Y476500D01*
G01X205158Y478583D02*
X205408Y478833D01*
X205700Y478958D01*
X206033Y479000D01*
X206450Y478917D01*
X206742Y478708D01*
X206825Y478458D01*
X206783Y478208D01*
X206617Y478000D01*
X205783Y477583D01*
X205408Y477292D01*
X205158Y476875D01*
X205075Y476500D01*
X206825D01*
G01X208258Y477542D02*
X208550Y477833D01*
X208800Y478000D01*
X209133Y478083D01*
X209425Y478000D01*
X209633Y477833D01*
X209800Y477583D01*
X209842Y477292D01*
X209800Y477042D01*
X209633Y476792D01*
X209383Y476583D01*
X209092Y476500D01*
X208758Y476583D01*
X208467Y476833D01*
X208300Y477208D01*
X208258Y477625D01*
X208342Y478167D01*
X208467Y478458D01*
X208675Y478750D01*
X208967Y478958D01*
X209258Y479000D01*
X209550Y478917D01*
X209758Y478708D01*
G01X211442Y476792D02*
X211733Y476583D01*
X212067Y476500D01*
X212400Y476583D01*
X212692Y476833D01*
X212900Y477208D01*
X212983Y477583D01*
Y478042D01*
X212900Y478417D01*
X212692Y478750D01*
X212442Y478917D01*
X212150Y479000D01*
X211817Y478917D01*
X211567Y478750D01*
X211400Y478500D01*
X211317Y478167D01*
X211400Y477875D01*
X211608Y477583D01*
X211858Y477417D01*
X212150Y477375D01*
X212483Y477458D01*
X212733Y477667D01*
X212983Y478042D01*
G01X206700Y497300D02*
Y493300D01*
X214100D01*
G01X194735Y487740D02*
X192235D01*
Y488781D01*
X192360Y489115D01*
X192527Y489323D01*
X192860Y489406D01*
X193193Y489323D01*
X193402Y489073D01*
X193527Y488781D01*
Y487740D01*
G01Y488781D02*
X194735Y489406D01*
G01X192652Y490881D02*
X192402Y491131D01*
X192277Y491423D01*
X192235Y491756D01*
X192318Y492173D01*
X192527Y492465D01*
X192777Y492548D01*
X193027Y492506D01*
X193235Y492340D01*
X193652Y491506D01*
X193943Y491131D01*
X194360Y490881D01*
X194735Y490798D01*
Y492548D01*
G01X192235Y494773D02*
X192318Y494440D01*
X192527Y494190D01*
X192777Y494023D01*
X193110Y493898D01*
X193485Y493856D01*
X193860Y493898D01*
X194193Y494023D01*
X194443Y494190D01*
X194652Y494440D01*
X194735Y494773D01*
X194652Y495106D01*
X194443Y495356D01*
X194193Y495523D01*
X193860Y495648D01*
X193485Y495690D01*
X193110Y495648D01*
X192777Y495523D01*
X192527Y495356D01*
X192318Y495106D01*
X192235Y494773D01*
G01Y497873D02*
X192318Y497540D01*
X192527Y497290D01*
X192777Y497123D01*
X193110Y496998D01*
X193485Y496956D01*
X193860Y496998D01*
X194193Y497123D01*
X194443Y497290D01*
X194652Y497540D01*
X194735Y497873D01*
X194652Y498206D01*
X194443Y498456D01*
X194193Y498623D01*
X193860Y498748D01*
X193485Y498790D01*
X193110Y498748D01*
X192777Y498623D01*
X192527Y498456D01*
X192318Y498206D01*
X192235Y497873D01*
G01X198435Y487740D02*
X195935D01*
Y488781D01*
X196060Y489115D01*
X196227Y489323D01*
X196560Y489406D01*
X196893Y489323D01*
X197102Y489073D01*
X197227Y488781D01*
Y487740D01*
G01Y488781D02*
X198435Y489406D01*
G01Y491673D02*
X198393Y491965D01*
X198268Y492298D01*
X198060Y492506D01*
X197768Y492590D01*
X197477Y492506D01*
X197227Y492256D01*
X197102Y491881D01*
Y491465D01*
X197018Y491215D01*
X196810Y491006D01*
X196518Y490923D01*
X196227Y491048D01*
X196018Y491340D01*
X195935Y491673D01*
X196018Y492006D01*
X196227Y492298D01*
X196518Y492423D01*
X196810Y492340D01*
X197018Y492131D01*
X197102Y491881D01*
Y491465D01*
X197227Y491090D01*
X197477Y490840D01*
X197768Y490756D01*
X198060Y490840D01*
X198268Y491048D01*
X198393Y491381D01*
X198435Y491673D01*
G01Y494773D02*
X198393Y495065D01*
X198268Y495398D01*
X198060Y495606D01*
X197768Y495690D01*
X197477Y495606D01*
X197227Y495356D01*
X197102Y494981D01*
Y494565D01*
X197018Y494315D01*
X196810Y494106D01*
X196518Y494023D01*
X196227Y494148D01*
X196018Y494440D01*
X195935Y494773D01*
X196018Y495106D01*
X196227Y495398D01*
X196518Y495523D01*
X196810Y495440D01*
X197018Y495231D01*
X197102Y494981D01*
Y494565D01*
X197227Y494190D01*
X197477Y493940D01*
X197768Y493856D01*
X198060Y493940D01*
X198268Y494148D01*
X198393Y494481D01*
X198435Y494773D01*
G01X202135Y487740D02*
X199635D01*
Y488781D01*
X199760Y489115D01*
X199927Y489323D01*
X200260Y489406D01*
X200593Y489323D01*
X200802Y489073D01*
X200927Y488781D01*
Y487740D01*
G01Y488781D02*
X202135Y489406D01*
G01X200052Y490881D02*
X199802Y491131D01*
X199677Y491423D01*
X199635Y491756D01*
X199718Y492173D01*
X199927Y492465D01*
X200177Y492548D01*
X200427Y492506D01*
X200635Y492340D01*
X201052Y491506D01*
X201343Y491131D01*
X201760Y490881D01*
X202135Y490798D01*
Y492548D01*
G01Y494773D02*
X202093Y495065D01*
X201968Y495398D01*
X201760Y495606D01*
X201468Y495690D01*
X201177Y495606D01*
X200927Y495356D01*
X200802Y494981D01*
Y494565D01*
X200718Y494315D01*
X200510Y494106D01*
X200218Y494023D01*
X199927Y494148D01*
X199718Y494440D01*
X199635Y494773D01*
X199718Y495106D01*
X199927Y495398D01*
X200218Y495523D01*
X200510Y495440D01*
X200718Y495231D01*
X200802Y494981D01*
Y494565D01*
X200927Y494190D01*
X201177Y493940D01*
X201468Y493856D01*
X201760Y493940D01*
X201968Y494148D01*
X202093Y494481D01*
X202135Y494773D01*
G01Y497790D02*
X201593Y497873D01*
X201135Y497998D01*
X200718Y498165D01*
X200260Y498373D01*
X199635Y498706D01*
Y497040D01*
G01X186528Y472821D02*
Y475321D01*
X187569D01*
X187903Y475196D01*
X188111Y475029D01*
X188194Y474696D01*
X188111Y474363D01*
X187861Y474154D01*
X187569Y474029D01*
X186528D01*
G01X187569D02*
X188194Y472821D01*
G01X190378D02*
X190461Y473363D01*
X190586Y473821D01*
X190753Y474238D01*
X190961Y474696D01*
X191294Y475321D01*
X189628D01*
G01X192769Y473863D02*
X193061Y474154D01*
X193311Y474321D01*
X193644Y474404D01*
X193936Y474321D01*
X194144Y474154D01*
X194311Y473904D01*
X194353Y473613D01*
X194311Y473363D01*
X194144Y473113D01*
X193894Y472904D01*
X193603Y472821D01*
X193269Y472904D01*
X192978Y473154D01*
X192811Y473529D01*
X192769Y473946D01*
X192853Y474488D01*
X192978Y474779D01*
X193186Y475071D01*
X193478Y475279D01*
X193769Y475321D01*
X194061Y475238D01*
X194269Y475029D01*
G01X195744Y473196D02*
X195994Y472988D01*
X196286Y472863D01*
X196661Y472821D01*
X197036Y472904D01*
X197328Y473071D01*
X197536Y473363D01*
X197578Y473696D01*
X197494Y474029D01*
X197286Y474238D01*
X196994Y474404D01*
X196703Y474446D01*
X196411Y474404D01*
X196036Y474238D01*
X196161Y475321D01*
X197286D01*
G01X177039Y476031D02*
Y472031D01*
X184439D01*
G01X180985Y484519D02*
X178485D01*
Y485560D01*
X178610Y485894D01*
X178777Y486102D01*
X179110Y486185D01*
X179443Y486102D01*
X179652Y485852D01*
X179777Y485560D01*
Y484519D01*
G01Y485560D02*
X180985Y486185D01*
G01X178902Y487660D02*
X178652Y487910D01*
X178527Y488202D01*
X178485Y488535D01*
X178568Y488952D01*
X178777Y489244D01*
X179027Y489327D01*
X179277Y489285D01*
X179485Y489119D01*
X179902Y488285D01*
X180193Y487910D01*
X180610Y487660D01*
X180985Y487577D01*
Y489327D01*
G01X180693Y490844D02*
X180902Y491135D01*
X180985Y491469D01*
X180902Y491802D01*
X180652Y492094D01*
X180277Y492302D01*
X179902Y492385D01*
X179443D01*
X179068Y492302D01*
X178735Y492094D01*
X178568Y491844D01*
X178485Y491552D01*
X178568Y491219D01*
X178735Y490969D01*
X178985Y490802D01*
X179318Y490719D01*
X179610Y490802D01*
X179902Y491010D01*
X180068Y491260D01*
X180110Y491552D01*
X180027Y491885D01*
X179818Y492135D01*
X179443Y492385D01*
G01X179943Y493860D02*
X179652Y494152D01*
X179485Y494402D01*
X179402Y494735D01*
X179485Y495027D01*
X179652Y495235D01*
X179902Y495402D01*
X180193Y495444D01*
X180443Y495402D01*
X180693Y495235D01*
X180902Y494985D01*
X180985Y494694D01*
X180902Y494360D01*
X180652Y494069D01*
X180277Y493902D01*
X179860Y493860D01*
X179318Y493944D01*
X179027Y494069D01*
X178735Y494277D01*
X178527Y494569D01*
X178485Y494860D01*
X178568Y495152D01*
X178777Y495360D01*
G01X182924Y487748D02*
X186924D01*
Y495148D01*
G01X191035Y487740D02*
X188535D01*
Y488781D01*
X188660Y489115D01*
X188827Y489323D01*
X189160Y489406D01*
X189493Y489323D01*
X189702Y489073D01*
X189827Y488781D01*
Y487740D01*
G01Y488781D02*
X191035Y489406D01*
G01X188952Y490881D02*
X188702Y491131D01*
X188577Y491423D01*
X188535Y491756D01*
X188618Y492173D01*
X188827Y492465D01*
X189077Y492548D01*
X189327Y492506D01*
X189535Y492340D01*
X189952Y491506D01*
X190243Y491131D01*
X190660Y490881D01*
X191035Y490798D01*
Y492548D01*
G01Y494690D02*
X190493Y494773D01*
X190035Y494898D01*
X189618Y495065D01*
X189160Y495273D01*
X188535Y495606D01*
Y493940D01*
G01X191035Y498373D02*
X188535D01*
X190327Y496831D01*
Y498915D01*
G01X212500Y480517D02*
X210000D01*
Y481558D01*
X210125Y481892D01*
X210292Y482100D01*
X210625Y482183D01*
X210958Y482100D01*
X211167Y481850D01*
X211292Y481558D01*
Y480517D01*
G01Y481558D02*
X212500Y482183D01*
G01X211458Y483658D02*
X211167Y483950D01*
X211000Y484200D01*
X210917Y484533D01*
X211000Y484825D01*
X211167Y485033D01*
X211417Y485200D01*
X211708Y485242D01*
X211958Y485200D01*
X212208Y485033D01*
X212417Y484783D01*
X212500Y484492D01*
X212417Y484158D01*
X212167Y483867D01*
X211792Y483700D01*
X211375Y483658D01*
X210833Y483742D01*
X210542Y483867D01*
X210250Y484075D01*
X210042Y484367D01*
X210000Y484658D01*
X210083Y484950D01*
X210292Y485158D01*
G01X212500Y487550D02*
X210000D01*
X210500Y487050D01*
G01X212500D02*
Y488050D01*
G01X210000Y490650D02*
X210083Y490317D01*
X210292Y490067D01*
X210542Y489900D01*
X210875Y489775D01*
X211250Y489733D01*
X211625Y489775D01*
X211958Y489900D01*
X212208Y490067D01*
X212417Y490317D01*
X212500Y490650D01*
X212417Y490983D01*
X212208Y491233D01*
X211958Y491400D01*
X211625Y491525D01*
X211250Y491567D01*
X210875Y491525D01*
X210542Y491400D01*
X210292Y491233D01*
X210083Y490983D01*
X210000Y490650D01*
G01X201883Y450800D02*
Y449008D01*
X202050Y448633D01*
X202383Y448383D01*
X202800Y448300D01*
X203217Y448383D01*
X203550Y448633D01*
X203717Y449008D01*
Y450800D01*
G01X205108Y450383D02*
X205358Y450633D01*
X205650Y450758D01*
X205983Y450800D01*
X206400Y450717D01*
X206692Y450508D01*
X206775Y450258D01*
X206733Y450008D01*
X206567Y449800D01*
X205733Y449383D01*
X205358Y449092D01*
X205108Y448675D01*
X205025Y448300D01*
X206775D01*
G01X208292Y448592D02*
X208583Y448383D01*
X208917Y448300D01*
X209250Y448383D01*
X209542Y448633D01*
X209750Y449008D01*
X209833Y449383D01*
Y449842D01*
X209750Y450217D01*
X209542Y450550D01*
X209292Y450717D01*
X209000Y450800D01*
X208667Y450717D01*
X208417Y450550D01*
X208250Y450300D01*
X208167Y449967D01*
X208250Y449675D01*
X208458Y449383D01*
X208708Y449217D01*
X209000Y449175D01*
X209333Y449258D01*
X209583Y449467D01*
X209833Y449842D01*
G01X142865Y457770D02*
X144835Y455800D01*
G01X140895D02*
X142865Y457770D01*
G01X155565Y496500D02*
Y455800D01*
G01X200875Y453133D02*
X201208Y452925D01*
X201583Y452800D01*
X201917D01*
X202250Y452925D01*
X202500Y453133D01*
X202625Y453425D01*
X202542Y453717D01*
X202333Y453967D01*
X201958Y454133D01*
X201458Y454217D01*
X201167Y454383D01*
X201042Y454675D01*
X201125Y454967D01*
X201333Y455175D01*
X201625Y455300D01*
X201917D01*
X202208Y455217D01*
X202458Y455008D01*
G01X203933Y452800D02*
Y455300D01*
G01X205517D02*
X203933Y453758D01*
G01X205767Y452800D02*
X204642Y454467D01*
G01X207950Y455300D02*
Y452800D01*
G01X206992Y455300D02*
X208908D01*
G01X210258Y454883D02*
X210508Y455133D01*
X210800Y455258D01*
X211133Y455300D01*
X211550Y455217D01*
X211842Y455008D01*
X211925Y454758D01*
X211883Y454508D01*
X211717Y454300D01*
X210883Y453883D01*
X210508Y453592D01*
X210258Y453175D01*
X210175Y452800D01*
X211925D01*
G01X150067Y527400D02*
X150600Y527750D01*
X151000Y528334D01*
X151267Y529150D01*
X151000Y529850D01*
X150467Y530317D01*
X149533Y530667D01*
X145933D01*
Y523667D01*
X150333D01*
X151267Y524134D01*
X151800Y524834D01*
X152067Y525650D01*
X151800Y526467D01*
X151000Y527167D01*
X150067Y527400D01*
X145933D01*
G01X185422Y523500D02*
X194096D01*
G01X219100Y509994D02*
X207001D01*
X207000Y509993D01*
Y508000D01*
X199000D01*
Y510000D01*
X171000D01*
Y512000D01*
X148500D01*
Y510000D01*
X145000D01*
G01X202000Y523500D02*
X209000D01*
Y528797D01*
X226500D01*
Y547400D01*
G01X174887Y497681D02*
X172387D01*
Y498722D01*
X172512Y499056D01*
X172679Y499264D01*
X173012Y499347D01*
X173345Y499264D01*
X173554Y499014D01*
X173679Y498722D01*
Y497681D01*
G01Y498722D02*
X174887Y499347D01*
G01Y501614D02*
X174845Y501906D01*
X174720Y502239D01*
X174512Y502447D01*
X174220Y502531D01*
X173929Y502447D01*
X173679Y502197D01*
X173554Y501822D01*
Y501406D01*
X173470Y501156D01*
X173262Y500947D01*
X172970Y500864D01*
X172679Y500989D01*
X172470Y501281D01*
X172387Y501614D01*
X172470Y501947D01*
X172679Y502239D01*
X172970Y502364D01*
X173262Y502281D01*
X173470Y502072D01*
X173554Y501822D01*
Y501406D01*
X173679Y501031D01*
X173929Y500781D01*
X174220Y500697D01*
X174512Y500781D01*
X174720Y500989D01*
X174845Y501322D01*
X174887Y501614D01*
G01X174595Y504006D02*
X174804Y504297D01*
X174887Y504631D01*
X174804Y504964D01*
X174554Y505256D01*
X174179Y505464D01*
X173804Y505547D01*
X173345D01*
X172970Y505464D01*
X172637Y505256D01*
X172470Y505006D01*
X172387Y504714D01*
X172470Y504381D01*
X172637Y504131D01*
X172887Y503964D01*
X173220Y503881D01*
X173512Y503964D01*
X173804Y504172D01*
X173970Y504422D01*
X174012Y504714D01*
X173929Y505047D01*
X173720Y505297D01*
X173345Y505547D01*
G01X144292Y521686D02*
Y517686D01*
X151692D01*
G01X155896Y513919D02*
X159896D01*
Y521319D01*
G01X144292Y517686D02*
Y513686D01*
X151692D01*
G01X159902Y513949D02*
X163902D01*
Y521349D01*
G01X184537Y513981D02*
X188537D01*
Y521381D01*
G01X180474Y515291D02*
X184474D01*
Y522691D01*
G01X164280Y515000D02*
X168280D01*
Y522400D01*
G01X189167Y508384D02*
X185167D01*
Y500984D01*
G01X168380Y515000D02*
X172380D01*
Y522400D01*
G01X189400Y500400D02*
X193400D01*
Y507800D01*
G01X205067Y504500D02*
Y507000D01*
X206108D01*
X206442Y506875D01*
X206650Y506708D01*
X206733Y506375D01*
X206650Y506042D01*
X206400Y505833D01*
X206108Y505708D01*
X205067D01*
G01X206108D02*
X206733Y504500D01*
G01X209000D02*
X209292Y504542D01*
X209625Y504667D01*
X209833Y504875D01*
X209917Y505167D01*
X209833Y505458D01*
X209583Y505708D01*
X209208Y505833D01*
X208792D01*
X208542Y505917D01*
X208333Y506125D01*
X208250Y506417D01*
X208375Y506708D01*
X208667Y506917D01*
X209000Y507000D01*
X209333Y506917D01*
X209625Y506708D01*
X209750Y506417D01*
X209667Y506125D01*
X209458Y505917D01*
X209208Y505833D01*
X208792D01*
X208417Y505708D01*
X208167Y505458D01*
X208083Y505167D01*
X208167Y504875D01*
X208375Y504667D01*
X208708Y504542D01*
X209000Y504500D01*
G01X212017D02*
X212100Y505042D01*
X212225Y505500D01*
X212392Y505917D01*
X212600Y506375D01*
X212933Y507000D01*
X211267D01*
G01X197900Y505300D02*
Y501300D01*
X205300D01*
G01X200700Y522300D02*
X196700D01*
Y514900D01*
G01X205500Y522300D02*
X201500D01*
Y514900D01*
G01X214600Y522400D02*
X210600D01*
Y515000D01*
G01X148952Y535240D02*
X146452D01*
Y536281D01*
X146577Y536615D01*
X146744Y536823D01*
X147077Y536906D01*
X147410Y536823D01*
X147619Y536573D01*
X147744Y536281D01*
Y535240D01*
G01Y536281D02*
X148952Y536906D01*
G01X148452Y538256D02*
X148744Y538506D01*
X148910Y538840D01*
X148952Y539215D01*
X148910Y539548D01*
X148702Y539881D01*
X148452Y540090D01*
X148202Y540131D01*
X147910Y540048D01*
X147702Y539756D01*
X147619Y539465D01*
Y539090D01*
G01Y539465D02*
X147494Y539715D01*
X147285Y539923D01*
X147035Y540006D01*
X146785Y539923D01*
X146577Y539715D01*
X146452Y539340D01*
X146494Y538965D01*
X146660Y538590D01*
G01X148577Y541356D02*
X148785Y541606D01*
X148910Y541898D01*
X148952Y542273D01*
X148869Y542648D01*
X148702Y542940D01*
X148410Y543148D01*
X148077Y543190D01*
X147744Y543106D01*
X147535Y542898D01*
X147369Y542606D01*
X147327Y542315D01*
X147369Y542023D01*
X147535Y541648D01*
X146452Y541773D01*
Y542898D01*
G01X148952Y545373D02*
X146452D01*
X146952Y544873D01*
G01X148952D02*
Y545873D01*
G01X192649Y514951D02*
X196649D01*
Y522351D01*
G01X188600Y514000D02*
X192600D01*
Y521400D01*
G01X176469Y515993D02*
X180469D01*
Y523393D01*
G01X193500Y500800D02*
X197500D01*
Y508200D01*
G01X184648Y508454D02*
X180648D01*
Y501054D01*
G01X172400Y510700D02*
X176400D01*
Y518100D01*
G01X210000Y497300D02*
X214000D01*
Y504700D01*
G01X150393Y608268D02*
Y533464D01*
X225197D01*
Y608268D01*
X150393D01*
G01X194500Y629000D02*
X196000D01*
Y635200D01*
X205900D01*
G01X146600Y630000D02*
X142200D01*
Y619000D01*
G01X190700Y629000D02*
X169315D01*
X169314Y629001D01*
Y630000D01*
X150200D01*
G01X162700Y616000D02*
X169300D01*
Y619500D01*
X174365D01*
G01X216200Y623300D02*
Y625000D01*
X197300D01*
G03X197200Y624900I0J-100D01*
G01Y619500D01*
X178602D01*
G01X206100Y643400D02*
X202100D01*
Y636000D01*
G01X144572Y639132D02*
X140572D01*
Y631732D01*
G01X152872Y639132D02*
X148872D01*
Y631732D01*
G01X209706Y635992D02*
X213706D01*
Y643392D01*
G01X168500Y639200D02*
X164500D01*
Y631800D01*
G01X159458Y639232D02*
X155458D01*
Y631832D01*
G01X184976Y631068D02*
X188976D01*
Y638468D01*
G01X189076Y631198D02*
X193076D01*
Y638598D01*
G01X168600Y631800D02*
X172600D01*
Y639200D01*
G01X172700Y631800D02*
X176700D01*
Y639200D01*
G01X176776Y631068D02*
X180776D01*
Y638468D01*
G01X180876Y631068D02*
X184876D01*
Y638468D01*
G01X147279Y624570D02*
X143279D01*
Y617170D01*
G01X150559Y609180D02*
Y611680D01*
X151600D01*
X151934Y611555D01*
X152142Y611388D01*
X152225Y611055D01*
X152142Y610722D01*
X151892Y610513D01*
X151600Y610388D01*
X150559D01*
G01X151600D02*
X152225Y609180D01*
G01X153575Y609680D02*
X153825Y609388D01*
X154159Y609222D01*
X154534Y609180D01*
X154867Y609222D01*
X155200Y609430D01*
X155409Y609680D01*
X155450Y609930D01*
X155367Y610222D01*
X155075Y610430D01*
X154784Y610513D01*
X154409D01*
G01X154784D02*
X155034Y610638D01*
X155242Y610847D01*
X155325Y611097D01*
X155242Y611347D01*
X155034Y611555D01*
X154659Y611680D01*
X154284Y611638D01*
X153909Y611472D01*
G01X156800Y611263D02*
X157050Y611513D01*
X157342Y611638D01*
X157675Y611680D01*
X158092Y611597D01*
X158384Y611388D01*
X158467Y611138D01*
X158425Y610888D01*
X158259Y610680D01*
X157425Y610263D01*
X157050Y609972D01*
X156800Y609555D01*
X156717Y609180D01*
X158467D01*
G01X159900Y611263D02*
X160150Y611513D01*
X160442Y611638D01*
X160775Y611680D01*
X161192Y611597D01*
X161484Y611388D01*
X161567Y611138D01*
X161525Y610888D01*
X161359Y610680D01*
X160525Y610263D01*
X160150Y609972D01*
X159900Y609555D01*
X159817Y609180D01*
X161567D01*
G01X174700Y628100D02*
X170700D01*
Y620700D01*
G01X178800Y628100D02*
X174800D01*
Y620700D01*
G01X182985Y628100D02*
X178985D01*
Y620700D01*
G01X187085Y628100D02*
X183085D01*
Y620700D01*
G01X191185Y628100D02*
X187185D01*
Y620700D01*
G01X195285Y628100D02*
X191285D01*
Y620700D01*
G01X149759Y613080D02*
Y615580D01*
X150800D01*
X151134Y615455D01*
X151342Y615288D01*
X151425Y614955D01*
X151342Y614622D01*
X151092Y614413D01*
X150800Y614288D01*
X149759D01*
G01X150800D02*
X151425Y613080D01*
G01X152775Y613580D02*
X153025Y613288D01*
X153359Y613122D01*
X153734Y613080D01*
X154067Y613122D01*
X154400Y613330D01*
X154609Y613580D01*
X154650Y613830D01*
X154567Y614122D01*
X154275Y614330D01*
X153984Y614413D01*
X153609D01*
G01X153984D02*
X154234Y614538D01*
X154442Y614747D01*
X154525Y614997D01*
X154442Y615247D01*
X154234Y615455D01*
X153859Y615580D01*
X153484Y615538D01*
X153109Y615372D01*
G01X156000Y615163D02*
X156250Y615413D01*
X156542Y615538D01*
X156875Y615580D01*
X157292Y615497D01*
X157584Y615288D01*
X157667Y615038D01*
X157625Y614788D01*
X157459Y614580D01*
X156625Y614163D01*
X156250Y613872D01*
X156000Y613455D01*
X155917Y613080D01*
X157667D01*
G01X159892Y615580D02*
X159559Y615497D01*
X159309Y615288D01*
X159142Y615038D01*
X159017Y614705D01*
X158975Y614330D01*
X159017Y613955D01*
X159142Y613622D01*
X159309Y613372D01*
X159559Y613163D01*
X159892Y613080D01*
X160225Y613163D01*
X160475Y613372D01*
X160642Y613622D01*
X160767Y613955D01*
X160809Y614330D01*
X160767Y614705D01*
X160642Y615038D01*
X160475Y615288D01*
X160225Y615497D01*
X159892Y615580D01*
G01X151700Y620800D02*
X155700D01*
Y628200D01*
G01X151400Y628600D02*
X147400D01*
Y621200D01*
G01X163359Y611983D02*
Y609483D01*
G01X162401Y611983D02*
X164317D01*
G01X165626Y609483D02*
Y611983D01*
X166626D01*
X166959Y611858D01*
X167209Y611566D01*
X167292Y611233D01*
X167209Y610900D01*
X167001Y610650D01*
X166626Y610525D01*
X165626D01*
G01X168642Y609858D02*
X168892Y609650D01*
X169184Y609525D01*
X169559Y609483D01*
X169934Y609566D01*
X170226Y609733D01*
X170434Y610025D01*
X170476Y610358D01*
X170392Y610691D01*
X170184Y610900D01*
X169892Y611066D01*
X169601Y611108D01*
X169309Y611066D01*
X168934Y610900D01*
X169059Y611983D01*
X170184D01*
G01X172576Y609483D02*
X172659Y610025D01*
X172784Y610483D01*
X172951Y610900D01*
X173159Y611358D01*
X173492Y611983D01*
X171826D01*
G01X199286Y612399D02*
Y609899D01*
G01X198328Y612399D02*
X200244D01*
G01X201553Y609899D02*
Y612399D01*
X202553D01*
X202886Y612274D01*
X203136Y611982D01*
X203219Y611649D01*
X203136Y611316D01*
X202928Y611066D01*
X202553Y610941D01*
X201553D01*
G01X204694Y611982D02*
X204944Y612232D01*
X205236Y612357D01*
X205569Y612399D01*
X205986Y612316D01*
X206278Y612107D01*
X206361Y611857D01*
X206319Y611607D01*
X206153Y611399D01*
X205319Y610982D01*
X204944Y610691D01*
X204694Y610274D01*
X204611Y609899D01*
X206361D01*
G01X208586D02*
Y612399D01*
X208086Y611899D01*
G01Y609899D02*
X209086D01*
G01X211686Y612399D02*
X211353Y612316D01*
X211103Y612107D01*
X210936Y611857D01*
X210811Y611524D01*
X210769Y611149D01*
X210811Y610774D01*
X210936Y610441D01*
X211103Y610191D01*
X211353Y609982D01*
X211686Y609899D01*
X212019Y609982D01*
X212269Y610191D01*
X212436Y610441D01*
X212561Y610774D01*
X212603Y611149D01*
X212561Y611524D01*
X212436Y611857D01*
X212269Y612107D01*
X212019Y612316D01*
X211686Y612399D01*
G01X190642Y697117D02*
X190517Y696867D01*
X190434Y696575D01*
Y696242D01*
X190559Y695867D01*
X190767Y695575D01*
X191017Y695367D01*
X191434Y695200D01*
X191809Y695158D01*
X192184Y695242D01*
X192434Y695367D01*
X192684Y695617D01*
X192851Y695908D01*
X192934Y696200D01*
Y696492D01*
X192851Y696783D01*
X192726Y697033D01*
X192559Y697242D01*
G01X192934Y699800D02*
X190434D01*
X192226Y698258D01*
Y700342D01*
G01X192642Y701692D02*
X192851Y701983D01*
X192934Y702317D01*
X192851Y702650D01*
X192601Y702942D01*
X192226Y703150D01*
X191851Y703233D01*
X191392D01*
X191017Y703150D01*
X190684Y702942D01*
X190517Y702692D01*
X190434Y702400D01*
X190517Y702067D01*
X190684Y701817D01*
X190934Y701650D01*
X191267Y701567D01*
X191559Y701650D01*
X191851Y701858D01*
X192017Y702108D01*
X192059Y702400D01*
X191976Y702733D01*
X191767Y702983D01*
X191392Y703233D01*
G01X185430Y700206D02*
X185305Y699956D01*
X185222Y699664D01*
Y699331D01*
X185347Y698956D01*
X185555Y698664D01*
X185805Y698456D01*
X186222Y698289D01*
X186597Y698247D01*
X186972Y698331D01*
X187222Y698456D01*
X187472Y698706D01*
X187639Y698997D01*
X187722Y699289D01*
Y699581D01*
X187639Y699872D01*
X187514Y700122D01*
X187347Y700331D01*
G01X187722Y702389D02*
X185222D01*
X185722Y701889D01*
G01X187722D02*
Y702889D01*
G01Y705489D02*
X187680Y705781D01*
X187555Y706114D01*
X187347Y706322D01*
X187055Y706406D01*
X186764Y706322D01*
X186514Y706072D01*
X186389Y705697D01*
Y705281D01*
X186305Y705031D01*
X186097Y704822D01*
X185805Y704739D01*
X185514Y704864D01*
X185305Y705156D01*
X185222Y705489D01*
X185305Y705822D01*
X185514Y706114D01*
X185805Y706239D01*
X186097Y706156D01*
X186305Y705947D01*
X186389Y705697D01*
Y705281D01*
X186514Y704906D01*
X186764Y704656D01*
X187055Y704572D01*
X187347Y704656D01*
X187555Y704864D01*
X187680Y705197D01*
X187722Y705489D01*
G01Y708589D02*
X185222D01*
X185722Y708089D01*
G01X187722D02*
Y709089D01*
G01X190208Y652067D02*
X190083Y651817D01*
X190000Y651525D01*
Y651192D01*
X190125Y650817D01*
X190333Y650525D01*
X190583Y650317D01*
X191000Y650150D01*
X191375Y650108D01*
X191750Y650192D01*
X192000Y650317D01*
X192250Y650567D01*
X192417Y650858D01*
X192500Y651150D01*
Y651442D01*
X192417Y651733D01*
X192292Y651983D01*
X192125Y652192D01*
G01X192500Y654250D02*
X190000D01*
X190500Y653750D01*
G01X192500D02*
Y654750D01*
G01X190417Y656558D02*
X190167Y656808D01*
X190042Y657100D01*
X190000Y657433D01*
X190083Y657850D01*
X190292Y658142D01*
X190542Y658225D01*
X190792Y658183D01*
X191000Y658017D01*
X191417Y657183D01*
X191708Y656808D01*
X192125Y656558D01*
X192500Y656475D01*
Y658225D01*
G01X190417Y659658D02*
X190167Y659908D01*
X190042Y660200D01*
X190000Y660533D01*
X190083Y660950D01*
X190292Y661242D01*
X190542Y661325D01*
X190792Y661283D01*
X191000Y661117D01*
X191417Y660283D01*
X191708Y659908D01*
X192125Y659658D01*
X192500Y659575D01*
Y661325D01*
G01X197708Y649267D02*
X197583Y649017D01*
X197500Y648725D01*
Y648392D01*
X197625Y648017D01*
X197833Y647725D01*
X198083Y647517D01*
X198500Y647350D01*
X198875Y647308D01*
X199250Y647392D01*
X199500Y647517D01*
X199750Y647767D01*
X199917Y648058D01*
X200000Y648350D01*
Y648642D01*
X199917Y648933D01*
X199792Y649183D01*
X199625Y649392D01*
G01X200000Y651450D02*
X197500D01*
X198000Y650950D01*
G01X200000D02*
Y651950D01*
G01Y654550D02*
X197500D01*
X198000Y654050D01*
G01X200000D02*
Y655050D01*
G01Y657650D02*
X199958Y657942D01*
X199833Y658275D01*
X199625Y658483D01*
X199333Y658567D01*
X199042Y658483D01*
X198792Y658233D01*
X198667Y657858D01*
Y657442D01*
X198583Y657192D01*
X198375Y656983D01*
X198083Y656900D01*
X197792Y657025D01*
X197583Y657317D01*
X197500Y657650D01*
X197583Y657983D01*
X197792Y658275D01*
X198083Y658400D01*
X198375Y658317D01*
X198583Y658108D01*
X198667Y657858D01*
Y657442D01*
X198792Y657067D01*
X199042Y656817D01*
X199333Y656733D01*
X199625Y656817D01*
X199833Y657025D01*
X199958Y657358D01*
X200000Y657650D01*
G01X174017Y654000D02*
Y656500D01*
X175058D01*
X175392Y656375D01*
X175600Y656208D01*
X175683Y655875D01*
X175600Y655542D01*
X175350Y655333D01*
X175058Y655208D01*
X174017D01*
G01X175058D02*
X175683Y654000D01*
G01X177033Y654500D02*
X177283Y654208D01*
X177617Y654042D01*
X177992Y654000D01*
X178325Y654042D01*
X178658Y654250D01*
X178867Y654500D01*
X178908Y654750D01*
X178825Y655042D01*
X178533Y655250D01*
X178242Y655333D01*
X177867D01*
G01X178242D02*
X178492Y655458D01*
X178700Y655667D01*
X178783Y655917D01*
X178700Y656167D01*
X178492Y656375D01*
X178117Y656500D01*
X177742Y656458D01*
X177367Y656292D01*
G01X180258Y655042D02*
X180550Y655333D01*
X180800Y655500D01*
X181133Y655583D01*
X181425Y655500D01*
X181633Y655333D01*
X181800Y655083D01*
X181842Y654792D01*
X181800Y654542D01*
X181633Y654292D01*
X181383Y654083D01*
X181092Y654000D01*
X180758Y654083D01*
X180467Y654333D01*
X180300Y654708D01*
X180258Y655125D01*
X180342Y655667D01*
X180467Y655958D01*
X180675Y656250D01*
X180967Y656458D01*
X181258Y656500D01*
X181550Y656417D01*
X181758Y656208D01*
G01X184067Y654000D02*
X184150Y654542D01*
X184275Y655000D01*
X184442Y655417D01*
X184650Y655875D01*
X184983Y656500D01*
X183317D01*
G01X186128Y645963D02*
Y641963D01*
X193528D01*
G01X188900Y647517D02*
X186400D01*
Y648558D01*
X186525Y648892D01*
X186692Y649100D01*
X187025Y649183D01*
X187358Y649100D01*
X187567Y648850D01*
X187692Y648558D01*
Y647517D01*
G01Y648558D02*
X188900Y649183D01*
G01Y651950D02*
X186400D01*
X188192Y650408D01*
Y652492D01*
G01X186400Y654550D02*
X186483Y654217D01*
X186692Y653967D01*
X186942Y653800D01*
X187275Y653675D01*
X187650Y653633D01*
X188025Y653675D01*
X188358Y653800D01*
X188608Y653967D01*
X188817Y654217D01*
X188900Y654550D01*
X188817Y654883D01*
X188608Y655133D01*
X188358Y655300D01*
X188025Y655425D01*
X187650Y655467D01*
X187275Y655425D01*
X186942Y655300D01*
X186692Y655133D01*
X186483Y654883D01*
X186400Y654550D01*
G01X188608Y656942D02*
X188817Y657233D01*
X188900Y657567D01*
X188817Y657900D01*
X188567Y658192D01*
X188192Y658400D01*
X187817Y658483D01*
X187358D01*
X186983Y658400D01*
X186650Y658192D01*
X186483Y657942D01*
X186400Y657650D01*
X186483Y657317D01*
X186650Y657067D01*
X186900Y656900D01*
X187233Y656817D01*
X187525Y656900D01*
X187817Y657108D01*
X187983Y657358D01*
X188025Y657650D01*
X187942Y657983D01*
X187733Y658233D01*
X187358Y658483D01*
G01X207400Y647517D02*
X204900D01*
Y648558D01*
X205025Y648892D01*
X205192Y649100D01*
X205525Y649183D01*
X205858Y649100D01*
X206067Y648850D01*
X206192Y648558D01*
Y647517D01*
G01Y648558D02*
X207400Y649183D01*
G01Y651950D02*
X204900D01*
X206692Y650408D01*
Y652492D01*
G01X204900Y654550D02*
X204983Y654217D01*
X205192Y653967D01*
X205442Y653800D01*
X205775Y653675D01*
X206150Y653633D01*
X206525Y653675D01*
X206858Y653800D01*
X207108Y653967D01*
X207317Y654217D01*
X207400Y654550D01*
X207317Y654883D01*
X207108Y655133D01*
X206858Y655300D01*
X206525Y655425D01*
X206150Y655467D01*
X205775Y655425D01*
X205442Y655300D01*
X205192Y655133D01*
X204983Y654883D01*
X204900Y654550D01*
G01X205317Y656858D02*
X205067Y657108D01*
X204942Y657400D01*
X204900Y657733D01*
X204983Y658150D01*
X205192Y658442D01*
X205442Y658525D01*
X205692Y658483D01*
X205900Y658317D01*
X206317Y657483D01*
X206608Y657108D01*
X207025Y656858D01*
X207400Y656775D01*
Y658525D01*
G01X143149Y685715D02*
Y681715D01*
X150549D01*
G01X176075Y698524D02*
X173575D01*
Y699565D01*
X173700Y699899D01*
X173867Y700107D01*
X174200Y700190D01*
X174533Y700107D01*
X174742Y699857D01*
X174867Y699565D01*
Y698524D01*
G01Y699565D02*
X176075Y700190D01*
G01Y702957D02*
X173575D01*
X175367Y701415D01*
Y703499D01*
G01X175783Y704849D02*
X175992Y705140D01*
X176075Y705474D01*
X175992Y705807D01*
X175742Y706099D01*
X175367Y706307D01*
X174992Y706390D01*
X174533D01*
X174158Y706307D01*
X173825Y706099D01*
X173658Y705849D01*
X173575Y705557D01*
X173658Y705224D01*
X173825Y704974D01*
X174075Y704807D01*
X174408Y704724D01*
X174700Y704807D01*
X174992Y705015D01*
X175158Y705265D01*
X175200Y705557D01*
X175117Y705890D01*
X174908Y706140D01*
X174533Y706390D01*
G01X176075Y708657D02*
X173575D01*
X174075Y708157D01*
G01X176075D02*
Y709157D01*
G01X156300Y708915D02*
X152300D01*
Y701515D01*
G01X183722Y698456D02*
X181222D01*
Y699497D01*
X181347Y699831D01*
X181514Y700039D01*
X181847Y700122D01*
X182180Y700039D01*
X182389Y699789D01*
X182514Y699497D01*
Y698456D01*
G01Y699497D02*
X183722Y700122D01*
G01Y702889D02*
X181222D01*
X183014Y701347D01*
Y703431D01*
G01X183722Y705489D02*
X183680Y705781D01*
X183555Y706114D01*
X183347Y706322D01*
X183055Y706406D01*
X182764Y706322D01*
X182514Y706072D01*
X182389Y705697D01*
Y705281D01*
X182305Y705031D01*
X182097Y704822D01*
X181805Y704739D01*
X181514Y704864D01*
X181305Y705156D01*
X181222Y705489D01*
X181305Y705822D01*
X181514Y706114D01*
X181805Y706239D01*
X182097Y706156D01*
X182305Y705947D01*
X182389Y705697D01*
Y705281D01*
X182514Y704906D01*
X182764Y704656D01*
X183055Y704572D01*
X183347Y704656D01*
X183555Y704864D01*
X183680Y705197D01*
X183722Y705489D01*
G01Y708589D02*
X183680Y708881D01*
X183555Y709214D01*
X183347Y709422D01*
X183055Y709506D01*
X182764Y709422D01*
X182514Y709172D01*
X182389Y708797D01*
Y708381D01*
X182305Y708131D01*
X182097Y707922D01*
X181805Y707839D01*
X181514Y707964D01*
X181305Y708256D01*
X181222Y708589D01*
X181305Y708922D01*
X181514Y709214D01*
X181805Y709339D01*
X182097Y709256D01*
X182305Y709047D01*
X182389Y708797D01*
Y708381D01*
X182514Y708006D01*
X182764Y707756D01*
X183055Y707672D01*
X183347Y707756D01*
X183555Y707964D01*
X183680Y708297D01*
X183722Y708589D01*
G01X170047Y710475D02*
X166047D01*
Y703075D01*
G01X179534Y685517D02*
X177034D01*
Y686558D01*
X177159Y686892D01*
X177326Y687100D01*
X177659Y687183D01*
X177992Y687100D01*
X178201Y686850D01*
X178326Y686558D01*
Y685517D01*
G01Y686558D02*
X179534Y687183D01*
G01Y689950D02*
X177034D01*
X178826Y688408D01*
Y690492D01*
G01X179534Y692550D02*
X179492Y692842D01*
X179367Y693175D01*
X179159Y693383D01*
X178867Y693467D01*
X178576Y693383D01*
X178326Y693133D01*
X178201Y692758D01*
Y692342D01*
X178117Y692092D01*
X177909Y691883D01*
X177617Y691800D01*
X177326Y691925D01*
X177117Y692217D01*
X177034Y692550D01*
X177117Y692883D01*
X177326Y693175D01*
X177617Y693300D01*
X177909Y693217D01*
X178117Y693008D01*
X178201Y692758D01*
Y692342D01*
X178326Y691967D01*
X178576Y691717D01*
X178867Y691633D01*
X179159Y691717D01*
X179367Y691925D01*
X179492Y692258D01*
X179534Y692550D01*
G01X178492Y694858D02*
X178201Y695150D01*
X178034Y695400D01*
X177951Y695733D01*
X178034Y696025D01*
X178201Y696233D01*
X178451Y696400D01*
X178742Y696442D01*
X178992Y696400D01*
X179242Y696233D01*
X179451Y695983D01*
X179534Y695692D01*
X179451Y695358D01*
X179201Y695067D01*
X178826Y694900D01*
X178409Y694858D01*
X177867Y694942D01*
X177576Y695067D01*
X177284Y695275D01*
X177076Y695567D01*
X177034Y695858D01*
X177117Y696150D01*
X177326Y696358D01*
G01X153749Y701115D02*
X149749D01*
Y693715D01*
G01X183034Y685517D02*
X180534D01*
Y686558D01*
X180659Y686892D01*
X180826Y687100D01*
X181159Y687183D01*
X181492Y687100D01*
X181701Y686850D01*
X181826Y686558D01*
Y685517D01*
G01Y686558D02*
X183034Y687183D01*
G01Y689950D02*
X180534D01*
X182326Y688408D01*
Y690492D01*
G01X183034Y692550D02*
X182992Y692842D01*
X182867Y693175D01*
X182659Y693383D01*
X182367Y693467D01*
X182076Y693383D01*
X181826Y693133D01*
X181701Y692758D01*
Y692342D01*
X181617Y692092D01*
X181409Y691883D01*
X181117Y691800D01*
X180826Y691925D01*
X180617Y692217D01*
X180534Y692550D01*
X180617Y692883D01*
X180826Y693175D01*
X181117Y693300D01*
X181409Y693217D01*
X181617Y693008D01*
X181701Y692758D01*
Y692342D01*
X181826Y691967D01*
X182076Y691717D01*
X182367Y691633D01*
X182659Y691717D01*
X182867Y691925D01*
X182992Y692258D01*
X183034Y692550D01*
G01X180951Y694858D02*
X180701Y695108D01*
X180576Y695400D01*
X180534Y695733D01*
X180617Y696150D01*
X180826Y696442D01*
X181076Y696525D01*
X181326Y696483D01*
X181534Y696317D01*
X181951Y695483D01*
X182242Y695108D01*
X182659Y694858D01*
X183034Y694775D01*
Y696525D01*
G01X153849Y693715D02*
X157849D01*
Y701115D01*
G01X196200Y650417D02*
X193700D01*
Y651458D01*
X193825Y651792D01*
X193992Y652000D01*
X194325Y652083D01*
X194658Y652000D01*
X194867Y651750D01*
X194992Y651458D01*
Y650417D01*
G01Y651458D02*
X196200Y652083D01*
G01Y654850D02*
X193700D01*
X195492Y653308D01*
Y655392D01*
G01X196200Y657450D02*
X193700D01*
X194200Y656950D01*
G01X196200D02*
Y657950D01*
G01X194117Y659758D02*
X193867Y660008D01*
X193742Y660300D01*
X193700Y660633D01*
X193783Y661050D01*
X193992Y661342D01*
X194242Y661425D01*
X194492Y661383D01*
X194700Y661217D01*
X195117Y660383D01*
X195408Y660008D01*
X195825Y659758D01*
X196200Y659675D01*
Y661425D01*
G01X203700Y647517D02*
X201200D01*
Y648558D01*
X201325Y648892D01*
X201492Y649100D01*
X201825Y649183D01*
X202158Y649100D01*
X202367Y648850D01*
X202492Y648558D01*
Y647517D01*
G01Y648558D02*
X203700Y649183D01*
G01Y651950D02*
X201200D01*
X202992Y650408D01*
Y652492D01*
G01X201200Y654550D02*
X201283Y654217D01*
X201492Y653967D01*
X201742Y653800D01*
X202075Y653675D01*
X202450Y653633D01*
X202825Y653675D01*
X203158Y653800D01*
X203408Y653967D01*
X203617Y654217D01*
X203700Y654550D01*
X203617Y654883D01*
X203408Y655133D01*
X203158Y655300D01*
X202825Y655425D01*
X202450Y655467D01*
X202075Y655425D01*
X201742Y655300D01*
X201492Y655133D01*
X201283Y654883D01*
X201200Y654550D01*
G01X203325Y656733D02*
X203533Y656983D01*
X203658Y657275D01*
X203700Y657650D01*
X203617Y658025D01*
X203450Y658317D01*
X203158Y658525D01*
X202825Y658567D01*
X202492Y658483D01*
X202283Y658275D01*
X202117Y657983D01*
X202075Y657692D01*
X202117Y657400D01*
X202283Y657025D01*
X201200Y657150D01*
Y658275D01*
G01X160318Y642147D02*
X157818D01*
Y643188D01*
X157943Y643522D01*
X158110Y643730D01*
X158443Y643813D01*
X158776Y643730D01*
X158985Y643480D01*
X159110Y643188D01*
Y642147D01*
G01Y643188D02*
X160318Y643813D01*
G01X159818Y645163D02*
X160110Y645413D01*
X160276Y645747D01*
X160318Y646122D01*
X160276Y646455D01*
X160068Y646788D01*
X159818Y646997D01*
X159568Y647038D01*
X159276Y646955D01*
X159068Y646663D01*
X158985Y646372D01*
Y645997D01*
G01Y646372D02*
X158860Y646622D01*
X158651Y646830D01*
X158401Y646913D01*
X158151Y646830D01*
X157943Y646622D01*
X157818Y646247D01*
X157860Y645872D01*
X158026Y645497D01*
G01X160318Y649180D02*
X157818D01*
X158318Y648680D01*
G01X160318D02*
Y649680D01*
G01X159818Y651363D02*
X160110Y651613D01*
X160276Y651947D01*
X160318Y652322D01*
X160276Y652655D01*
X160068Y652988D01*
X159818Y653197D01*
X159568Y653238D01*
X159276Y653155D01*
X159068Y652863D01*
X158985Y652572D01*
Y652197D01*
G01Y652572D02*
X158860Y652822D01*
X158651Y653030D01*
X158401Y653113D01*
X158151Y653030D01*
X157943Y652822D01*
X157818Y652447D01*
X157860Y652072D01*
X158026Y651697D01*
G01X154800Y641473D02*
X152300D01*
Y642514D01*
X152425Y642848D01*
X152592Y643056D01*
X152925Y643139D01*
X153258Y643056D01*
X153467Y642806D01*
X153592Y642514D01*
Y641473D01*
G01Y642514D02*
X154800Y643139D01*
G01X154300Y644489D02*
X154592Y644739D01*
X154758Y645073D01*
X154800Y645448D01*
X154758Y645781D01*
X154550Y646114D01*
X154300Y646323D01*
X154050Y646364D01*
X153758Y646281D01*
X153550Y645989D01*
X153467Y645698D01*
Y645323D01*
G01Y645698D02*
X153342Y645948D01*
X153133Y646156D01*
X152883Y646239D01*
X152633Y646156D01*
X152425Y645948D01*
X152300Y645573D01*
X152342Y645198D01*
X152508Y644823D01*
G01X152300Y648506D02*
X152383Y648173D01*
X152592Y647923D01*
X152842Y647756D01*
X153175Y647631D01*
X153550Y647589D01*
X153925Y647631D01*
X154258Y647756D01*
X154508Y647923D01*
X154717Y648173D01*
X154800Y648506D01*
X154717Y648839D01*
X154508Y649089D01*
X154258Y649256D01*
X153925Y649381D01*
X153550Y649423D01*
X153175Y649381D01*
X152842Y649256D01*
X152592Y649089D01*
X152383Y648839D01*
X152300Y648506D01*
G01X154508Y650898D02*
X154717Y651189D01*
X154800Y651523D01*
X154717Y651856D01*
X154467Y652148D01*
X154092Y652356D01*
X153717Y652439D01*
X153258D01*
X152883Y652356D01*
X152550Y652148D01*
X152383Y651898D01*
X152300Y651606D01*
X152383Y651273D01*
X152550Y651023D01*
X152800Y650856D01*
X153133Y650773D01*
X153425Y650856D01*
X153717Y651064D01*
X153883Y651314D01*
X153925Y651606D01*
X153842Y651939D01*
X153633Y652189D01*
X153258Y652439D01*
G01X180983Y642021D02*
X178483D01*
Y643062D01*
X178608Y643396D01*
X178775Y643604D01*
X179108Y643687D01*
X179441Y643604D01*
X179650Y643354D01*
X179775Y643062D01*
Y642021D01*
G01Y643062D02*
X180983Y643687D01*
G01X178900Y645162D02*
X178650Y645412D01*
X178525Y645704D01*
X178483Y646037D01*
X178566Y646454D01*
X178775Y646746D01*
X179025Y646829D01*
X179275Y646787D01*
X179483Y646621D01*
X179900Y645787D01*
X180191Y645412D01*
X180608Y645162D01*
X180983Y645079D01*
Y646829D01*
G01X178483Y649054D02*
X178566Y648721D01*
X178775Y648471D01*
X179025Y648304D01*
X179358Y648179D01*
X179733Y648137D01*
X180108Y648179D01*
X180441Y648304D01*
X180691Y648471D01*
X180900Y648721D01*
X180983Y649054D01*
X180900Y649387D01*
X180691Y649637D01*
X180441Y649804D01*
X180108Y649929D01*
X179733Y649971D01*
X179358Y649929D01*
X179025Y649804D01*
X178775Y649637D01*
X178566Y649387D01*
X178483Y649054D01*
G01X180983Y652654D02*
X178483D01*
X180275Y651112D01*
Y653196D01*
G01X184924Y642125D02*
X182424D01*
Y643166D01*
X182549Y643500D01*
X182716Y643708D01*
X183049Y643791D01*
X183382Y643708D01*
X183591Y643458D01*
X183716Y643166D01*
Y642125D01*
G01Y643166D02*
X184924Y643791D01*
G01X182841Y645266D02*
X182591Y645516D01*
X182466Y645808D01*
X182424Y646141D01*
X182507Y646558D01*
X182716Y646850D01*
X182966Y646933D01*
X183216Y646891D01*
X183424Y646725D01*
X183841Y645891D01*
X184132Y645516D01*
X184549Y645266D01*
X184924Y645183D01*
Y646933D01*
G01X182424Y649158D02*
X182507Y648825D01*
X182716Y648575D01*
X182966Y648408D01*
X183299Y648283D01*
X183674Y648241D01*
X184049Y648283D01*
X184382Y648408D01*
X184632Y648575D01*
X184841Y648825D01*
X184924Y649158D01*
X184841Y649491D01*
X184632Y649741D01*
X184382Y649908D01*
X184049Y650033D01*
X183674Y650075D01*
X183299Y650033D01*
X182966Y649908D01*
X182716Y649741D01*
X182507Y649491D01*
X182424Y649158D01*
G01X184424Y651341D02*
X184716Y651591D01*
X184882Y651925D01*
X184924Y652300D01*
X184882Y652633D01*
X184674Y652966D01*
X184424Y653175D01*
X184174Y653216D01*
X183882Y653133D01*
X183674Y652841D01*
X183591Y652550D01*
Y652175D01*
G01Y652550D02*
X183466Y652800D01*
X183257Y653008D01*
X183007Y653091D01*
X182757Y653008D01*
X182549Y652800D01*
X182424Y652425D01*
X182466Y652050D01*
X182632Y651675D01*
G01X164489Y642147D02*
X161989D01*
Y643188D01*
X162114Y643522D01*
X162281Y643730D01*
X162614Y643813D01*
X162947Y643730D01*
X163156Y643480D01*
X163281Y643188D01*
Y642147D01*
G01Y643188D02*
X164489Y643813D01*
G01Y646080D02*
X161989D01*
X162489Y645580D01*
G01X164489D02*
Y646580D01*
G01Y649180D02*
X164447Y649472D01*
X164322Y649805D01*
X164114Y650013D01*
X163822Y650097D01*
X163531Y650013D01*
X163281Y649763D01*
X163156Y649388D01*
Y648972D01*
X163072Y648722D01*
X162864Y648513D01*
X162572Y648430D01*
X162281Y648555D01*
X162072Y648847D01*
X161989Y649180D01*
X162072Y649513D01*
X162281Y649805D01*
X162572Y649930D01*
X162864Y649847D01*
X163072Y649638D01*
X163156Y649388D01*
Y648972D01*
X163281Y648597D01*
X163531Y648347D01*
X163822Y648263D01*
X164114Y648347D01*
X164322Y648555D01*
X164447Y648888D01*
X164489Y649180D01*
G01Y652280D02*
X164447Y652572D01*
X164322Y652905D01*
X164114Y653113D01*
X163822Y653197D01*
X163531Y653113D01*
X163281Y652863D01*
X163156Y652488D01*
Y652072D01*
X163072Y651822D01*
X162864Y651613D01*
X162572Y651530D01*
X162281Y651655D01*
X162072Y651947D01*
X161989Y652280D01*
X162072Y652613D01*
X162281Y652905D01*
X162572Y653030D01*
X162864Y652947D01*
X163072Y652738D01*
X163156Y652488D01*
Y652072D01*
X163281Y651697D01*
X163531Y651447D01*
X163822Y651363D01*
X164114Y651447D01*
X164322Y651655D01*
X164447Y651988D01*
X164489Y652280D01*
G01X168723Y642084D02*
X166223D01*
Y643125D01*
X166348Y643459D01*
X166515Y643667D01*
X166848Y643750D01*
X167181Y643667D01*
X167390Y643417D01*
X167515Y643125D01*
Y642084D01*
G01Y643125D02*
X168723Y643750D01*
G01Y646017D02*
X166223D01*
X166723Y645517D01*
G01X168723D02*
Y646517D01*
G01Y649117D02*
X168681Y649409D01*
X168556Y649742D01*
X168348Y649950D01*
X168056Y650034D01*
X167765Y649950D01*
X167515Y649700D01*
X167390Y649325D01*
Y648909D01*
X167306Y648659D01*
X167098Y648450D01*
X166806Y648367D01*
X166515Y648492D01*
X166306Y648784D01*
X166223Y649117D01*
X166306Y649450D01*
X166515Y649742D01*
X166806Y649867D01*
X167098Y649784D01*
X167306Y649575D01*
X167390Y649325D01*
Y648909D01*
X167515Y648534D01*
X167765Y648284D01*
X168056Y648200D01*
X168348Y648284D01*
X168556Y648492D01*
X168681Y648825D01*
X168723Y649117D01*
G01Y652134D02*
X168181Y652217D01*
X167723Y652342D01*
X167306Y652509D01*
X166848Y652717D01*
X166223Y653050D01*
Y651384D01*
G01X173021Y642021D02*
X170521D01*
Y643062D01*
X170646Y643396D01*
X170813Y643604D01*
X171146Y643687D01*
X171479Y643604D01*
X171688Y643354D01*
X171813Y643062D01*
Y642021D01*
G01Y643062D02*
X173021Y643687D01*
G01Y645954D02*
X170521D01*
X171021Y645454D01*
G01X173021D02*
Y646454D01*
G01Y649054D02*
X172979Y649346D01*
X172854Y649679D01*
X172646Y649887D01*
X172354Y649971D01*
X172063Y649887D01*
X171813Y649637D01*
X171688Y649262D01*
Y648846D01*
X171604Y648596D01*
X171396Y648387D01*
X171104Y648304D01*
X170813Y648429D01*
X170604Y648721D01*
X170521Y649054D01*
X170604Y649387D01*
X170813Y649679D01*
X171104Y649804D01*
X171396Y649721D01*
X171604Y649512D01*
X171688Y649262D01*
Y648846D01*
X171813Y648471D01*
X172063Y648221D01*
X172354Y648137D01*
X172646Y648221D01*
X172854Y648429D01*
X172979Y648762D01*
X173021Y649054D01*
G01X170521Y652154D02*
X170604Y651821D01*
X170813Y651571D01*
X171063Y651404D01*
X171396Y651279D01*
X171771Y651237D01*
X172146Y651279D01*
X172479Y651404D01*
X172729Y651571D01*
X172938Y651821D01*
X173021Y652154D01*
X172938Y652487D01*
X172729Y652737D01*
X172479Y652904D01*
X172146Y653029D01*
X171771Y653071D01*
X171396Y653029D01*
X171063Y652904D01*
X170813Y652737D01*
X170604Y652487D01*
X170521Y652154D01*
G01X177128Y642210D02*
X174628D01*
Y643251D01*
X174753Y643585D01*
X174920Y643793D01*
X175253Y643876D01*
X175586Y643793D01*
X175795Y643543D01*
X175920Y643251D01*
Y642210D01*
G01Y643251D02*
X177128Y643876D01*
G01Y646143D02*
X174628D01*
X175128Y645643D01*
G01X177128D02*
Y646643D01*
G01Y649160D02*
X176586Y649243D01*
X176128Y649368D01*
X175711Y649535D01*
X175253Y649743D01*
X174628Y650076D01*
Y648410D01*
G01X176836Y651635D02*
X177045Y651926D01*
X177128Y652260D01*
X177045Y652593D01*
X176795Y652885D01*
X176420Y653093D01*
X176045Y653176D01*
X175586D01*
X175211Y653093D01*
X174878Y652885D01*
X174711Y652635D01*
X174628Y652343D01*
X174711Y652010D01*
X174878Y651760D01*
X175128Y651593D01*
X175461Y651510D01*
X175753Y651593D01*
X176045Y651801D01*
X176211Y652051D01*
X176253Y652343D01*
X176170Y652676D01*
X175961Y652926D01*
X175586Y653176D01*
G01X180075Y698524D02*
X177575D01*
Y699565D01*
X177700Y699899D01*
X177867Y700107D01*
X178200Y700190D01*
X178533Y700107D01*
X178742Y699857D01*
X178867Y699565D01*
Y698524D01*
G01Y699565D02*
X180075Y700190D01*
G01Y702957D02*
X177575D01*
X179367Y701415D01*
Y703499D01*
G01X180075Y705557D02*
X180033Y705849D01*
X179908Y706182D01*
X179700Y706390D01*
X179408Y706474D01*
X179117Y706390D01*
X178867Y706140D01*
X178742Y705765D01*
Y705349D01*
X178658Y705099D01*
X178450Y704890D01*
X178158Y704807D01*
X177867Y704932D01*
X177658Y705224D01*
X177575Y705557D01*
X177658Y705890D01*
X177867Y706182D01*
X178158Y706307D01*
X178450Y706224D01*
X178658Y706015D01*
X178742Y705765D01*
Y705349D01*
X178867Y704974D01*
X179117Y704724D01*
X179408Y704640D01*
X179700Y704724D01*
X179908Y704932D01*
X180033Y705265D01*
X180075Y705557D01*
G01Y708574D02*
X179533Y708657D01*
X179075Y708782D01*
X178658Y708949D01*
X178200Y709157D01*
X177575Y709490D01*
Y707824D01*
G01X156349Y701515D02*
X160349D01*
Y708915D01*
G01X153149Y713215D02*
Y709215D01*
X160549D01*
G01X186533Y685517D02*
X184033D01*
Y686558D01*
X184158Y686892D01*
X184325Y687100D01*
X184658Y687183D01*
X184991Y687100D01*
X185200Y686850D01*
X185325Y686558D01*
Y685517D01*
G01Y686558D02*
X186533Y687183D01*
G01Y689950D02*
X184033D01*
X185825Y688408D01*
Y690492D01*
G01X186533Y692550D02*
X186491Y692842D01*
X186366Y693175D01*
X186158Y693383D01*
X185866Y693467D01*
X185575Y693383D01*
X185325Y693133D01*
X185200Y692758D01*
Y692342D01*
X185116Y692092D01*
X184908Y691883D01*
X184616Y691800D01*
X184325Y691925D01*
X184116Y692217D01*
X184033Y692550D01*
X184116Y692883D01*
X184325Y693175D01*
X184616Y693300D01*
X184908Y693217D01*
X185116Y693008D01*
X185200Y692758D01*
Y692342D01*
X185325Y691967D01*
X185575Y691717D01*
X185866Y691633D01*
X186158Y691717D01*
X186366Y691925D01*
X186491Y692258D01*
X186533Y692550D01*
G01X186158Y694733D02*
X186366Y694983D01*
X186491Y695275D01*
X186533Y695650D01*
X186450Y696025D01*
X186283Y696317D01*
X185991Y696525D01*
X185658Y696567D01*
X185325Y696483D01*
X185116Y696275D01*
X184950Y695983D01*
X184908Y695692D01*
X184950Y695400D01*
X185116Y695025D01*
X184033Y695150D01*
Y696275D01*
G01X166249Y701115D02*
X162249D01*
Y693715D01*
G01X207517Y662000D02*
Y664500D01*
X208558D01*
X208892Y664375D01*
X209100Y664208D01*
X209183Y663875D01*
X209100Y663542D01*
X208850Y663333D01*
X208558Y663208D01*
X207517D01*
G01X208558D02*
X209183Y662000D01*
G01X211367D02*
X211450Y662542D01*
X211575Y663000D01*
X211742Y663417D01*
X211950Y663875D01*
X212283Y664500D01*
X210617D01*
G01X214467Y662000D02*
X214550Y662542D01*
X214675Y663000D01*
X214842Y663417D01*
X215050Y663875D01*
X215383Y664500D01*
X213717D01*
G01X217650Y662000D02*
X217942Y662042D01*
X218275Y662167D01*
X218483Y662375D01*
X218567Y662667D01*
X218483Y662958D01*
X218233Y663208D01*
X217858Y663333D01*
X217442D01*
X217192Y663417D01*
X216983Y663625D01*
X216900Y663917D01*
X217025Y664208D01*
X217317Y664417D01*
X217650Y664500D01*
X217983Y664417D01*
X218275Y664208D01*
X218400Y663917D01*
X218317Y663625D01*
X218108Y663417D01*
X217858Y663333D01*
X217442D01*
X217067Y663208D01*
X216817Y662958D01*
X216733Y662667D01*
X216817Y662375D01*
X217025Y662167D01*
X217358Y662042D01*
X217650Y662000D01*
G01X212123Y660996D02*
X208123D01*
Y653596D01*
G01X209517Y646500D02*
Y649000D01*
X210558D01*
X210892Y648875D01*
X211100Y648708D01*
X211183Y648375D01*
X211100Y648042D01*
X210850Y647833D01*
X210558Y647708D01*
X209517D01*
G01X210558D02*
X211183Y646500D01*
G01X213367D02*
X213450Y647042D01*
X213575Y647500D01*
X213742Y647917D01*
X213950Y648375D01*
X214283Y649000D01*
X212617D01*
G01X216467Y646500D02*
X216550Y647042D01*
X216675Y647500D01*
X216842Y647917D01*
X217050Y648375D01*
X217383Y649000D01*
X215717D01*
G01X218942Y646792D02*
X219233Y646583D01*
X219567Y646500D01*
X219900Y646583D01*
X220192Y646833D01*
X220400Y647208D01*
X220483Y647583D01*
Y648042D01*
X220400Y648417D01*
X220192Y648750D01*
X219942Y648917D01*
X219650Y649000D01*
X219317Y648917D01*
X219067Y648750D01*
X218900Y648500D01*
X218817Y648167D01*
X218900Y647875D01*
X219108Y647583D01*
X219358Y647417D01*
X219650Y647375D01*
X219983Y647458D01*
X220233Y647667D01*
X220483Y648042D01*
G01X179417Y681366D02*
Y683866D01*
X180458D01*
X180792Y683741D01*
X181000Y683574D01*
X181083Y683241D01*
X181000Y682908D01*
X180750Y682699D01*
X180458Y682574D01*
X179417D01*
G01X180458D02*
X181083Y681366D01*
G01X183850D02*
Y683866D01*
X182308Y682074D01*
X184392D01*
G01X186450Y681366D02*
X186742Y681408D01*
X187075Y681533D01*
X187283Y681741D01*
X187367Y682033D01*
X187283Y682324D01*
X187033Y682574D01*
X186658Y682699D01*
X186242D01*
X185992Y682783D01*
X185783Y682991D01*
X185700Y683283D01*
X185825Y683574D01*
X186117Y683783D01*
X186450Y683866D01*
X186783Y683783D01*
X187075Y683574D01*
X187200Y683283D01*
X187117Y682991D01*
X186908Y682783D01*
X186658Y682699D01*
X186242D01*
X185867Y682574D01*
X185617Y682324D01*
X185533Y682033D01*
X185617Y681741D01*
X185825Y681533D01*
X186158Y681408D01*
X186450Y681366D01*
G01X188842Y681658D02*
X189133Y681449D01*
X189467Y681366D01*
X189800Y681449D01*
X190092Y681699D01*
X190300Y682074D01*
X190383Y682449D01*
Y682908D01*
X190300Y683283D01*
X190092Y683616D01*
X189842Y683783D01*
X189550Y683866D01*
X189217Y683783D01*
X188967Y683616D01*
X188800Y683366D01*
X188717Y683033D01*
X188800Y682741D01*
X189008Y682449D01*
X189258Y682283D01*
X189550Y682241D01*
X189883Y682324D01*
X190133Y682533D01*
X190383Y682908D01*
G01X209139Y699740D02*
Y697240D01*
G01X208181Y699740D02*
X210097D01*
G01X211406Y697240D02*
Y699740D01*
X212406D01*
X212739Y699615D01*
X212989Y699323D01*
X213072Y698990D01*
X212989Y698657D01*
X212781Y698407D01*
X212406Y698282D01*
X211406D01*
G01X214256Y697240D02*
Y699740D01*
X215339Y697657D01*
X216422Y699740D01*
Y697240D01*
G01X218439D02*
Y699740D01*
X217939Y699240D01*
G01Y697240D02*
X218939D01*
G01X192401Y665921D02*
X235001D01*
Y693921D01*
X192401D01*
Y665921D01*
G01X179892Y666667D02*
Y669167D01*
X181808Y666667D01*
Y669167D01*
G01X183033D02*
Y667375D01*
X183200Y667000D01*
X183533Y666750D01*
X183950Y666667D01*
X184367Y666750D01*
X184700Y667000D01*
X184867Y667375D01*
Y669167D01*
G01X187050D02*
Y666667D01*
G01X186092Y669167D02*
X188008D01*
G01X190150Y666667D02*
Y669167D01*
X189650Y668667D01*
G01Y666667D02*
X190650D01*
G01X188920Y705291D02*
Y716491D01*
G01X206920Y705291D02*
X188920D01*
G01X206920Y716491D02*
Y705291D01*
G01X164017Y711167D02*
Y713667D01*
X165058D01*
X165392Y713542D01*
X165600Y713375D01*
X165683Y713042D01*
X165600Y712709D01*
X165350Y712500D01*
X165058Y712375D01*
X164017D01*
G01X165058D02*
X165683Y711167D01*
G01X168450D02*
Y713667D01*
X166908Y711875D01*
X168992D01*
G01X170342Y711459D02*
X170633Y711250D01*
X170967Y711167D01*
X171300Y711250D01*
X171592Y711500D01*
X171800Y711875D01*
X171883Y712250D01*
Y712709D01*
X171800Y713084D01*
X171592Y713417D01*
X171342Y713584D01*
X171050Y713667D01*
X170717Y713584D01*
X170467Y713417D01*
X170300Y713167D01*
X170217Y712834D01*
X170300Y712542D01*
X170508Y712250D01*
X170758Y712084D01*
X171050Y712042D01*
X171383Y712125D01*
X171633Y712334D01*
X171883Y712709D01*
G01X174150Y711167D02*
X174442Y711209D01*
X174775Y711334D01*
X174983Y711542D01*
X175067Y711834D01*
X174983Y712125D01*
X174733Y712375D01*
X174358Y712500D01*
X173942D01*
X173692Y712584D01*
X173483Y712792D01*
X173400Y713084D01*
X173525Y713375D01*
X173817Y713584D01*
X174150Y713667D01*
X174483Y713584D01*
X174775Y713375D01*
X174900Y713084D01*
X174817Y712792D01*
X174608Y712584D01*
X174358Y712500D01*
X173942D01*
X173567Y712375D01*
X173317Y712125D01*
X173233Y711834D01*
X173317Y711542D01*
X173525Y711334D01*
X173858Y711209D01*
X174150Y711167D01*
G01X148869Y723645D02*
Y728645D01*
X143869D01*
G01X147862Y722719D02*
X150862D01*
G01X147862Y712876D02*
X149862D01*
G01X193767Y747458D02*
X193517Y747583D01*
X193225Y747666D01*
X192892D01*
X192517Y747541D01*
X192225Y747333D01*
X192017Y747083D01*
X191850Y746666D01*
X191808Y746291D01*
X191892Y745916D01*
X192017Y745666D01*
X192267Y745416D01*
X192558Y745249D01*
X192850Y745166D01*
X193142D01*
X193433Y745249D01*
X193683Y745374D01*
X193892Y745541D01*
G01X195950Y745166D02*
Y747666D01*
X195450Y747166D01*
G01Y745166D02*
X196450D01*
G01X198967D02*
X199050Y745708D01*
X199175Y746166D01*
X199342Y746583D01*
X199550Y747041D01*
X199883Y747666D01*
X198217D01*
G01X201233Y745541D02*
X201483Y745333D01*
X201775Y745208D01*
X202150Y745166D01*
X202525Y745249D01*
X202817Y745416D01*
X203025Y745708D01*
X203067Y746041D01*
X202983Y746374D01*
X202775Y746583D01*
X202483Y746749D01*
X202192Y746791D01*
X201900Y746749D01*
X201525Y746583D01*
X201650Y747666D01*
X202775D01*
G01X188920Y743691D02*
Y732491D01*
G01X206920Y743691D02*
X188920D01*
G01X206920Y732491D02*
Y743691D01*
G01X164764Y747442D02*
Y744942D01*
X166430D01*
G01X167989Y745234D02*
X168280Y745025D01*
X168614Y744942D01*
X168947Y745025D01*
X169239Y745275D01*
X169447Y745650D01*
X169530Y746025D01*
Y746484D01*
X169447Y746859D01*
X169239Y747192D01*
X168989Y747359D01*
X168697Y747442D01*
X168364Y747359D01*
X168114Y747192D01*
X167947Y746942D01*
X167864Y746609D01*
X167947Y746317D01*
X168155Y746025D01*
X168405Y745859D01*
X168697Y745817D01*
X169030Y745900D01*
X169280Y746109D01*
X169530Y746484D01*
G01X186947Y714775D02*
X151547D01*
Y742775D01*
X186947D01*
Y714775D01*
G01X306000Y453400D02*
Y436700D01*
G02X305900Y436600I-100J0D01*
G01X265500D01*
Y446000D01*
X275500D01*
Y451733D01*
X278000D01*
Y464863D01*
X275725D01*
Y477151D01*
X278000D01*
Y487000D01*
X274500D01*
Y494000D01*
X272000D01*
Y509850D01*
G01X267867Y463292D02*
X267617Y463417D01*
X267325Y463500D01*
X266992D01*
X266617Y463375D01*
X266325Y463167D01*
X266117Y462917D01*
X265950Y462500D01*
X265908Y462125D01*
X265992Y461750D01*
X266117Y461500D01*
X266367Y461250D01*
X266658Y461083D01*
X266950Y461000D01*
X267242D01*
X267533Y461083D01*
X267783Y461208D01*
X267992Y461375D01*
G01X269967Y461000D02*
X270050Y461542D01*
X270175Y462000D01*
X270342Y462417D01*
X270550Y462875D01*
X270883Y463500D01*
X269217D01*
G01X273650Y461000D02*
Y463500D01*
X272108Y461708D01*
X274192D01*
G01X265917Y478300D02*
Y480800D01*
X266958D01*
X267292Y480675D01*
X267500Y480508D01*
X267583Y480175D01*
X267500Y479842D01*
X267250Y479633D01*
X266958Y479508D01*
X265917D01*
G01X266958D02*
X267583Y478300D01*
G01X269058Y480383D02*
X269308Y480633D01*
X269600Y480758D01*
X269933Y480800D01*
X270350Y480717D01*
X270642Y480508D01*
X270725Y480258D01*
X270683Y480008D01*
X270517Y479800D01*
X269683Y479383D01*
X269308Y479092D01*
X269058Y478675D01*
X268975Y478300D01*
X270725D01*
G01X272158Y479342D02*
X272450Y479633D01*
X272700Y479800D01*
X273033Y479883D01*
X273325Y479800D01*
X273533Y479633D01*
X273700Y479383D01*
X273742Y479092D01*
X273700Y478842D01*
X273533Y478592D01*
X273283Y478383D01*
X272992Y478300D01*
X272658Y478383D01*
X272367Y478633D01*
X272200Y479008D01*
X272158Y479425D01*
X272242Y479967D01*
X272367Y480258D01*
X272575Y480550D01*
X272867Y480758D01*
X273158Y480800D01*
X273450Y480717D01*
X273658Y480508D01*
G01X275258Y479342D02*
X275550Y479633D01*
X275800Y479800D01*
X276133Y479883D01*
X276425Y479800D01*
X276633Y479633D01*
X276800Y479383D01*
X276842Y479092D01*
X276800Y478842D01*
X276633Y478592D01*
X276383Y478383D01*
X276092Y478300D01*
X275758Y478383D01*
X275467Y478633D01*
X275300Y479008D01*
X275258Y479425D01*
X275342Y479967D01*
X275467Y480258D01*
X275675Y480550D01*
X275967Y480758D01*
X276258Y480800D01*
X276550Y480717D01*
X276758Y480508D01*
G01X273400Y468300D02*
Y472300D01*
X266000D01*
G01X266017Y452700D02*
Y455200D01*
X267058D01*
X267392Y455075D01*
X267600Y454908D01*
X267683Y454575D01*
X267600Y454242D01*
X267350Y454033D01*
X267058Y453908D01*
X266017D01*
G01X267058D02*
X267683Y452700D01*
G01X269158Y454783D02*
X269408Y455033D01*
X269700Y455158D01*
X270033Y455200D01*
X270450Y455117D01*
X270742Y454908D01*
X270825Y454658D01*
X270783Y454408D01*
X270617Y454200D01*
X269783Y453783D01*
X269408Y453492D01*
X269158Y453075D01*
X269075Y452700D01*
X270825D01*
G01X272258Y453742D02*
X272550Y454033D01*
X272800Y454200D01*
X273133Y454283D01*
X273425Y454200D01*
X273633Y454033D01*
X273800Y453783D01*
X273842Y453492D01*
X273800Y453242D01*
X273633Y452992D01*
X273383Y452783D01*
X273092Y452700D01*
X272758Y452783D01*
X272467Y453033D01*
X272300Y453408D01*
X272258Y453825D01*
X272342Y454367D01*
X272467Y454658D01*
X272675Y454950D01*
X272967Y455158D01*
X273258Y455200D01*
X273550Y455117D01*
X273758Y454908D01*
G01X276150Y452700D02*
X276442Y452742D01*
X276775Y452867D01*
X276983Y453075D01*
X277067Y453367D01*
X276983Y453658D01*
X276733Y453908D01*
X276358Y454033D01*
X275942D01*
X275692Y454117D01*
X275483Y454325D01*
X275400Y454617D01*
X275525Y454908D01*
X275817Y455117D01*
X276150Y455200D01*
X276483Y455117D01*
X276775Y454908D01*
X276900Y454617D01*
X276817Y454325D01*
X276608Y454117D01*
X276358Y454033D01*
X275942D01*
X275567Y453908D01*
X275317Y453658D01*
X275233Y453367D01*
X275317Y453075D01*
X275525Y452867D01*
X275858Y452742D01*
X276150Y452700D01*
G01X273400Y456200D02*
Y460200D01*
X266000D01*
G01X270833Y493417D02*
X268333D01*
Y494458D01*
X268458Y494792D01*
X268625Y495000D01*
X268958Y495083D01*
X269291Y495000D01*
X269500Y494750D01*
X269625Y494458D01*
Y493417D01*
G01Y494458D02*
X270833Y495083D01*
G01X268750Y496558D02*
X268500Y496808D01*
X268375Y497100D01*
X268333Y497433D01*
X268416Y497850D01*
X268625Y498142D01*
X268875Y498225D01*
X269125Y498183D01*
X269333Y498017D01*
X269750Y497183D01*
X270041Y496808D01*
X270458Y496558D01*
X270833Y496475D01*
Y498225D01*
G01X269791Y499658D02*
X269500Y499950D01*
X269333Y500200D01*
X269250Y500533D01*
X269333Y500825D01*
X269500Y501033D01*
X269750Y501200D01*
X270041Y501242D01*
X270291Y501200D01*
X270541Y501033D01*
X270750Y500783D01*
X270833Y500492D01*
X270750Y500158D01*
X270500Y499867D01*
X270125Y499700D01*
X269708Y499658D01*
X269166Y499742D01*
X268875Y499867D01*
X268583Y500075D01*
X268375Y500367D01*
X268333Y500658D01*
X268416Y500950D01*
X268625Y501158D01*
G01X270833Y503467D02*
X270291Y503550D01*
X269833Y503675D01*
X269416Y503842D01*
X268958Y504050D01*
X268333Y504383D01*
Y502717D01*
G01X273800Y487500D02*
Y491500D01*
X266400D01*
G01X277122Y487821D02*
Y490321D01*
X278163D01*
X278497Y490196D01*
X278705Y490029D01*
X278788Y489696D01*
X278705Y489363D01*
X278455Y489154D01*
X278163Y489029D01*
X277122D01*
G01X278163D02*
X278788Y487821D01*
G01X280138Y488321D02*
X280388Y488029D01*
X280722Y487863D01*
X281097Y487821D01*
X281430Y487863D01*
X281763Y488071D01*
X281972Y488321D01*
X282013Y488571D01*
X281930Y488863D01*
X281638Y489071D01*
X281347Y489154D01*
X280972D01*
G01X281347D02*
X281597Y489279D01*
X281805Y489488D01*
X281888Y489738D01*
X281805Y489988D01*
X281597Y490196D01*
X281222Y490321D01*
X280847Y490279D01*
X280472Y490113D01*
G01X284655Y487821D02*
Y490321D01*
X283113Y488529D01*
X285197D01*
G01X287255Y490321D02*
X286922Y490238D01*
X286672Y490029D01*
X286505Y489779D01*
X286380Y489446D01*
X286338Y489071D01*
X286380Y488696D01*
X286505Y488363D01*
X286672Y488113D01*
X286922Y487904D01*
X287255Y487821D01*
X287588Y487904D01*
X287838Y488113D01*
X288005Y488363D01*
X288130Y488696D01*
X288172Y489071D01*
X288130Y489446D01*
X288005Y489779D01*
X287838Y490029D01*
X287588Y490238D01*
X287255Y490321D01*
G01X277486Y473340D02*
Y475840D01*
X278527D01*
X278861Y475715D01*
X279069Y475548D01*
X279152Y475215D01*
X279069Y474882D01*
X278819Y474673D01*
X278527Y474548D01*
X277486D01*
G01X278527D02*
X279152Y473340D01*
G01X280502Y473840D02*
X280752Y473548D01*
X281086Y473382D01*
X281461Y473340D01*
X281794Y473382D01*
X282127Y473590D01*
X282336Y473840D01*
X282377Y474090D01*
X282294Y474382D01*
X282002Y474590D01*
X281711Y474673D01*
X281336D01*
G01X281711D02*
X281961Y474798D01*
X282169Y475007D01*
X282252Y475257D01*
X282169Y475507D01*
X281961Y475715D01*
X281586Y475840D01*
X281211Y475798D01*
X280836Y475632D01*
G01X283602Y473840D02*
X283852Y473548D01*
X284186Y473382D01*
X284561Y473340D01*
X284894Y473382D01*
X285227Y473590D01*
X285436Y473840D01*
X285477Y474090D01*
X285394Y474382D01*
X285102Y474590D01*
X284811Y474673D01*
X284436D01*
G01X284811D02*
X285061Y474798D01*
X285269Y475007D01*
X285352Y475257D01*
X285269Y475507D01*
X285061Y475715D01*
X284686Y475840D01*
X284311Y475798D01*
X283936Y475632D01*
G01X287619Y473340D02*
X287911Y473382D01*
X288244Y473507D01*
X288452Y473715D01*
X288536Y474007D01*
X288452Y474298D01*
X288202Y474548D01*
X287827Y474673D01*
X287411D01*
X287161Y474757D01*
X286952Y474965D01*
X286869Y475257D01*
X286994Y475548D01*
X287286Y475757D01*
X287619Y475840D01*
X287952Y475757D01*
X288244Y475548D01*
X288369Y475257D01*
X288286Y474965D01*
X288077Y474757D01*
X287827Y474673D01*
X287411D01*
X287036Y474548D01*
X286786Y474298D01*
X286702Y474007D01*
X286786Y473715D01*
X286994Y473507D01*
X287327Y473382D01*
X287619Y473340D01*
G01X280517Y441000D02*
Y443500D01*
X281558D01*
X281892Y443375D01*
X282100Y443208D01*
X282183Y442875D01*
X282100Y442542D01*
X281850Y442333D01*
X281558Y442208D01*
X280517D01*
G01X281558D02*
X282183Y441000D01*
G01X283658Y443083D02*
X283908Y443333D01*
X284200Y443458D01*
X284533Y443500D01*
X284950Y443417D01*
X285242Y443208D01*
X285325Y442958D01*
X285283Y442708D01*
X285117Y442500D01*
X284283Y442083D01*
X283908Y441792D01*
X283658Y441375D01*
X283575Y441000D01*
X285325D01*
G01X287467D02*
X287550Y441542D01*
X287675Y442000D01*
X287842Y442417D01*
X288050Y442875D01*
X288383Y443500D01*
X286717D01*
G01X290650Y441000D02*
Y443500D01*
X290150Y443000D01*
G01Y441000D02*
X291150D01*
G01X277517Y465812D02*
Y468312D01*
X278558D01*
X278892Y468187D01*
X279100Y468020D01*
X279183Y467687D01*
X279100Y467354D01*
X278850Y467145D01*
X278558Y467020D01*
X277517D01*
G01X278558D02*
X279183Y465812D01*
G01X281450D02*
Y468312D01*
X280950Y467812D01*
G01Y465812D02*
X281950D01*
G01X283758Y466854D02*
X284050Y467145D01*
X284300Y467312D01*
X284633Y467395D01*
X284925Y467312D01*
X285133Y467145D01*
X285300Y466895D01*
X285342Y466604D01*
X285300Y466354D01*
X285133Y466104D01*
X284883Y465895D01*
X284592Y465812D01*
X284258Y465895D01*
X283967Y466145D01*
X283800Y466520D01*
X283758Y466937D01*
X283842Y467479D01*
X283967Y467770D01*
X284175Y468062D01*
X284467Y468270D01*
X284758Y468312D01*
X285050Y468229D01*
X285258Y468020D01*
G01X286858Y466854D02*
X287150Y467145D01*
X287400Y467312D01*
X287733Y467395D01*
X288025Y467312D01*
X288233Y467145D01*
X288400Y466895D01*
X288442Y466604D01*
X288400Y466354D01*
X288233Y466104D01*
X287983Y465895D01*
X287692Y465812D01*
X287358Y465895D01*
X287067Y466145D01*
X286900Y466520D01*
X286858Y466937D01*
X286942Y467479D01*
X287067Y467770D01*
X287275Y468062D01*
X287567Y468270D01*
X287858Y468312D01*
X288150Y468229D01*
X288358Y468020D01*
G01X277611Y469562D02*
Y472062D01*
X278652D01*
X278986Y471937D01*
X279194Y471770D01*
X279277Y471437D01*
X279194Y471104D01*
X278944Y470895D01*
X278652Y470770D01*
X277611D01*
G01X278652D02*
X279277Y469562D01*
G01X281544D02*
Y472062D01*
X281044Y471562D01*
G01Y469562D02*
X282044D01*
G01X283852Y470604D02*
X284144Y470895D01*
X284394Y471062D01*
X284727Y471145D01*
X285019Y471062D01*
X285227Y470895D01*
X285394Y470645D01*
X285436Y470354D01*
X285394Y470104D01*
X285227Y469854D01*
X284977Y469645D01*
X284686Y469562D01*
X284352Y469645D01*
X284061Y469895D01*
X283894Y470270D01*
X283852Y470687D01*
X283936Y471229D01*
X284061Y471520D01*
X284269Y471812D01*
X284561Y472020D01*
X284852Y472062D01*
X285144Y471979D01*
X285352Y471770D01*
G01X288244Y469562D02*
Y472062D01*
X286702Y470270D01*
X288786D01*
G01X279217Y457600D02*
Y460100D01*
X280258D01*
X280592Y459975D01*
X280800Y459808D01*
X280883Y459475D01*
X280800Y459142D01*
X280550Y458933D01*
X280258Y458808D01*
X279217D01*
G01X280258D02*
X280883Y457600D01*
G01X283150D02*
Y460100D01*
X282650Y459600D01*
G01Y457600D02*
X283650D01*
G01X285458Y458642D02*
X285750Y458933D01*
X286000Y459100D01*
X286333Y459183D01*
X286625Y459100D01*
X286833Y458933D01*
X287000Y458683D01*
X287042Y458392D01*
X287000Y458142D01*
X286833Y457892D01*
X286583Y457683D01*
X286292Y457600D01*
X285958Y457683D01*
X285667Y457933D01*
X285500Y458308D01*
X285458Y458725D01*
X285542Y459267D01*
X285667Y459558D01*
X285875Y459850D01*
X286167Y460058D01*
X286458Y460100D01*
X286750Y460017D01*
X286958Y459808D01*
G01X288558Y459683D02*
X288808Y459933D01*
X289100Y460058D01*
X289433Y460100D01*
X289850Y460017D01*
X290142Y459808D01*
X290225Y459558D01*
X290183Y459308D01*
X290017Y459100D01*
X289183Y458683D01*
X288808Y458392D01*
X288558Y457975D01*
X288475Y457600D01*
X290225D01*
G01X279317Y453800D02*
Y456300D01*
X280358D01*
X280692Y456175D01*
X280900Y456008D01*
X280983Y455675D01*
X280900Y455342D01*
X280650Y455133D01*
X280358Y455008D01*
X279317D01*
G01X280358D02*
X280983Y453800D01*
G01X283250D02*
Y456300D01*
X282750Y455800D01*
G01Y453800D02*
X283750D01*
G01X285558Y454842D02*
X285850Y455133D01*
X286100Y455300D01*
X286433Y455383D01*
X286725Y455300D01*
X286933Y455133D01*
X287100Y454883D01*
X287142Y454592D01*
X287100Y454342D01*
X286933Y454092D01*
X286683Y453883D01*
X286392Y453800D01*
X286058Y453883D01*
X285767Y454133D01*
X285600Y454508D01*
X285558Y454925D01*
X285642Y455467D01*
X285767Y455758D01*
X285975Y456050D01*
X286267Y456258D01*
X286558Y456300D01*
X286850Y456217D01*
X287058Y456008D01*
G01X289450Y456300D02*
X289117Y456217D01*
X288867Y456008D01*
X288700Y455758D01*
X288575Y455425D01*
X288533Y455050D01*
X288575Y454675D01*
X288700Y454342D01*
X288867Y454092D01*
X289117Y453883D01*
X289450Y453800D01*
X289783Y453883D01*
X290033Y454092D01*
X290200Y454342D01*
X290325Y454675D01*
X290367Y455050D01*
X290325Y455425D01*
X290200Y455758D01*
X290033Y456008D01*
X289783Y456217D01*
X289450Y456300D01*
G01X280517Y444667D02*
Y447167D01*
X281558D01*
X281892Y447042D01*
X282100Y446875D01*
X282183Y446542D01*
X282100Y446209D01*
X281850Y446000D01*
X281558Y445875D01*
X280517D01*
G01X281558D02*
X282183Y444667D01*
G01X284450D02*
Y447167D01*
X283950Y446667D01*
G01Y444667D02*
X284950D01*
G01X286633Y445042D02*
X286883Y444834D01*
X287175Y444709D01*
X287550Y444667D01*
X287925Y444750D01*
X288217Y444917D01*
X288425Y445209D01*
X288467Y445542D01*
X288383Y445875D01*
X288175Y446084D01*
X287883Y446250D01*
X287592Y446292D01*
X287300Y446250D01*
X286925Y446084D01*
X287050Y447167D01*
X288175D01*
G01X290567Y444667D02*
X290650Y445209D01*
X290775Y445667D01*
X290942Y446084D01*
X291150Y446542D01*
X291483Y447167D01*
X289817D01*
G01X280417Y448800D02*
Y451300D01*
X281458D01*
X281792Y451175D01*
X282000Y451008D01*
X282083Y450675D01*
X282000Y450342D01*
X281750Y450133D01*
X281458Y450008D01*
X280417D01*
G01X281458D02*
X282083Y448800D01*
G01X284350D02*
Y451300D01*
X283850Y450800D01*
G01Y448800D02*
X284850D01*
G01X286533Y449175D02*
X286783Y448967D01*
X287075Y448842D01*
X287450Y448800D01*
X287825Y448883D01*
X288117Y449050D01*
X288325Y449342D01*
X288367Y449675D01*
X288283Y450008D01*
X288075Y450217D01*
X287783Y450383D01*
X287492Y450425D01*
X287200Y450383D01*
X286825Y450217D01*
X286950Y451300D01*
X288075D01*
G01X289633Y449175D02*
X289883Y448967D01*
X290175Y448842D01*
X290550Y448800D01*
X290925Y448883D01*
X291217Y449050D01*
X291425Y449342D01*
X291467Y449675D01*
X291383Y450008D01*
X291175Y450217D01*
X290883Y450383D01*
X290592Y450425D01*
X290300Y450383D01*
X289925Y450217D01*
X290050Y451300D01*
X291175D01*
G01X265917Y482300D02*
Y484800D01*
X266958D01*
X267292Y484675D01*
X267500Y484508D01*
X267583Y484175D01*
X267500Y483842D01*
X267250Y483633D01*
X266958Y483508D01*
X265917D01*
G01X266958D02*
X267583Y482300D01*
G01X269767D02*
X269850Y482842D01*
X269975Y483300D01*
X270142Y483717D01*
X270350Y484175D01*
X270683Y484800D01*
X269017D01*
G01X272158Y483342D02*
X272450Y483633D01*
X272700Y483800D01*
X273033Y483883D01*
X273325Y483800D01*
X273533Y483633D01*
X273700Y483383D01*
X273742Y483092D01*
X273700Y482842D01*
X273533Y482592D01*
X273283Y482383D01*
X272992Y482300D01*
X272658Y482383D01*
X272367Y482633D01*
X272200Y483008D01*
X272158Y483425D01*
X272242Y483967D01*
X272367Y484258D01*
X272575Y484550D01*
X272867Y484758D01*
X273158Y484800D01*
X273450Y484717D01*
X273658Y484508D01*
G01X276550Y482300D02*
Y484800D01*
X275008Y483008D01*
X277092D01*
G01X266000Y476380D02*
Y472380D01*
X273400D01*
G01X267650Y440900D02*
Y438400D01*
G01X266692Y440900D02*
X268608D01*
G01X269917Y438400D02*
Y440900D01*
X270917D01*
X271250Y440775D01*
X271500Y440483D01*
X271583Y440150D01*
X271500Y439817D01*
X271292Y439567D01*
X270917Y439442D01*
X269917D01*
G01X273767Y438400D02*
X273850Y438942D01*
X273975Y439400D01*
X274142Y439817D01*
X274350Y440275D01*
X274683Y440900D01*
X273017D01*
G01X276033Y438775D02*
X276283Y438567D01*
X276575Y438442D01*
X276950Y438400D01*
X277325Y438483D01*
X277617Y438650D01*
X277825Y438942D01*
X277867Y439275D01*
X277783Y439608D01*
X277575Y439817D01*
X277283Y439983D01*
X276992Y440025D01*
X276700Y439983D01*
X276325Y439817D01*
X276450Y440900D01*
X277575D01*
G01X267650Y444500D02*
Y442000D01*
G01X266692Y444500D02*
X268608D01*
G01X269917Y442000D02*
Y444500D01*
X270917D01*
X271250Y444375D01*
X271500Y444083D01*
X271583Y443750D01*
X271500Y443417D01*
X271292Y443167D01*
X270917Y443042D01*
X269917D01*
G01X272933Y442375D02*
X273183Y442167D01*
X273475Y442042D01*
X273850Y442000D01*
X274225Y442083D01*
X274517Y442250D01*
X274725Y442542D01*
X274767Y442875D01*
X274683Y443208D01*
X274475Y443417D01*
X274183Y443583D01*
X273892Y443625D01*
X273600Y443583D01*
X273225Y443417D01*
X273350Y444500D01*
X274475D01*
G01X276033Y442375D02*
X276283Y442167D01*
X276575Y442042D01*
X276950Y442000D01*
X277325Y442083D01*
X277617Y442250D01*
X277825Y442542D01*
X277867Y442875D01*
X277783Y443208D01*
X277575Y443417D01*
X277283Y443583D01*
X276992Y443625D01*
X276700Y443583D01*
X276325Y443417D01*
X276450Y444500D01*
X277575D01*
G01X239800Y457770D02*
X241770Y455800D01*
G01X237830D02*
X239800Y457770D01*
G01X252500Y496500D02*
Y455800D01*
G01X227100D02*
Y496500D01*
G01X252500Y455800D02*
X227100D01*
G01X214600Y508900D02*
Y446700D01*
X265000D01*
Y508900D01*
X214600D01*
G01X244100Y446750D02*
X239500Y451350D01*
X234850Y446700D01*
G01X274854Y500555D02*
X278187Y507555D01*
X281520Y500555D01*
G01X280320Y503005D02*
X276054D01*
G01X227804Y553625D02*
X231137Y560625D01*
X234470Y553625D01*
G01X233270Y556075D02*
X229004D01*
G01X247695Y514584D02*
X251195Y519584D01*
G01X247695D02*
X251195Y514584D01*
G01X253462Y518751D02*
X253962Y519251D01*
X254545Y519501D01*
X255212Y519584D01*
X256045Y519417D01*
X256628Y519001D01*
X256795Y518501D01*
X256712Y518001D01*
X256378Y517584D01*
X254712Y516751D01*
X253962Y516167D01*
X253462Y515334D01*
X253295Y514584D01*
X256795D01*
G01X260645Y514417D02*
X260478Y514501D01*
Y514667D01*
X260645Y514751D01*
X260812Y514667D01*
Y514501D01*
X260645Y514417D01*
G01Y516667D02*
X260478Y516751D01*
Y516917D01*
X260645Y517001D01*
X260812Y516917D01*
Y516751D01*
X260645Y516667D01*
G01X264412Y515334D02*
X264912Y514917D01*
X265495Y514667D01*
X266245Y514584D01*
X266995Y514751D01*
X267578Y515084D01*
X267995Y515667D01*
X268078Y516334D01*
X267912Y517001D01*
X267495Y517417D01*
X266912Y517751D01*
X266328Y517834D01*
X265745Y517751D01*
X264995Y517417D01*
X265245Y519584D01*
X267495D01*
G01X271845D02*
X271178Y519417D01*
X270678Y519001D01*
X270345Y518501D01*
X270095Y517834D01*
X270012Y517084D01*
X270095Y516334D01*
X270345Y515667D01*
X270678Y515167D01*
X271178Y514751D01*
X271845Y514584D01*
X272512Y514751D01*
X273012Y515167D01*
X273345Y515667D01*
X273595Y516334D01*
X273678Y517084D01*
X273595Y517834D01*
X273345Y518501D01*
X273012Y519001D01*
X272512Y519417D01*
X271845Y519584D01*
G01X275278Y514584D02*
Y519584D01*
X277445Y515417D01*
X279612Y519584D01*
Y514584D01*
G01X281295D02*
Y519584D01*
G01X284795D02*
Y514584D01*
G01Y517084D02*
X281295D01*
G01X287062Y519584D02*
X290228D01*
X287062Y514584D01*
X290228D01*
G01X279500Y557000D02*
X293038D01*
Y578573D01*
G01X274000Y557000D02*
X270500D01*
Y545000D01*
G01Y537000D02*
Y535000D01*
X277500D01*
Y521000D01*
X280500D01*
G01X273463Y512892D02*
X301000D01*
G01X251549Y529186D02*
Y522198D01*
X246000D01*
Y511300D01*
X231300D01*
Y509994D01*
X223100D01*
G01X254500Y563999D02*
Y553500D01*
X251549D01*
Y547400D01*
G01X226500Y582000D02*
Y547400D01*
X251549D01*
Y532846D01*
G01X283191Y566515D02*
X283066Y566265D01*
X282983Y565973D01*
Y565640D01*
X283108Y565265D01*
X283316Y564973D01*
X283566Y564765D01*
X283983Y564598D01*
X284358Y564556D01*
X284733Y564640D01*
X284983Y564765D01*
X285233Y565015D01*
X285400Y565306D01*
X285483Y565598D01*
Y565890D01*
X285400Y566181D01*
X285275Y566431D01*
X285108Y566640D01*
G01X285483Y568615D02*
X284941Y568698D01*
X284483Y568823D01*
X284066Y568990D01*
X283608Y569198D01*
X282983Y569531D01*
Y567865D01*
G01X284441Y571006D02*
X284150Y571298D01*
X283983Y571548D01*
X283900Y571881D01*
X283983Y572173D01*
X284150Y572381D01*
X284400Y572548D01*
X284691Y572590D01*
X284941Y572548D01*
X285191Y572381D01*
X285400Y572131D01*
X285483Y571840D01*
X285400Y571506D01*
X285150Y571215D01*
X284775Y571048D01*
X284358Y571006D01*
X283816Y571090D01*
X283525Y571215D01*
X283233Y571423D01*
X283025Y571715D01*
X282983Y572006D01*
X283066Y572298D01*
X283275Y572506D01*
G01X269533Y560906D02*
Y563406D01*
X270574D01*
X270908Y563281D01*
X271116Y563114D01*
X271199Y562781D01*
X271116Y562448D01*
X270866Y562239D01*
X270574Y562114D01*
X269533D01*
G01X270574D02*
X271199Y560906D01*
G01X272549Y561281D02*
X272799Y561073D01*
X273091Y560948D01*
X273466Y560906D01*
X273841Y560989D01*
X274133Y561156D01*
X274341Y561448D01*
X274383Y561781D01*
X274299Y562114D01*
X274091Y562323D01*
X273799Y562489D01*
X273508Y562531D01*
X273216Y562489D01*
X272841Y562323D01*
X272966Y563406D01*
X274091D01*
G01X275774Y562989D02*
X276024Y563239D01*
X276316Y563364D01*
X276649Y563406D01*
X277066Y563323D01*
X277358Y563114D01*
X277441Y562864D01*
X277399Y562614D01*
X277233Y562406D01*
X276399Y561989D01*
X276024Y561698D01*
X275774Y561281D01*
X275691Y560906D01*
X277441D01*
G01X279045Y563694D02*
Y559694D01*
X286445D01*
G01X264566Y538233D02*
X262066D01*
Y539274D01*
X262191Y539608D01*
X262358Y539816D01*
X262691Y539899D01*
X263024Y539816D01*
X263233Y539566D01*
X263358Y539274D01*
Y538233D01*
G01Y539274D02*
X264566Y539899D01*
G01X264191Y541249D02*
X264399Y541499D01*
X264524Y541791D01*
X264566Y542166D01*
X264483Y542541D01*
X264316Y542833D01*
X264024Y543041D01*
X263691Y543083D01*
X263358Y542999D01*
X263149Y542791D01*
X262983Y542499D01*
X262941Y542208D01*
X262983Y541916D01*
X263149Y541541D01*
X262066Y541666D01*
Y542791D01*
G01X264274Y544558D02*
X264483Y544849D01*
X264566Y545183D01*
X264483Y545516D01*
X264233Y545808D01*
X263858Y546016D01*
X263483Y546099D01*
X263024D01*
X262649Y546016D01*
X262316Y545808D01*
X262149Y545558D01*
X262066Y545266D01*
X262149Y544933D01*
X262316Y544683D01*
X262566Y544516D01*
X262899Y544433D01*
X263191Y544516D01*
X263483Y544724D01*
X263649Y544974D01*
X263691Y545266D01*
X263608Y545599D01*
X263399Y545849D01*
X263024Y546099D01*
G01X269514Y545985D02*
X265514D01*
Y538585D01*
G01X245700Y557500D02*
X241700D01*
Y550100D01*
G01X243263Y537142D02*
Y541142D01*
X235863D01*
G01X245996Y559061D02*
Y555061D01*
X253396D01*
G01X246077Y565068D02*
Y561068D01*
X253477D01*
G01X248725Y569260D02*
Y565260D01*
X256125D01*
G01X250828Y534660D02*
Y538660D01*
X243428D01*
G01X221200Y510066D02*
Y514066D01*
X213800D01*
G01X255367Y556000D02*
Y558500D01*
X256408D01*
X256742Y558375D01*
X256950Y558208D01*
X257033Y557875D01*
X256950Y557542D01*
X256700Y557333D01*
X256408Y557208D01*
X255367D01*
G01X256408D02*
X257033Y556000D01*
G01X258383Y556375D02*
X258633Y556167D01*
X258925Y556042D01*
X259300Y556000D01*
X259675Y556083D01*
X259967Y556250D01*
X260175Y556542D01*
X260217Y556875D01*
X260133Y557208D01*
X259925Y557417D01*
X259633Y557583D01*
X259342Y557625D01*
X259050Y557583D01*
X258675Y557417D01*
X258800Y558500D01*
X259925D01*
G01X261608Y557042D02*
X261900Y557333D01*
X262150Y557500D01*
X262483Y557583D01*
X262775Y557500D01*
X262983Y557333D01*
X263150Y557083D01*
X263192Y556792D01*
X263150Y556542D01*
X262983Y556292D01*
X262733Y556083D01*
X262442Y556000D01*
X262108Y556083D01*
X261817Y556333D01*
X261650Y556708D01*
X261608Y557125D01*
X261692Y557667D01*
X261817Y557958D01*
X262025Y558250D01*
X262317Y558458D01*
X262608Y558500D01*
X262900Y558417D01*
X263108Y558208D01*
G01X262000Y555100D02*
Y551100D01*
X269400D01*
G01X270425Y543121D02*
Y539121D01*
X277825D01*
G01X248638Y526501D02*
Y530501D01*
X241238D01*
G01X237596Y562398D02*
Y558398D01*
X244996D01*
G01X237596Y566498D02*
Y562498D01*
X244996D01*
G01X241109Y522700D02*
Y526700D01*
X233709D01*
G01X241000Y518563D02*
Y522563D01*
X233600D01*
G01X223262Y513180D02*
X227262D01*
Y520580D01*
G01X231342Y520355D02*
X227342D01*
Y512955D01*
G01X256000Y532017D02*
X253500D01*
Y533058D01*
X253625Y533392D01*
X253792Y533600D01*
X254125Y533683D01*
X254458Y533600D01*
X254667Y533350D01*
X254792Y533058D01*
Y532017D01*
G01Y533058D02*
X256000Y533683D01*
G01Y535867D02*
X255458Y535950D01*
X255000Y536075D01*
X254583Y536242D01*
X254125Y536450D01*
X253500Y536783D01*
Y535117D01*
G01X255500Y538133D02*
X255792Y538383D01*
X255958Y538717D01*
X256000Y539092D01*
X255958Y539425D01*
X255750Y539758D01*
X255500Y539967D01*
X255250Y540008D01*
X254958Y539925D01*
X254750Y539633D01*
X254667Y539342D01*
Y538967D01*
G01Y539342D02*
X254542Y539592D01*
X254333Y539800D01*
X254083Y539883D01*
X253833Y539800D01*
X253625Y539592D01*
X253500Y539217D01*
X253542Y538842D01*
X253708Y538467D01*
G01X256000Y542150D02*
X253500D01*
X254000Y541650D01*
G01X256000D02*
Y542650D01*
G01X256969Y539521D02*
X260969D01*
Y546921D01*
G01X281500Y529300D02*
Y525300D01*
X288900D01*
G01X281600Y524800D02*
Y520800D01*
X289000D01*
G01X281600Y537000D02*
Y533000D01*
X289000D01*
G01X274253Y498240D02*
Y495740D01*
G01X273295Y498240D02*
X275211D01*
G01X276520Y495740D02*
Y498240D01*
X277520D01*
X277853Y498115D01*
X278103Y497823D01*
X278186Y497490D01*
X278103Y497157D01*
X277895Y496907D01*
X277520Y496782D01*
X276520D01*
G01X279536Y496115D02*
X279786Y495907D01*
X280078Y495782D01*
X280453Y495740D01*
X280828Y495823D01*
X281120Y495990D01*
X281328Y496282D01*
X281370Y496615D01*
X281286Y496948D01*
X281078Y497157D01*
X280786Y497323D01*
X280495Y497365D01*
X280203Y497323D01*
X279828Y497157D01*
X279953Y498240D01*
X281078D01*
G01X283553D02*
X283220Y498157D01*
X282970Y497948D01*
X282803Y497698D01*
X282678Y497365D01*
X282636Y496990D01*
X282678Y496615D01*
X282803Y496282D01*
X282970Y496032D01*
X283220Y495823D01*
X283553Y495740D01*
X283886Y495823D01*
X284136Y496032D01*
X284303Y496282D01*
X284428Y496615D01*
X284470Y496990D01*
X284428Y497365D01*
X284303Y497698D01*
X284136Y497948D01*
X283886Y498157D01*
X283553Y498240D01*
G01X227100Y496500D02*
X252500D01*
G01X271245Y543694D02*
X284645D01*
G01X271245Y555094D02*
Y543694D01*
G01X284645Y555094D02*
X271245D01*
G01X214200Y635000D02*
X221600D01*
G01X226500Y591700D02*
Y585300D01*
G01X235649Y618500D02*
X228000D01*
G01X220146Y620568D02*
X228000D01*
Y599000D01*
X226500D01*
Y595400D01*
G01X225200Y635000D02*
X226000D01*
Y645500D01*
X240500D01*
Y628000D01*
G01X255521Y610173D02*
Y636537D01*
X240500D01*
G01X260658Y595042D02*
Y597210D01*
X255521D01*
Y598844D01*
G01X255816Y569833D02*
Y581419D01*
X260658D01*
Y591255D01*
G01X281767Y628792D02*
X281517Y628917D01*
X281225Y629000D01*
X280892D01*
X280517Y628875D01*
X280225Y628667D01*
X280017Y628417D01*
X279850Y628000D01*
X279808Y627625D01*
X279892Y627250D01*
X280017Y627000D01*
X280267Y626750D01*
X280558Y626583D01*
X280850Y626500D01*
X281142D01*
X281433Y626583D01*
X281683Y626708D01*
X281892Y626875D01*
G01X283158Y628583D02*
X283408Y628833D01*
X283700Y628958D01*
X284033Y629000D01*
X284450Y628917D01*
X284742Y628708D01*
X284825Y628458D01*
X284783Y628208D01*
X284617Y628000D01*
X283783Y627583D01*
X283408Y627292D01*
X283158Y626875D01*
X283075Y626500D01*
X284825D01*
G01X287550D02*
Y629000D01*
X286008Y627208D01*
X288092D01*
G01X290150Y629000D02*
X289817Y628917D01*
X289567Y628708D01*
X289400Y628458D01*
X289275Y628125D01*
X289233Y627750D01*
X289275Y627375D01*
X289400Y627042D01*
X289567Y626792D01*
X289817Y626583D01*
X290150Y626500D01*
X290483Y626583D01*
X290733Y626792D01*
X290900Y627042D01*
X291025Y627375D01*
X291067Y627750D01*
X291025Y628125D01*
X290900Y628458D01*
X290733Y628708D01*
X290483Y628917D01*
X290150Y629000D01*
G01X260208Y612767D02*
X260083Y612517D01*
X260000Y612225D01*
Y611892D01*
X260125Y611517D01*
X260333Y611225D01*
X260583Y611017D01*
X261000Y610850D01*
X261375Y610808D01*
X261750Y610892D01*
X262000Y611017D01*
X262250Y611267D01*
X262417Y611558D01*
X262500Y611850D01*
Y612142D01*
X262417Y612433D01*
X262292Y612683D01*
X262125Y612892D01*
G01Y614033D02*
X262333Y614283D01*
X262458Y614575D01*
X262500Y614950D01*
X262417Y615325D01*
X262250Y615617D01*
X261958Y615825D01*
X261625Y615867D01*
X261292Y615783D01*
X261083Y615575D01*
X260917Y615283D01*
X260875Y614992D01*
X260917Y614700D01*
X261083Y614325D01*
X260000Y614450D01*
Y615575D01*
G01X262500Y618050D02*
X260000D01*
X260500Y617550D01*
G01X262500D02*
Y618550D01*
G01Y621150D02*
X262458Y621442D01*
X262333Y621775D01*
X262125Y621983D01*
X261833Y622067D01*
X261542Y621983D01*
X261292Y621733D01*
X261167Y621358D01*
Y620942D01*
X261083Y620692D01*
X260875Y620483D01*
X260583Y620400D01*
X260292Y620525D01*
X260083Y620817D01*
X260000Y621150D01*
X260083Y621483D01*
X260292Y621775D01*
X260583Y621900D01*
X260875Y621817D01*
X261083Y621608D01*
X261167Y621358D01*
Y620942D01*
X261292Y620567D01*
X261542Y620317D01*
X261833Y620233D01*
X262125Y620317D01*
X262333Y620525D01*
X262458Y620858D01*
X262500Y621150D01*
G01X278655Y568162D02*
X278530Y567912D01*
X278447Y567620D01*
Y567287D01*
X278572Y566912D01*
X278780Y566620D01*
X279030Y566412D01*
X279447Y566245D01*
X279822Y566203D01*
X280197Y566287D01*
X280447Y566412D01*
X280697Y566662D01*
X280864Y566953D01*
X280947Y567245D01*
Y567537D01*
X280864Y567828D01*
X280739Y568078D01*
X280572Y568287D01*
G01Y569428D02*
X280780Y569678D01*
X280905Y569970D01*
X280947Y570345D01*
X280864Y570720D01*
X280697Y571012D01*
X280405Y571220D01*
X280072Y571262D01*
X279739Y571178D01*
X279530Y570970D01*
X279364Y570678D01*
X279322Y570387D01*
X279364Y570095D01*
X279530Y569720D01*
X278447Y569845D01*
Y570970D01*
G01X280947Y573445D02*
X278447D01*
X278947Y572945D01*
G01X280947D02*
Y573945D01*
G01X280447Y575628D02*
X280739Y575878D01*
X280905Y576212D01*
X280947Y576587D01*
X280905Y576920D01*
X280697Y577253D01*
X280447Y577462D01*
X280197Y577503D01*
X279905Y577420D01*
X279697Y577128D01*
X279614Y576837D01*
Y576462D01*
G01Y576837D02*
X279489Y577087D01*
X279280Y577295D01*
X279030Y577378D01*
X278780Y577295D01*
X278572Y577087D01*
X278447Y576712D01*
X278489Y576337D01*
X278655Y575962D01*
G01X272317Y631792D02*
X272067Y631917D01*
X271775Y632000D01*
X271442D01*
X271067Y631875D01*
X270775Y631667D01*
X270567Y631417D01*
X270400Y631000D01*
X270358Y630625D01*
X270442Y630250D01*
X270567Y630000D01*
X270817Y629750D01*
X271108Y629583D01*
X271400Y629500D01*
X271692D01*
X271983Y629583D01*
X272233Y629708D01*
X272442Y629875D01*
G01X273583D02*
X273833Y629667D01*
X274125Y629542D01*
X274500Y629500D01*
X274875Y629583D01*
X275167Y629750D01*
X275375Y630042D01*
X275417Y630375D01*
X275333Y630708D01*
X275125Y630917D01*
X274833Y631083D01*
X274542Y631125D01*
X274250Y631083D01*
X273875Y630917D01*
X274000Y632000D01*
X275125D01*
G01X276808Y631583D02*
X277058Y631833D01*
X277350Y631958D01*
X277683Y632000D01*
X278100Y631917D01*
X278392Y631708D01*
X278475Y631458D01*
X278433Y631208D01*
X278267Y631000D01*
X277433Y630583D01*
X277058Y630292D01*
X276808Y629875D01*
X276725Y629500D01*
X278475D01*
G01X246067Y637500D02*
Y640000D01*
X247108D01*
X247442Y639875D01*
X247650Y639708D01*
X247733Y639375D01*
X247650Y639042D01*
X247400Y638833D01*
X247108Y638708D01*
X246067D01*
G01X247108D02*
X247733Y637500D01*
G01X249917D02*
X250000Y638042D01*
X250125Y638500D01*
X250292Y638917D01*
X250500Y639375D01*
X250833Y640000D01*
X249167D01*
G01X252308Y639583D02*
X252558Y639833D01*
X252850Y639958D01*
X253183Y640000D01*
X253600Y639917D01*
X253892Y639708D01*
X253975Y639458D01*
X253933Y639208D01*
X253767Y639000D01*
X252933Y638583D01*
X252558Y638292D01*
X252308Y637875D01*
X252225Y637500D01*
X253975D01*
G01X238000Y644600D02*
X234000D01*
Y637200D01*
G01X225400Y643400D02*
X221400D01*
Y636000D01*
G01X261048Y601268D02*
Y603768D01*
X262089D01*
X262423Y603643D01*
X262631Y603476D01*
X262714Y603143D01*
X262631Y602810D01*
X262381Y602601D01*
X262089Y602476D01*
X261048D01*
G01X262089D02*
X262714Y601268D01*
G01X264064Y601768D02*
X264314Y601476D01*
X264648Y601310D01*
X265023Y601268D01*
X265356Y601310D01*
X265689Y601518D01*
X265898Y601768D01*
X265939Y602018D01*
X265856Y602310D01*
X265564Y602518D01*
X265273Y602601D01*
X264898D01*
G01X265273D02*
X265523Y602726D01*
X265731Y602935D01*
X265814Y603185D01*
X265731Y603435D01*
X265523Y603643D01*
X265148Y603768D01*
X264773Y603726D01*
X264398Y603560D01*
G01X268081Y603768D02*
X267748Y603685D01*
X267498Y603476D01*
X267331Y603226D01*
X267206Y602893D01*
X267164Y602518D01*
X267206Y602143D01*
X267331Y601810D01*
X267498Y601560D01*
X267748Y601351D01*
X268081Y601268D01*
X268414Y601351D01*
X268664Y601560D01*
X268831Y601810D01*
X268956Y602143D01*
X268998Y602518D01*
X268956Y602893D01*
X268831Y603226D01*
X268664Y603476D01*
X268414Y603685D01*
X268081Y603768D01*
G01X270389Y602310D02*
X270681Y602601D01*
X270931Y602768D01*
X271264Y602851D01*
X271556Y602768D01*
X271764Y602601D01*
X271931Y602351D01*
X271973Y602060D01*
X271931Y601810D01*
X271764Y601560D01*
X271514Y601351D01*
X271223Y601268D01*
X270889Y601351D01*
X270598Y601601D01*
X270431Y601976D01*
X270389Y602393D01*
X270473Y602935D01*
X270598Y603226D01*
X270806Y603518D01*
X271098Y603726D01*
X271389Y603768D01*
X271681Y603685D01*
X271889Y603476D01*
G01X273100Y603800D02*
Y607800D01*
X265700D01*
G01X256567Y633000D02*
Y635500D01*
X257608D01*
X257942Y635375D01*
X258150Y635208D01*
X258233Y634875D01*
X258150Y634542D01*
X257900Y634333D01*
X257608Y634208D01*
X256567D01*
G01X257608D02*
X258233Y633000D01*
G01X260417D02*
X260500Y633542D01*
X260625Y634000D01*
X260792Y634417D01*
X261000Y634875D01*
X261333Y635500D01*
X259667D01*
G01X262808Y634042D02*
X263100Y634333D01*
X263350Y634500D01*
X263683Y634583D01*
X263975Y634500D01*
X264183Y634333D01*
X264350Y634083D01*
X264392Y633792D01*
X264350Y633542D01*
X264183Y633292D01*
X263933Y633083D01*
X263642Y633000D01*
X263308Y633083D01*
X263017Y633333D01*
X262850Y633708D01*
X262808Y634125D01*
X262892Y634667D01*
X263017Y634958D01*
X263225Y635250D01*
X263517Y635458D01*
X263808Y635500D01*
X264100Y635417D01*
X264308Y635208D01*
G01X230000Y637200D02*
X234000D01*
Y644600D01*
G01X217200Y636800D02*
X221200D01*
Y644200D01*
G01X237900Y603000D02*
Y599000D01*
X245300D01*
G01X238300Y591800D02*
Y587800D01*
X245700D01*
G01X240000Y627200D02*
X236000D01*
Y619800D01*
G01Y627200D02*
X232000D01*
Y619800D01*
G01X223900Y629100D02*
X219900D01*
Y621700D01*
G01X230700Y636300D02*
Y632300D01*
X238100D01*
G01X246700Y580300D02*
Y576300D01*
X254100D01*
G01X245700Y587700D02*
Y583700D01*
X253100D01*
G01X246600Y575500D02*
Y571500D01*
X254000D01*
G01X231952Y631830D02*
X227952D01*
Y624430D01*
G01X227900Y629100D02*
X223900D01*
Y621700D01*
G01X245900Y611400D02*
X249900D01*
Y618800D01*
G01X253900D02*
X249900D01*
Y611400D01*
G01X271067Y633000D02*
Y635500D01*
X272108D01*
X272442Y635375D01*
X272650Y635208D01*
X272733Y634875D01*
X272650Y634542D01*
X272400Y634333D01*
X272108Y634208D01*
X271067D01*
G01X272108D02*
X272733Y633000D01*
G01X274917D02*
X275000Y633542D01*
X275125Y634000D01*
X275292Y634417D01*
X275500Y634875D01*
X275833Y635500D01*
X274167D01*
G01X277183Y633500D02*
X277433Y633208D01*
X277767Y633042D01*
X278142Y633000D01*
X278475Y633042D01*
X278808Y633250D01*
X279017Y633500D01*
X279058Y633750D01*
X278975Y634042D01*
X278683Y634250D01*
X278392Y634333D01*
X278017D01*
G01X278392D02*
X278642Y634458D01*
X278850Y634667D01*
X278933Y634917D01*
X278850Y635167D01*
X278642Y635375D01*
X278267Y635500D01*
X277892Y635458D01*
X277517Y635292D01*
G01X244258Y579690D02*
Y583690D01*
X236858D01*
G01X245600Y583700D02*
Y587700D01*
X238200D01*
G01X246542Y570585D02*
Y574585D01*
X239142D01*
G01X244025Y566522D02*
Y570522D01*
X236625D01*
G01X245900Y618800D02*
X241900D01*
Y611400D01*
G01X264402Y568536D02*
Y571036D01*
X265443D01*
X265777Y570911D01*
X265985Y570744D01*
X266068Y570411D01*
X265985Y570078D01*
X265735Y569869D01*
X265443Y569744D01*
X264402D01*
G01X265443D02*
X266068Y568536D01*
G01X268252D02*
X268335Y569078D01*
X268460Y569536D01*
X268627Y569953D01*
X268835Y570411D01*
X269168Y571036D01*
X267502D01*
G01X270643Y569578D02*
X270935Y569869D01*
X271185Y570036D01*
X271518Y570119D01*
X271810Y570036D01*
X272018Y569869D01*
X272185Y569619D01*
X272227Y569328D01*
X272185Y569078D01*
X272018Y568828D01*
X271768Y568619D01*
X271477Y568536D01*
X271143Y568619D01*
X270852Y568869D01*
X270685Y569244D01*
X270643Y569661D01*
X270727Y570203D01*
X270852Y570494D01*
X271060Y570786D01*
X271352Y570994D01*
X271643Y571036D01*
X271935Y570953D01*
X272143Y570744D01*
G01X273618Y569036D02*
X273868Y568744D01*
X274202Y568578D01*
X274577Y568536D01*
X274910Y568578D01*
X275243Y568786D01*
X275452Y569036D01*
X275493Y569286D01*
X275410Y569578D01*
X275118Y569786D01*
X274827Y569869D01*
X274452D01*
G01X274827D02*
X275077Y569994D01*
X275285Y570203D01*
X275368Y570453D01*
X275285Y570703D01*
X275077Y570911D01*
X274702Y571036D01*
X274327Y570994D01*
X273952Y570828D01*
G01X266719Y576462D02*
Y572462D01*
X274119D01*
G01X269000Y624517D02*
X266500D01*
Y625558D01*
X266625Y625892D01*
X266792Y626100D01*
X267125Y626183D01*
X267458Y626100D01*
X267667Y625850D01*
X267792Y625558D01*
Y624517D01*
G01Y625558D02*
X269000Y626183D01*
G01Y628367D02*
X268458Y628450D01*
X268000Y628575D01*
X267583Y628742D01*
X267125Y628950D01*
X266500Y629283D01*
Y627617D01*
G01X269000Y631467D02*
X268458Y631550D01*
X268000Y631675D01*
X267583Y631842D01*
X267125Y632050D01*
X266500Y632383D01*
Y630717D01*
G01X269000Y635150D02*
X266500D01*
X268292Y633608D01*
Y635692D01*
G01X266000Y611017D02*
X263500D01*
Y612058D01*
X263625Y612392D01*
X263792Y612600D01*
X264125Y612683D01*
X264458Y612600D01*
X264667Y612350D01*
X264792Y612058D01*
Y611017D01*
G01Y612058D02*
X266000Y612683D01*
G01Y614867D02*
X265458Y614950D01*
X265000Y615075D01*
X264583Y615242D01*
X264125Y615450D01*
X263500Y615783D01*
Y614117D01*
G01X266000Y617967D02*
X265458Y618050D01*
X265000Y618175D01*
X264583Y618342D01*
X264125Y618550D01*
X263500Y618883D01*
Y617217D01*
G01X265625Y620233D02*
X265833Y620483D01*
X265958Y620775D01*
X266000Y621150D01*
X265917Y621525D01*
X265750Y621817D01*
X265458Y622025D01*
X265125Y622067D01*
X264792Y621983D01*
X264583Y621775D01*
X264417Y621483D01*
X264375Y621192D01*
X264417Y620900D01*
X264583Y620525D01*
X263500Y620650D01*
Y621775D01*
G01X264823Y630096D02*
X260823D01*
Y622696D01*
G01X258960Y591575D02*
Y595575D01*
X251560D01*
G01X216373Y615385D02*
Y612885D01*
G01X215415Y615385D02*
X217331D01*
G01X218640Y612885D02*
Y615385D01*
X219640D01*
X219973Y615260D01*
X220223Y614968D01*
X220306Y614635D01*
X220223Y614302D01*
X220015Y614052D01*
X219640Y613927D01*
X218640D01*
G01X221656Y613260D02*
X221906Y613052D01*
X222198Y612927D01*
X222573Y612885D01*
X222948Y612968D01*
X223240Y613135D01*
X223448Y613427D01*
X223490Y613760D01*
X223406Y614093D01*
X223198Y614302D01*
X222906Y614468D01*
X222615Y614510D01*
X222323Y614468D01*
X221948Y614302D01*
X222073Y615385D01*
X223198D01*
G01X224756Y613385D02*
X225006Y613093D01*
X225340Y612927D01*
X225715Y612885D01*
X226048Y612927D01*
X226381Y613135D01*
X226590Y613385D01*
X226631Y613635D01*
X226548Y613927D01*
X226256Y614135D01*
X225965Y614218D01*
X225590D01*
G01X225965D02*
X226215Y614343D01*
X226423Y614552D01*
X226506Y614802D01*
X226423Y615052D01*
X226215Y615260D01*
X225840Y615385D01*
X225465Y615343D01*
X225090Y615177D01*
G01X275345Y604565D02*
Y602773D01*
X275512Y602398D01*
X275845Y602148D01*
X276262Y602065D01*
X276679Y602148D01*
X277012Y602398D01*
X277179Y602773D01*
Y604565D01*
G01X278445Y602565D02*
X278695Y602273D01*
X279029Y602107D01*
X279404Y602065D01*
X279737Y602107D01*
X280070Y602315D01*
X280279Y602565D01*
X280320Y602815D01*
X280237Y603107D01*
X279945Y603315D01*
X279654Y603398D01*
X279279D01*
G01X279654D02*
X279904Y603523D01*
X280112Y603732D01*
X280195Y603982D01*
X280112Y604232D01*
X279904Y604440D01*
X279529Y604565D01*
X279154Y604523D01*
X278779Y604357D01*
G01X282462Y604565D02*
X282129Y604482D01*
X281879Y604273D01*
X281712Y604023D01*
X281587Y603690D01*
X281545Y603315D01*
X281587Y602940D01*
X281712Y602607D01*
X281879Y602357D01*
X282129Y602148D01*
X282462Y602065D01*
X282795Y602148D01*
X283045Y602357D01*
X283212Y602607D01*
X283337Y602940D01*
X283379Y603315D01*
X283337Y603690D01*
X283212Y604023D01*
X283045Y604273D01*
X282795Y604482D01*
X282462Y604565D01*
G01X279600Y600200D02*
X277800Y598100D01*
X275600Y600200D01*
G01X272000Y600300D02*
Y581100D01*
X283200D01*
Y600300D01*
X272000D01*
Y599900D01*
G01X260303Y605493D02*
X262053Y607993D01*
G01X260303D02*
X262053Y605493D01*
G01X263486Y607576D02*
X263736Y607826D01*
X264028Y607951D01*
X264361Y607993D01*
X264778Y607910D01*
X265070Y607701D01*
X265153Y607451D01*
X265111Y607201D01*
X264945Y606993D01*
X264111Y606576D01*
X263736Y606285D01*
X263486Y605868D01*
X263403Y605493D01*
X265153D01*
G01X283483Y609217D02*
X266783D01*
Y621317D01*
X283483D01*
Y609217D01*
G01X253824Y626614D02*
Y619614D01*
X240424D01*
Y626614D01*
X253824D01*
G01X268929Y710243D02*
X268679Y710368D01*
X268387Y710451D01*
X268054D01*
X267679Y710326D01*
X267387Y710118D01*
X267179Y709868D01*
X267012Y709451D01*
X266970Y709076D01*
X267054Y708701D01*
X267179Y708451D01*
X267429Y708201D01*
X267720Y708034D01*
X268012Y707951D01*
X268304D01*
X268595Y708034D01*
X268845Y708159D01*
X269054Y708326D01*
G01X271112Y707951D02*
Y710451D01*
X270612Y709951D01*
G01Y707951D02*
X271612D01*
G01X273504Y708243D02*
X273795Y708034D01*
X274129Y707951D01*
X274462Y708034D01*
X274754Y708284D01*
X274962Y708659D01*
X275045Y709034D01*
Y709493D01*
X274962Y709868D01*
X274754Y710201D01*
X274504Y710368D01*
X274212Y710451D01*
X273879Y710368D01*
X273629Y710201D01*
X273462Y709951D01*
X273379Y709618D01*
X273462Y709326D01*
X273670Y709034D01*
X273920Y708868D01*
X274212Y708826D01*
X274545Y708909D01*
X274795Y709118D01*
X275045Y709493D01*
G01X276520Y708993D02*
X276812Y709284D01*
X277062Y709451D01*
X277395Y709534D01*
X277687Y709451D01*
X277895Y709284D01*
X278062Y709034D01*
X278104Y708743D01*
X278062Y708493D01*
X277895Y708243D01*
X277645Y708034D01*
X277354Y707951D01*
X277020Y708034D01*
X276729Y708284D01*
X276562Y708659D01*
X276520Y709076D01*
X276604Y709618D01*
X276729Y709909D01*
X276937Y710201D01*
X277229Y710409D01*
X277520Y710451D01*
X277812Y710368D01*
X278020Y710159D01*
G01X235542Y696817D02*
X235417Y696567D01*
X235334Y696275D01*
Y695942D01*
X235459Y695567D01*
X235667Y695275D01*
X235917Y695067D01*
X236334Y694900D01*
X236709Y694858D01*
X237084Y694942D01*
X237334Y695067D01*
X237584Y695317D01*
X237751Y695608D01*
X237834Y695900D01*
Y696192D01*
X237751Y696483D01*
X237626Y696733D01*
X237459Y696942D01*
G01X237334Y698083D02*
X237626Y698333D01*
X237792Y698667D01*
X237834Y699042D01*
X237792Y699375D01*
X237584Y699708D01*
X237334Y699917D01*
X237084Y699958D01*
X236792Y699875D01*
X236584Y699583D01*
X236501Y699292D01*
Y698917D01*
G01Y699292D02*
X236376Y699542D01*
X236167Y699750D01*
X235917Y699833D01*
X235667Y699750D01*
X235459Y699542D01*
X235334Y699167D01*
X235376Y698792D01*
X235542Y698417D01*
G01X237834Y702600D02*
X235334D01*
X237126Y701058D01*
Y703142D01*
G01X247317Y711792D02*
X247067Y711917D01*
X246775Y712000D01*
X246442D01*
X246067Y711875D01*
X245775Y711667D01*
X245567Y711417D01*
X245400Y711000D01*
X245358Y710625D01*
X245442Y710250D01*
X245567Y710000D01*
X245817Y709750D01*
X246108Y709583D01*
X246400Y709500D01*
X246692D01*
X246983Y709583D01*
X247233Y709708D01*
X247442Y709875D01*
G01X248583Y710000D02*
X248833Y709708D01*
X249167Y709542D01*
X249542Y709500D01*
X249875Y709542D01*
X250208Y709750D01*
X250417Y710000D01*
X250458Y710250D01*
X250375Y710542D01*
X250083Y710750D01*
X249792Y710833D01*
X249417D01*
G01X249792D02*
X250042Y710958D01*
X250250Y711167D01*
X250333Y711417D01*
X250250Y711667D01*
X250042Y711875D01*
X249667Y712000D01*
X249292Y711958D01*
X248917Y711792D01*
G01X251683Y710000D02*
X251933Y709708D01*
X252267Y709542D01*
X252642Y709500D01*
X252975Y709542D01*
X253308Y709750D01*
X253517Y710000D01*
X253558Y710250D01*
X253475Y710542D01*
X253183Y710750D01*
X252892Y710833D01*
X252517D01*
G01X252892D02*
X253142Y710958D01*
X253350Y711167D01*
X253433Y711417D01*
X253350Y711667D01*
X253142Y711875D01*
X252767Y712000D01*
X252392Y711958D01*
X252017Y711792D01*
G01X223767Y648792D02*
X223517Y648917D01*
X223225Y649000D01*
X222892D01*
X222517Y648875D01*
X222225Y648667D01*
X222017Y648417D01*
X221850Y648000D01*
X221808Y647625D01*
X221892Y647250D01*
X222017Y647000D01*
X222267Y646750D01*
X222558Y646583D01*
X222850Y646500D01*
X223142D01*
X223433Y646583D01*
X223683Y646708D01*
X223892Y646875D01*
G01X225033D02*
X225283Y646667D01*
X225575Y646542D01*
X225950Y646500D01*
X226325Y646583D01*
X226617Y646750D01*
X226825Y647042D01*
X226867Y647375D01*
X226783Y647708D01*
X226575Y647917D01*
X226283Y648083D01*
X225992Y648125D01*
X225700Y648083D01*
X225325Y647917D01*
X225450Y649000D01*
X226575D01*
G01X228258Y648583D02*
X228508Y648833D01*
X228800Y648958D01*
X229133Y649000D01*
X229550Y648917D01*
X229842Y648708D01*
X229925Y648458D01*
X229883Y648208D01*
X229717Y648000D01*
X228883Y647583D01*
X228508Y647292D01*
X228258Y646875D01*
X228175Y646500D01*
X229925D01*
G01X232150Y649000D02*
X231817Y648917D01*
X231567Y648708D01*
X231400Y648458D01*
X231275Y648125D01*
X231233Y647750D01*
X231275Y647375D01*
X231400Y647042D01*
X231567Y646792D01*
X231817Y646583D01*
X232150Y646500D01*
X232483Y646583D01*
X232733Y646792D01*
X232900Y647042D01*
X233025Y647375D01*
X233067Y647750D01*
X233025Y648125D01*
X232900Y648458D01*
X232733Y648708D01*
X232483Y648917D01*
X232150Y649000D01*
G01X244817Y643292D02*
X244567Y643417D01*
X244275Y643500D01*
X243942D01*
X243567Y643375D01*
X243275Y643167D01*
X243067Y642917D01*
X242900Y642500D01*
X242858Y642125D01*
X242942Y641750D01*
X243067Y641500D01*
X243317Y641250D01*
X243608Y641083D01*
X243900Y641000D01*
X244192D01*
X244483Y641083D01*
X244733Y641208D01*
X244942Y641375D01*
G01X246083D02*
X246333Y641167D01*
X246625Y641042D01*
X247000Y641000D01*
X247375Y641083D01*
X247667Y641250D01*
X247875Y641542D01*
X247917Y641875D01*
X247833Y642208D01*
X247625Y642417D01*
X247333Y642583D01*
X247042Y642625D01*
X246750Y642583D01*
X246375Y642417D01*
X246500Y643500D01*
X247625D01*
G01X250100D02*
X249767Y643417D01*
X249517Y643208D01*
X249350Y642958D01*
X249225Y642625D01*
X249183Y642250D01*
X249225Y641875D01*
X249350Y641542D01*
X249517Y641292D01*
X249767Y641083D01*
X250100Y641000D01*
X250433Y641083D01*
X250683Y641292D01*
X250850Y641542D01*
X250975Y641875D01*
X251017Y642250D01*
X250975Y642625D01*
X250850Y642958D01*
X250683Y643208D01*
X250433Y643417D01*
X250100Y643500D01*
G01X239208Y694317D02*
X239083Y694067D01*
X239000Y693775D01*
Y693442D01*
X239125Y693067D01*
X239333Y692775D01*
X239583Y692567D01*
X240000Y692400D01*
X240375Y692358D01*
X240750Y692442D01*
X241000Y692567D01*
X241250Y692817D01*
X241417Y693108D01*
X241500Y693400D01*
Y693692D01*
X241417Y693983D01*
X241292Y694233D01*
X241125Y694442D01*
G01X241000Y695583D02*
X241292Y695833D01*
X241458Y696167D01*
X241500Y696542D01*
X241458Y696875D01*
X241250Y697208D01*
X241000Y697417D01*
X240750Y697458D01*
X240458Y697375D01*
X240250Y697083D01*
X240167Y696792D01*
Y696417D01*
G01Y696792D02*
X240042Y697042D01*
X239833Y697250D01*
X239583Y697333D01*
X239333Y697250D01*
X239125Y697042D01*
X239000Y696667D01*
X239042Y696292D01*
X239208Y695917D01*
G01X241500Y699600D02*
X241458Y699892D01*
X241333Y700225D01*
X241125Y700433D01*
X240833Y700517D01*
X240542Y700433D01*
X240292Y700183D01*
X240167Y699808D01*
Y699392D01*
X240083Y699142D01*
X239875Y698933D01*
X239583Y698850D01*
X239292Y698975D01*
X239083Y699267D01*
X239000Y699600D01*
X239083Y699933D01*
X239292Y700225D01*
X239583Y700350D01*
X239875Y700267D01*
X240083Y700058D01*
X240167Y699808D01*
Y699392D01*
X240292Y699017D01*
X240542Y698767D01*
X240833Y698683D01*
X241125Y698767D01*
X241333Y698975D01*
X241458Y699308D01*
X241500Y699600D01*
G01Y702067D02*
X239000D01*
Y703108D01*
X239125Y703442D01*
X239292Y703650D01*
X239625Y703733D01*
X239958Y703650D01*
X240167Y703400D01*
X240292Y703108D01*
Y702067D01*
G01Y703108D02*
X241500Y703733D01*
G01Y706000D02*
X241458Y706292D01*
X241333Y706625D01*
X241125Y706833D01*
X240833Y706917D01*
X240542Y706833D01*
X240292Y706583D01*
X240167Y706208D01*
Y705792D01*
X240083Y705542D01*
X239875Y705333D01*
X239583Y705250D01*
X239292Y705375D01*
X239083Y705667D01*
X239000Y706000D01*
X239083Y706333D01*
X239292Y706625D01*
X239583Y706750D01*
X239875Y706667D01*
X240083Y706458D01*
X240167Y706208D01*
Y705792D01*
X240292Y705417D01*
X240542Y705167D01*
X240833Y705083D01*
X241125Y705167D01*
X241333Y705375D01*
X241458Y705708D01*
X241500Y706000D01*
G01X239000Y709100D02*
X239083Y708767D01*
X239292Y708517D01*
X239542Y708350D01*
X239875Y708225D01*
X240250Y708183D01*
X240625Y708225D01*
X240958Y708350D01*
X241208Y708517D01*
X241417Y708767D01*
X241500Y709100D01*
X241417Y709433D01*
X241208Y709683D01*
X240958Y709850D01*
X240625Y709975D01*
X240250Y710017D01*
X239875Y709975D01*
X239542Y709850D01*
X239292Y709683D01*
X239083Y709433D01*
X239000Y709100D01*
G01X257576Y671731D02*
Y667731D01*
X264976D01*
G01X256000Y644264D02*
X260000D01*
Y651664D01*
G01X262282Y640199D02*
Y644199D01*
X254882D01*
G01X284500Y668517D02*
X282000D01*
Y669558D01*
X282125Y669892D01*
X282292Y670100D01*
X282625Y670183D01*
X282958Y670100D01*
X283167Y669850D01*
X283292Y669558D01*
Y668517D01*
G01Y669558D02*
X284500Y670183D01*
G01X284000Y671533D02*
X284292Y671783D01*
X284458Y672117D01*
X284500Y672492D01*
X284458Y672825D01*
X284250Y673158D01*
X284000Y673367D01*
X283750Y673408D01*
X283458Y673325D01*
X283250Y673033D01*
X283167Y672742D01*
Y672367D01*
G01Y672742D02*
X283042Y672992D01*
X282833Y673200D01*
X282583Y673283D01*
X282333Y673200D01*
X282125Y672992D01*
X282000Y672617D01*
X282042Y672242D01*
X282208Y671867D01*
G01X284000Y674633D02*
X284292Y674883D01*
X284458Y675217D01*
X284500Y675592D01*
X284458Y675925D01*
X284250Y676258D01*
X284000Y676467D01*
X283750Y676508D01*
X283458Y676425D01*
X283250Y676133D01*
X283167Y675842D01*
Y675467D01*
G01Y675842D02*
X283042Y676092D01*
X282833Y676300D01*
X282583Y676383D01*
X282333Y676300D01*
X282125Y676092D01*
X282000Y675717D01*
X282042Y675342D01*
X282208Y674967D01*
G01X282417Y677858D02*
X282167Y678108D01*
X282042Y678400D01*
X282000Y678733D01*
X282083Y679150D01*
X282292Y679442D01*
X282542Y679525D01*
X282792Y679483D01*
X283000Y679317D01*
X283417Y678483D01*
X283708Y678108D01*
X284125Y677858D01*
X284500Y677775D01*
Y679525D01*
G01X269200Y670700D02*
X273200D01*
Y678100D01*
G01X223000Y652417D02*
X220500D01*
Y653458D01*
X220625Y653792D01*
X220792Y654000D01*
X221125Y654083D01*
X221458Y654000D01*
X221667Y653750D01*
X221792Y653458D01*
Y652417D01*
G01Y653458D02*
X223000Y654083D01*
G01Y656350D02*
X220500D01*
X221000Y655850D01*
G01X223000D02*
Y656850D01*
G01X222708Y658742D02*
X222917Y659033D01*
X223000Y659367D01*
X222917Y659700D01*
X222667Y659992D01*
X222292Y660200D01*
X221917Y660283D01*
X221458D01*
X221083Y660200D01*
X220750Y659992D01*
X220583Y659742D01*
X220500Y659450D01*
X220583Y659117D01*
X220750Y658867D01*
X221000Y658700D01*
X221333Y658617D01*
X221625Y658700D01*
X221917Y658908D01*
X222083Y659158D01*
X222125Y659450D01*
X222042Y659783D01*
X221833Y660033D01*
X221458Y660283D01*
G01X223000Y662467D02*
X222458Y662550D01*
X222000Y662675D01*
X221583Y662842D01*
X221125Y663050D01*
X220500Y663383D01*
Y661717D01*
G01X227984Y664443D02*
X223984D01*
Y657043D01*
G01X260431Y710224D02*
X256431D01*
Y702824D01*
G01X280100Y642572D02*
Y646572D01*
X272700D01*
G01X230334Y695067D02*
X227834D01*
Y696108D01*
X227959Y696442D01*
X228126Y696650D01*
X228459Y696733D01*
X228792Y696650D01*
X229001Y696400D01*
X229126Y696108D01*
Y695067D01*
G01Y696108D02*
X230334Y696733D01*
G01Y698917D02*
X229792Y699000D01*
X229334Y699125D01*
X228917Y699292D01*
X228459Y699500D01*
X227834Y699833D01*
Y698167D01*
G01X230334Y702100D02*
X227834D01*
X228334Y701600D01*
G01X230334D02*
Y702600D01*
G01X248800Y673900D02*
X252800D01*
Y681300D01*
G01X280670Y649978D02*
Y645978D01*
X288070D01*
G01X260645Y702835D02*
X264645D01*
Y710235D01*
G01X234334Y695067D02*
X231834D01*
Y696108D01*
X231959Y696442D01*
X232126Y696650D01*
X232459Y696733D01*
X232792Y696650D01*
X233001Y696400D01*
X233126Y696108D01*
Y695067D01*
G01Y696108D02*
X234334Y696733D01*
G01Y698917D02*
X233792Y699000D01*
X233334Y699125D01*
X232917Y699292D01*
X232459Y699500D01*
X231834Y699833D01*
Y698167D01*
G01X234334Y702100D02*
X234292Y702392D01*
X234167Y702725D01*
X233959Y702933D01*
X233667Y703017D01*
X233376Y702933D01*
X233126Y702683D01*
X233001Y702308D01*
Y701892D01*
X232917Y701642D01*
X232709Y701433D01*
X232417Y701350D01*
X232126Y701475D01*
X231917Y701767D01*
X231834Y702100D01*
X231917Y702433D01*
X232126Y702725D01*
X232417Y702850D01*
X232709Y702767D01*
X232917Y702558D01*
X233001Y702308D01*
Y701892D01*
X233126Y701517D01*
X233376Y701267D01*
X233667Y701183D01*
X233959Y701267D01*
X234167Y701475D01*
X234292Y701808D01*
X234334Y702100D01*
G01X256500Y673800D02*
X260500D01*
Y681200D01*
G01X239414Y666671D02*
X236914D01*
Y667712D01*
X237039Y668046D01*
X237206Y668254D01*
X237539Y668337D01*
X237872Y668254D01*
X238081Y668004D01*
X238206Y667712D01*
Y666671D01*
G01Y667712D02*
X239414Y668337D01*
G01Y670521D02*
X238872Y670604D01*
X238414Y670729D01*
X237997Y670896D01*
X237539Y671104D01*
X236914Y671437D01*
Y669771D01*
G01X239414Y673621D02*
X238872Y673704D01*
X238414Y673829D01*
X237997Y673996D01*
X237539Y674204D01*
X236914Y674537D01*
Y672871D01*
G01X233489Y664667D02*
Y660667D01*
X240889D01*
G01X234264Y650792D02*
X231764D01*
Y651833D01*
X231889Y652167D01*
X232056Y652375D01*
X232389Y652458D01*
X232722Y652375D01*
X232931Y652125D01*
X233056Y651833D01*
Y650792D01*
G01Y651833D02*
X234264Y652458D01*
G01Y654642D02*
X233722Y654725D01*
X233264Y654850D01*
X232847Y655017D01*
X232389Y655225D01*
X231764Y655558D01*
Y653892D01*
G01X233889Y656908D02*
X234097Y657158D01*
X234222Y657450D01*
X234264Y657825D01*
X234181Y658200D01*
X234014Y658492D01*
X233722Y658700D01*
X233389Y658742D01*
X233056Y658658D01*
X232847Y658450D01*
X232681Y658158D01*
X232639Y657867D01*
X232681Y657575D01*
X232847Y657200D01*
X231764Y657325D01*
Y658450D01*
G01X236807Y653171D02*
X240807D01*
Y660571D01*
G01X226334Y695067D02*
X223834D01*
Y696108D01*
X223959Y696442D01*
X224126Y696650D01*
X224459Y696733D01*
X224792Y696650D01*
X225001Y696400D01*
X225126Y696108D01*
Y695067D01*
G01Y696108D02*
X226334Y696733D01*
G01Y698917D02*
X225792Y699000D01*
X225334Y699125D01*
X224917Y699292D01*
X224459Y699500D01*
X223834Y699833D01*
Y698167D01*
G01X226334Y702600D02*
X223834D01*
X225626Y701058D01*
Y703142D01*
G01X248700Y681300D02*
X244700D01*
Y673900D01*
G01X280670Y654044D02*
Y650044D01*
X288070D01*
G01X249500Y707700D02*
X245500D01*
Y700300D01*
G01X271200Y637500D02*
Y641500D01*
X263800D01*
G01X216723Y657496D02*
X212723D01*
Y650096D01*
G01X228333Y704533D02*
X230125D01*
X230500Y704700D01*
X230750Y705033D01*
X230833Y705450D01*
X230750Y705867D01*
X230500Y706200D01*
X230125Y706367D01*
X228333D01*
G01X230541Y707842D02*
X230750Y708133D01*
X230833Y708467D01*
X230750Y708800D01*
X230500Y709092D01*
X230125Y709300D01*
X229750Y709383D01*
X229291D01*
X228916Y709300D01*
X228583Y709092D01*
X228416Y708842D01*
X228333Y708550D01*
X228416Y708217D01*
X228583Y707967D01*
X228833Y707800D01*
X229166Y707717D01*
X229458Y707800D01*
X229750Y708008D01*
X229916Y708258D01*
X229958Y708550D01*
X229875Y708883D01*
X229666Y709133D01*
X229291Y709383D01*
G01X243531Y682824D02*
Y696224D01*
G01X253531Y682824D02*
X243531D01*
G01X253531Y696224D02*
Y682824D01*
G01X243531Y696224D02*
X253531D01*
G01X235500Y704483D02*
X237292D01*
X237667Y704650D01*
X237917Y704983D01*
X238000Y705400D01*
X237917Y705817D01*
X237667Y706150D01*
X237292Y706317D01*
X235500D01*
G01X237500Y707583D02*
X237792Y707833D01*
X237958Y708167D01*
X238000Y708542D01*
X237958Y708875D01*
X237750Y709208D01*
X237500Y709417D01*
X237250Y709458D01*
X236958Y709375D01*
X236750Y709083D01*
X236667Y708792D01*
Y708417D01*
G01Y708792D02*
X236542Y709042D01*
X236333Y709250D01*
X236083Y709333D01*
X235833Y709250D01*
X235625Y709042D01*
X235500Y708667D01*
X235542Y708292D01*
X235708Y707917D01*
G01X238000Y711600D02*
X235500D01*
X236000Y711100D01*
G01X238000D02*
Y712100D01*
G01X278800Y696300D02*
Y682900D01*
G01X268800Y696300D02*
X278800D01*
G01X268800Y682900D02*
Y696300D01*
G01X278800Y682900D02*
X268800D01*
G01X231833Y704483D02*
X233625D01*
X234000Y704650D01*
X234250Y704983D01*
X234333Y705400D01*
X234250Y705817D01*
X234000Y706150D01*
X233625Y706317D01*
X231833D01*
G01X234333Y708500D02*
X231833D01*
X232333Y708000D01*
G01X234333D02*
Y709000D01*
G01X231833Y711600D02*
X231916Y711267D01*
X232125Y711017D01*
X232375Y710850D01*
X232708Y710725D01*
X233083Y710683D01*
X233458Y710725D01*
X233791Y710850D01*
X234041Y711017D01*
X234250Y711267D01*
X234333Y711600D01*
X234250Y711933D01*
X234041Y712183D01*
X233791Y712350D01*
X233458Y712475D01*
X233083Y712517D01*
X232708Y712475D01*
X232375Y712350D01*
X232125Y712183D01*
X231916Y711933D01*
X231833Y711600D01*
G01X255931Y682624D02*
Y696024D01*
G01X265931Y682624D02*
X255931D01*
G01X265931Y696024D02*
Y682624D01*
G01X255931Y696024D02*
X265931D01*
G01X243288Y675421D02*
X243246Y675088D01*
X243080Y674796D01*
X242830Y674546D01*
X242538Y674379D01*
X242205Y674296D01*
X241871D01*
X241538Y674379D01*
X241246Y674546D01*
X240996Y674796D01*
X240830Y675088D01*
X240788Y675421D01*
X240830Y675754D01*
X240996Y676046D01*
X241246Y676296D01*
X241538Y676463D01*
X241871Y676546D01*
X242205D01*
X242538Y676463D01*
X242830Y676296D01*
X243080Y676046D01*
X243246Y675754D01*
X243288Y675421D01*
G01X242621Y675754D02*
X243288Y676254D01*
G01Y679021D02*
X240788D01*
X242580Y677479D01*
Y679563D01*
G01X241500Y660000D02*
X255500D01*
G01X241500Y673000D02*
Y660000D01*
G01X255500Y673000D02*
X241500D01*
G01X255500Y660000D02*
Y673000D01*
G01X261208Y657817D02*
X261083Y657567D01*
X261000Y657275D01*
Y656942D01*
X261125Y656567D01*
X261333Y656275D01*
X261583Y656067D01*
X262000Y655900D01*
X262375Y655858D01*
X262750Y655942D01*
X263000Y656067D01*
X263250Y656317D01*
X263417Y656608D01*
X263500Y656900D01*
Y657192D01*
X263417Y657483D01*
X263292Y657733D01*
X263125Y657942D01*
G01X263000Y659083D02*
X263292Y659333D01*
X263458Y659667D01*
X263500Y660042D01*
X263458Y660375D01*
X263250Y660708D01*
X263000Y660917D01*
X262750Y660958D01*
X262458Y660875D01*
X262250Y660583D01*
X262167Y660292D01*
Y659917D01*
G01Y660292D02*
X262042Y660542D01*
X261833Y660750D01*
X261583Y660833D01*
X261333Y660750D01*
X261125Y660542D01*
X261000Y660167D01*
X261042Y659792D01*
X261208Y659417D01*
G01X263125Y662183D02*
X263333Y662433D01*
X263458Y662725D01*
X263500Y663100D01*
X263417Y663475D01*
X263250Y663767D01*
X262958Y663975D01*
X262625Y664017D01*
X262292Y663933D01*
X262083Y663725D01*
X261917Y663433D01*
X261875Y663142D01*
X261917Y662850D01*
X262083Y662475D01*
X261000Y662600D01*
Y663725D01*
G01X240000Y647450D02*
X239958Y647117D01*
X239792Y646825D01*
X239542Y646575D01*
X239250Y646408D01*
X238917Y646325D01*
X238583D01*
X238250Y646408D01*
X237958Y646575D01*
X237708Y646825D01*
X237542Y647117D01*
X237500Y647450D01*
X237542Y647783D01*
X237708Y648075D01*
X237958Y648325D01*
X238250Y648492D01*
X238583Y648575D01*
X238917D01*
X239250Y648492D01*
X239542Y648325D01*
X239792Y648075D01*
X239958Y647783D01*
X240000Y647450D01*
G01X239333Y647783D02*
X240000Y648283D01*
G01X239500Y649633D02*
X239792Y649883D01*
X239958Y650217D01*
X240000Y650592D01*
X239958Y650925D01*
X239750Y651258D01*
X239500Y651467D01*
X239250Y651508D01*
X238958Y651425D01*
X238750Y651133D01*
X238667Y650842D01*
Y650467D01*
G01Y650842D02*
X238542Y651092D01*
X238333Y651300D01*
X238083Y651383D01*
X237833Y651300D01*
X237625Y651092D01*
X237500Y650717D01*
X237542Y650342D01*
X237708Y649967D01*
G01X241500Y646000D02*
X255500D01*
G01X241500Y659000D02*
Y646000D01*
G01X255500Y659000D02*
X241500D01*
G01X255500Y646000D02*
Y659000D01*
G01X265950Y643500D02*
X265617Y643542D01*
X265325Y643708D01*
X265075Y643958D01*
X264908Y644250D01*
X264825Y644583D01*
Y644917D01*
X264908Y645250D01*
X265075Y645542D01*
X265325Y645792D01*
X265617Y645958D01*
X265950Y646000D01*
X266283Y645958D01*
X266575Y645792D01*
X266825Y645542D01*
X266992Y645250D01*
X267075Y644917D01*
Y644583D01*
X266992Y644250D01*
X266825Y643958D01*
X266575Y643708D01*
X266283Y643542D01*
X265950Y643500D01*
G01X266283Y644167D02*
X266783Y643500D01*
G01X268258Y645583D02*
X268508Y645833D01*
X268800Y645958D01*
X269133Y646000D01*
X269550Y645917D01*
X269842Y645708D01*
X269925Y645458D01*
X269883Y645208D01*
X269717Y645000D01*
X268883Y644583D01*
X268508Y644292D01*
X268258Y643875D01*
X268175Y643500D01*
X269925D01*
G01X279206Y660233D02*
X265206D01*
G01X279206Y647233D02*
Y660233D01*
G01X265206Y647233D02*
X279206D01*
G01X265206Y660233D02*
Y647233D01*
G01X281784Y701220D02*
Y696220D01*
X286784D01*
G01X283191Y704952D02*
X281191D01*
G01X285500Y659483D02*
X283000D01*
Y660317D01*
X283125Y660650D01*
X283292Y660900D01*
X283542Y661108D01*
X283833Y661275D01*
X284250Y661317D01*
X284667Y661275D01*
X284958Y661108D01*
X285208Y660900D01*
X285375Y660650D01*
X285500Y660317D01*
Y659483D01*
G01Y663500D02*
X283000D01*
X283500Y663000D01*
G01X285500D02*
Y664000D01*
G01Y666600D02*
X283000D01*
X283500Y666100D01*
G01X285500D02*
Y667100D01*
G01X274100Y661600D02*
Y677700D01*
G01X281100Y661600D02*
X274100D01*
G01X281100Y677700D02*
Y661600D01*
G01X274100Y677700D02*
X281100D01*
G01X265836Y730195D02*
X265586Y730320D01*
X265294Y730403D01*
X264961D01*
X264586Y730278D01*
X264294Y730070D01*
X264086Y729820D01*
X263919Y729403D01*
X263877Y729028D01*
X263961Y728653D01*
X264086Y728403D01*
X264336Y728153D01*
X264627Y727986D01*
X264919Y727903D01*
X265211D01*
X265502Y727986D01*
X265752Y728111D01*
X265961Y728278D01*
G01X267227Y729986D02*
X267477Y730236D01*
X267769Y730361D01*
X268102Y730403D01*
X268519Y730320D01*
X268811Y730111D01*
X268894Y729861D01*
X268852Y729611D01*
X268686Y729403D01*
X267852Y728986D01*
X267477Y728695D01*
X267227Y728278D01*
X267144Y727903D01*
X268894D01*
G01X271119Y730403D02*
X270786Y730320D01*
X270536Y730111D01*
X270369Y729861D01*
X270244Y729528D01*
X270202Y729153D01*
X270244Y728778D01*
X270369Y728445D01*
X270536Y728195D01*
X270786Y727986D01*
X271119Y727903D01*
X271452Y727986D01*
X271702Y728195D01*
X271869Y728445D01*
X271994Y728778D01*
X272036Y729153D01*
X271994Y729528D01*
X271869Y729861D01*
X271702Y730111D01*
X271452Y730320D01*
X271119Y730403D01*
G01X274219Y727903D02*
Y730403D01*
X273719Y729903D01*
G01Y727903D02*
X274719D01*
G01X224542Y723767D02*
X224417Y723517D01*
X224334Y723225D01*
Y722892D01*
X224459Y722517D01*
X224667Y722225D01*
X224917Y722017D01*
X225334Y721850D01*
X225709Y721808D01*
X226084Y721892D01*
X226334Y722017D01*
X226584Y722267D01*
X226751Y722558D01*
X226834Y722850D01*
Y723142D01*
X226751Y723433D01*
X226626Y723683D01*
X226459Y723892D01*
G01X226834Y725950D02*
X224334D01*
X224834Y725450D01*
G01X226834D02*
Y726450D01*
G01X225792Y728258D02*
X225501Y728550D01*
X225334Y728800D01*
X225251Y729133D01*
X225334Y729425D01*
X225501Y729633D01*
X225751Y729800D01*
X226042Y729842D01*
X226292Y729800D01*
X226542Y729633D01*
X226751Y729383D01*
X226834Y729092D01*
X226751Y728758D01*
X226501Y728467D01*
X226126Y728300D01*
X225709Y728258D01*
X225167Y728342D01*
X224876Y728467D01*
X224584Y728675D01*
X224376Y728967D01*
X224334Y729258D01*
X224417Y729550D01*
X224626Y729758D01*
G01X226542Y731442D02*
X226751Y731733D01*
X226834Y732067D01*
X226751Y732400D01*
X226501Y732692D01*
X226126Y732900D01*
X225751Y732983D01*
X225292D01*
X224917Y732900D01*
X224584Y732692D01*
X224417Y732442D01*
X224334Y732150D01*
X224417Y731817D01*
X224584Y731567D01*
X224834Y731400D01*
X225167Y731317D01*
X225459Y731400D01*
X225751Y731608D01*
X225917Y731858D01*
X225959Y732150D01*
X225876Y732483D01*
X225667Y732733D01*
X225292Y732983D01*
G01X213708Y723767D02*
X213583Y723517D01*
X213500Y723225D01*
Y722892D01*
X213625Y722517D01*
X213833Y722225D01*
X214083Y722017D01*
X214500Y721850D01*
X214875Y721808D01*
X215250Y721892D01*
X215500Y722017D01*
X215750Y722267D01*
X215917Y722558D01*
X216000Y722850D01*
Y723142D01*
X215917Y723433D01*
X215792Y723683D01*
X215625Y723892D01*
G01X216000Y725950D02*
X213500D01*
X214000Y725450D01*
G01X216000D02*
Y726450D01*
G01Y728967D02*
X215458Y729050D01*
X215000Y729175D01*
X214583Y729342D01*
X214125Y729550D01*
X213500Y729883D01*
Y728217D01*
G01X216000Y732650D02*
X213500D01*
X215292Y731108D01*
Y733192D01*
G01X217708Y723767D02*
X217583Y723517D01*
X217500Y723225D01*
Y722892D01*
X217625Y722517D01*
X217833Y722225D01*
X218083Y722017D01*
X218500Y721850D01*
X218875Y721808D01*
X219250Y721892D01*
X219500Y722017D01*
X219750Y722267D01*
X219917Y722558D01*
X220000Y722850D01*
Y723142D01*
X219917Y723433D01*
X219792Y723683D01*
X219625Y723892D01*
G01X220000Y725950D02*
X217500D01*
X218000Y725450D01*
G01X220000D02*
Y726450D01*
G01Y728967D02*
X219458Y729050D01*
X219000Y729175D01*
X218583Y729342D01*
X218125Y729550D01*
X217500Y729883D01*
Y728217D01*
G01X217917Y731358D02*
X217667Y731608D01*
X217542Y731900D01*
X217500Y732233D01*
X217583Y732650D01*
X217792Y732942D01*
X218042Y733025D01*
X218292Y732983D01*
X218500Y732817D01*
X218917Y731983D01*
X219208Y731608D01*
X219625Y731358D01*
X220000Y731275D01*
Y733025D01*
G01X261167Y718436D02*
X258667D01*
Y719477D01*
X258792Y719811D01*
X258959Y720019D01*
X259292Y720102D01*
X259625Y720019D01*
X259834Y719769D01*
X259959Y719477D01*
Y718436D01*
G01Y719477D02*
X261167Y720102D01*
G01Y722369D02*
X261125Y722661D01*
X261000Y722994D01*
X260792Y723202D01*
X260500Y723286D01*
X260209Y723202D01*
X259959Y722952D01*
X259834Y722577D01*
Y722161D01*
X259750Y721911D01*
X259542Y721702D01*
X259250Y721619D01*
X258959Y721744D01*
X258750Y722036D01*
X258667Y722369D01*
X258750Y722702D01*
X258959Y722994D01*
X259250Y723119D01*
X259542Y723036D01*
X259750Y722827D01*
X259834Y722577D01*
Y722161D01*
X259959Y721786D01*
X260209Y721536D01*
X260500Y721452D01*
X260792Y721536D01*
X261000Y721744D01*
X261125Y722077D01*
X261167Y722369D01*
G01Y725469D02*
X258667D01*
X259167Y724969D01*
G01X261167D02*
Y725969D01*
G01X264086Y731903D02*
Y734403D01*
X265127D01*
X265461Y734278D01*
X265669Y734111D01*
X265752Y733778D01*
X265669Y733445D01*
X265419Y733236D01*
X265127Y733111D01*
X264086D01*
G01X265127D02*
X265752Y731903D01*
G01X267102Y732278D02*
X267352Y732070D01*
X267644Y731945D01*
X268019Y731903D01*
X268394Y731986D01*
X268686Y732153D01*
X268894Y732445D01*
X268936Y732778D01*
X268852Y733111D01*
X268644Y733320D01*
X268352Y733486D01*
X268061Y733528D01*
X267769Y733486D01*
X267394Y733320D01*
X267519Y734403D01*
X268644D01*
G01X271119D02*
X270786Y734320D01*
X270536Y734111D01*
X270369Y733861D01*
X270244Y733528D01*
X270202Y733153D01*
X270244Y732778D01*
X270369Y732445D01*
X270536Y732195D01*
X270786Y731986D01*
X271119Y731903D01*
X271452Y731986D01*
X271702Y732195D01*
X271869Y732445D01*
X271994Y732778D01*
X272036Y733153D01*
X271994Y733528D01*
X271869Y733861D01*
X271702Y734111D01*
X271452Y734320D01*
X271119Y734403D01*
G01X273511Y732195D02*
X273802Y731986D01*
X274136Y731903D01*
X274469Y731986D01*
X274761Y732236D01*
X274969Y732611D01*
X275052Y732986D01*
Y733445D01*
X274969Y733820D01*
X274761Y734153D01*
X274511Y734320D01*
X274219Y734403D01*
X273886Y734320D01*
X273636Y734153D01*
X273469Y733903D01*
X273386Y733570D01*
X273469Y733278D01*
X273677Y732986D01*
X273927Y732820D01*
X274219Y732778D01*
X274552Y732861D01*
X274802Y733070D01*
X275052Y733445D01*
G01X270020Y721420D02*
Y717420D01*
X277420D01*
G01X265834Y714567D02*
X263334D01*
Y715608D01*
X263459Y715942D01*
X263626Y716150D01*
X263959Y716233D01*
X264292Y716150D01*
X264501Y715900D01*
X264626Y715608D01*
Y714567D01*
G01Y715608D02*
X265834Y716233D01*
G01Y718500D02*
X265792Y718792D01*
X265667Y719125D01*
X265459Y719333D01*
X265167Y719417D01*
X264876Y719333D01*
X264626Y719083D01*
X264501Y718708D01*
Y718292D01*
X264417Y718042D01*
X264209Y717833D01*
X263917Y717750D01*
X263626Y717875D01*
X263417Y718167D01*
X263334Y718500D01*
X263417Y718833D01*
X263626Y719125D01*
X263917Y719250D01*
X264209Y719167D01*
X264417Y718958D01*
X264501Y718708D01*
Y718292D01*
X264626Y717917D01*
X264876Y717667D01*
X265167Y717583D01*
X265459Y717667D01*
X265667Y717875D01*
X265792Y718208D01*
X265834Y718500D01*
G01X263751Y720808D02*
X263501Y721058D01*
X263376Y721350D01*
X263334Y721683D01*
X263417Y722100D01*
X263626Y722392D01*
X263876Y722475D01*
X264126Y722433D01*
X264334Y722267D01*
X264751Y721433D01*
X265042Y721058D01*
X265459Y720808D01*
X265834Y720725D01*
Y722475D01*
G01X264086Y735903D02*
Y738403D01*
X265127D01*
X265461Y738278D01*
X265669Y738111D01*
X265752Y737778D01*
X265669Y737445D01*
X265419Y737236D01*
X265127Y737111D01*
X264086D01*
G01X265127D02*
X265752Y735903D01*
G01X267102Y736278D02*
X267352Y736070D01*
X267644Y735945D01*
X268019Y735903D01*
X268394Y735986D01*
X268686Y736153D01*
X268894Y736445D01*
X268936Y736778D01*
X268852Y737111D01*
X268644Y737320D01*
X268352Y737486D01*
X268061Y737528D01*
X267769Y737486D01*
X267394Y737320D01*
X267519Y738403D01*
X268644D01*
G01X271119Y735903D02*
Y738403D01*
X270619Y737903D01*
G01Y735903D02*
X271619D01*
G01X274219Y738403D02*
X273886Y738320D01*
X273636Y738111D01*
X273469Y737861D01*
X273344Y737528D01*
X273302Y737153D01*
X273344Y736778D01*
X273469Y736445D01*
X273636Y736195D01*
X273886Y735986D01*
X274219Y735903D01*
X274552Y735986D01*
X274802Y736195D01*
X274969Y736445D01*
X275094Y736778D01*
X275136Y737153D01*
X275094Y737528D01*
X274969Y737861D01*
X274802Y738111D01*
X274552Y738320D01*
X274219Y738403D01*
G01X277390Y721570D02*
Y725570D01*
X269990D01*
G01X247517Y713500D02*
Y716000D01*
X248558D01*
X248892Y715875D01*
X249100Y715708D01*
X249183Y715375D01*
X249100Y715042D01*
X248850Y714833D01*
X248558Y714708D01*
X247517D01*
G01X248558D02*
X249183Y713500D01*
G01X250533Y714000D02*
X250783Y713708D01*
X251117Y713542D01*
X251492Y713500D01*
X251825Y713542D01*
X252158Y713750D01*
X252367Y714000D01*
X252408Y714250D01*
X252325Y714542D01*
X252033Y714750D01*
X251742Y714833D01*
X251367D01*
G01X251742D02*
X251992Y714958D01*
X252200Y715167D01*
X252283Y715417D01*
X252200Y715667D01*
X251992Y715875D01*
X251617Y716000D01*
X251242Y715958D01*
X250867Y715792D01*
G01X253633Y713875D02*
X253883Y713667D01*
X254175Y713542D01*
X254550Y713500D01*
X254925Y713583D01*
X255217Y713750D01*
X255425Y714042D01*
X255467Y714375D01*
X255383Y714708D01*
X255175Y714917D01*
X254883Y715083D01*
X254592Y715125D01*
X254300Y715083D01*
X253925Y714917D01*
X254050Y716000D01*
X255175D01*
G01X256858Y714542D02*
X257150Y714833D01*
X257400Y715000D01*
X257733Y715083D01*
X258025Y715000D01*
X258233Y714833D01*
X258400Y714583D01*
X258442Y714292D01*
X258400Y714042D01*
X258233Y713792D01*
X257983Y713583D01*
X257692Y713500D01*
X257358Y713583D01*
X257067Y713833D01*
X256900Y714208D01*
X256858Y714625D01*
X256942Y715167D01*
X257067Y715458D01*
X257275Y715750D01*
X257567Y715958D01*
X257858Y716000D01*
X258150Y715917D01*
X258358Y715708D01*
G01X280308Y743767D02*
X280183Y743517D01*
X280100Y743225D01*
Y742892D01*
X280225Y742517D01*
X280433Y742225D01*
X280683Y742017D01*
X281100Y741850D01*
X281475Y741808D01*
X281850Y741892D01*
X282100Y742017D01*
X282350Y742267D01*
X282517Y742558D01*
X282600Y742850D01*
Y743142D01*
X282517Y743433D01*
X282392Y743683D01*
X282225Y743892D01*
G01X282600Y745950D02*
X280100D01*
X280600Y745450D01*
G01X282600D02*
Y746450D01*
G01X282308Y748342D02*
X282517Y748633D01*
X282600Y748967D01*
X282517Y749300D01*
X282267Y749592D01*
X281892Y749800D01*
X281517Y749883D01*
X281058D01*
X280683Y749800D01*
X280350Y749592D01*
X280183Y749342D01*
X280100Y749050D01*
X280183Y748717D01*
X280350Y748467D01*
X280600Y748300D01*
X280933Y748217D01*
X281225Y748300D01*
X281517Y748508D01*
X281683Y748758D01*
X281725Y749050D01*
X281642Y749383D01*
X281433Y749633D01*
X281058Y749883D01*
G01X282600Y752067D02*
X282058Y752150D01*
X281600Y752275D01*
X281183Y752442D01*
X280725Y752650D01*
X280100Y752983D01*
Y751317D01*
G01X234017Y743167D02*
Y745667D01*
X235058D01*
X235392Y745542D01*
X235600Y745375D01*
X235683Y745042D01*
X235600Y744709D01*
X235350Y744500D01*
X235058Y744375D01*
X234017D01*
G01X235058D02*
X235683Y743167D01*
G01X238450D02*
Y745667D01*
X236908Y743875D01*
X238992D01*
G01X241050Y743167D02*
X241342Y743209D01*
X241675Y743334D01*
X241883Y743542D01*
X241967Y743834D01*
X241883Y744125D01*
X241633Y744375D01*
X241258Y744500D01*
X240842D01*
X240592Y744584D01*
X240383Y744792D01*
X240300Y745084D01*
X240425Y745375D01*
X240717Y745584D01*
X241050Y745667D01*
X241383Y745584D01*
X241675Y745375D01*
X241800Y745084D01*
X241717Y744792D01*
X241508Y744584D01*
X241258Y744500D01*
X240842D01*
X240467Y744375D01*
X240217Y744125D01*
X240133Y743834D01*
X240217Y743542D01*
X240425Y743334D01*
X240758Y743209D01*
X241050Y743167D01*
G01X244150D02*
Y745667D01*
X243650Y745167D01*
G01Y743167D02*
X244650D01*
G01X246499Y722747D02*
Y714747D01*
X228899D01*
Y722747D01*
X246499D01*
G01X234017Y747167D02*
Y749667D01*
X235058D01*
X235392Y749542D01*
X235600Y749375D01*
X235683Y749042D01*
X235600Y748709D01*
X235350Y748500D01*
X235058Y748375D01*
X234017D01*
G01X235058D02*
X235683Y747167D01*
G01X238450D02*
Y749667D01*
X236908Y747875D01*
X238992D01*
G01X241050Y747167D02*
X241342Y747209D01*
X241675Y747334D01*
X241883Y747542D01*
X241967Y747834D01*
X241883Y748125D01*
X241633Y748375D01*
X241258Y748500D01*
X240842D01*
X240592Y748584D01*
X240383Y748792D01*
X240300Y749084D01*
X240425Y749375D01*
X240717Y749584D01*
X241050Y749667D01*
X241383Y749584D01*
X241675Y749375D01*
X241800Y749084D01*
X241717Y748792D01*
X241508Y748584D01*
X241258Y748500D01*
X240842D01*
X240467Y748375D01*
X240217Y748125D01*
X240133Y747834D01*
X240217Y747542D01*
X240425Y747334D01*
X240758Y747209D01*
X241050Y747167D01*
G01X244150Y749667D02*
X243817Y749584D01*
X243567Y749375D01*
X243400Y749125D01*
X243275Y748792D01*
X243233Y748417D01*
X243275Y748042D01*
X243400Y747709D01*
X243567Y747459D01*
X243817Y747250D01*
X244150Y747167D01*
X244483Y747250D01*
X244733Y747459D01*
X244900Y747709D01*
X245025Y748042D01*
X245067Y748417D01*
X245025Y748792D01*
X244900Y749125D01*
X244733Y749375D01*
X244483Y749584D01*
X244150Y749667D01*
G01X246499Y732347D02*
Y724347D01*
X228899D01*
Y732347D01*
X246499D01*
G01X234017Y751167D02*
Y753667D01*
X235058D01*
X235392Y753542D01*
X235600Y753375D01*
X235683Y753042D01*
X235600Y752709D01*
X235350Y752500D01*
X235058Y752375D01*
X234017D01*
G01X235058D02*
X235683Y751167D01*
G01X238450D02*
Y753667D01*
X236908Y751875D01*
X238992D01*
G01X240967Y751167D02*
X241050Y751709D01*
X241175Y752167D01*
X241342Y752584D01*
X241550Y753042D01*
X241883Y753667D01*
X240217D01*
G01X243442Y751459D02*
X243733Y751250D01*
X244067Y751167D01*
X244400Y751250D01*
X244692Y751500D01*
X244900Y751875D01*
X244983Y752250D01*
Y752709D01*
X244900Y753084D01*
X244692Y753417D01*
X244442Y753584D01*
X244150Y753667D01*
X243817Y753584D01*
X243567Y753417D01*
X243400Y753167D01*
X243317Y752834D01*
X243400Y752542D01*
X243608Y752250D01*
X243858Y752084D01*
X244150Y752042D01*
X244483Y752125D01*
X244733Y752334D01*
X244983Y752709D01*
G01X246499Y741947D02*
Y733947D01*
X228899D01*
Y741947D01*
X246499D01*
G01X279270Y728223D02*
X276770D01*
Y729223D01*
X276895Y729556D01*
X277187Y729806D01*
X277520Y729889D01*
X277853Y729806D01*
X278103Y729598D01*
X278228Y729223D01*
Y728223D01*
G01X276770Y731239D02*
X278562D01*
X278937Y731406D01*
X279187Y731739D01*
X279270Y732156D01*
X279187Y732573D01*
X278937Y732906D01*
X278562Y733073D01*
X276770D01*
G01X278978Y734548D02*
X279187Y734839D01*
X279270Y735173D01*
X279187Y735506D01*
X278937Y735798D01*
X278562Y736006D01*
X278187Y736089D01*
X277728D01*
X277353Y736006D01*
X277020Y735798D01*
X276853Y735548D01*
X276770Y735256D01*
X276853Y734923D01*
X277020Y734673D01*
X277270Y734506D01*
X277603Y734423D01*
X277895Y734506D01*
X278187Y734714D01*
X278353Y734964D01*
X278395Y735256D01*
X278312Y735589D01*
X278103Y735839D01*
X277728Y736089D01*
G01X286784Y723920D02*
X281784D01*
Y718920D01*
G01X331981Y26318D02*
X333773D01*
X334148Y26485D01*
X334398Y26818D01*
X334481Y27235D01*
X334398Y27652D01*
X334148Y27985D01*
X333773Y28152D01*
X331981D01*
G01X334148Y29460D02*
X334356Y29793D01*
X334481Y30168D01*
Y30502D01*
X334356Y30835D01*
X334148Y31085D01*
X333856Y31210D01*
X333564Y31127D01*
X333314Y30918D01*
X333148Y30543D01*
X333064Y30043D01*
X332898Y29752D01*
X332606Y29627D01*
X332314Y29710D01*
X332106Y29918D01*
X331981Y30210D01*
Y30502D01*
X332064Y30793D01*
X332273Y31043D01*
G01X333148Y33768D02*
X333023Y33935D01*
X332814Y34060D01*
X332523Y34143D01*
X332273Y34060D01*
X332106Y33893D01*
X331981Y33602D01*
Y32477D01*
X334481D01*
Y33852D01*
X334314Y34143D01*
X334064Y34310D01*
X333773Y34393D01*
X333481Y34310D01*
X333231Y34060D01*
X333148Y33768D01*
Y32477D01*
G01X334481Y36535D02*
X331981D01*
X332481Y36035D01*
G01X334481D02*
Y37035D01*
G01X363650Y0D02*
Y-3197D01*
X336350D01*
G01X363650Y0D02*
X336350D01*
Y44003D01*
X335350D01*
Y55603D01*
X336350D01*
Y87503D01*
X335350D01*
Y100203D01*
X364650D01*
Y86103D01*
X363650D01*
Y54253D01*
X364650D01*
Y45353D01*
X363650D01*
Y0D01*
G01X336350Y-3197D02*
Y0D01*
G01X343708Y133867D02*
X343583Y133617D01*
X343500Y133325D01*
Y132992D01*
X343625Y132617D01*
X343833Y132325D01*
X344083Y132117D01*
X344500Y131950D01*
X344875Y131908D01*
X345250Y131992D01*
X345500Y132117D01*
X345750Y132367D01*
X345917Y132658D01*
X346000Y132950D01*
Y133242D01*
X345917Y133533D01*
X345792Y133783D01*
X345625Y133992D01*
G01X343917Y135258D02*
X343667Y135508D01*
X343542Y135800D01*
X343500Y136133D01*
X343583Y136550D01*
X343792Y136842D01*
X344042Y136925D01*
X344292Y136883D01*
X344500Y136717D01*
X344917Y135883D01*
X345208Y135508D01*
X345625Y135258D01*
X346000Y135175D01*
Y136925D01*
G01X321708Y113317D02*
X321583Y113067D01*
X321500Y112775D01*
Y112442D01*
X321625Y112067D01*
X321833Y111775D01*
X322083Y111567D01*
X322500Y111400D01*
X322875Y111358D01*
X323250Y111442D01*
X323500Y111567D01*
X323750Y111817D01*
X323917Y112108D01*
X324000Y112400D01*
Y112692D01*
X323917Y112983D01*
X323792Y113233D01*
X323625Y113442D01*
G01X321917Y114708D02*
X321667Y114958D01*
X321542Y115250D01*
X321500Y115583D01*
X321583Y116000D01*
X321792Y116292D01*
X322042Y116375D01*
X322292Y116333D01*
X322500Y116167D01*
X322917Y115333D01*
X323208Y114958D01*
X323625Y114708D01*
X324000Y114625D01*
Y116375D01*
G01X321917Y117808D02*
X321667Y118058D01*
X321542Y118350D01*
X321500Y118683D01*
X321583Y119100D01*
X321792Y119392D01*
X322042Y119475D01*
X322292Y119433D01*
X322500Y119267D01*
X322917Y118433D01*
X323208Y118058D01*
X323625Y117808D01*
X324000Y117725D01*
Y119475D01*
G01X325708Y113317D02*
X325583Y113067D01*
X325500Y112775D01*
Y112442D01*
X325625Y112067D01*
X325833Y111775D01*
X326083Y111567D01*
X326500Y111400D01*
X326875Y111358D01*
X327250Y111442D01*
X327500Y111567D01*
X327750Y111817D01*
X327917Y112108D01*
X328000Y112400D01*
Y112692D01*
X327917Y112983D01*
X327792Y113233D01*
X327625Y113442D01*
G01X325917Y114708D02*
X325667Y114958D01*
X325542Y115250D01*
X325500Y115583D01*
X325583Y116000D01*
X325792Y116292D01*
X326042Y116375D01*
X326292Y116333D01*
X326500Y116167D01*
X326917Y115333D01*
X327208Y114958D01*
X327625Y114708D01*
X328000Y114625D01*
Y116375D01*
G01Y118600D02*
X325500D01*
X326000Y118100D01*
G01X328000D02*
Y119100D01*
G01X317500Y111567D02*
X320000D01*
Y113233D01*
G01X317917Y114708D02*
X317667Y114958D01*
X317542Y115250D01*
X317500Y115583D01*
X317583Y116000D01*
X317792Y116292D01*
X318042Y116375D01*
X318292Y116333D01*
X318500Y116167D01*
X318917Y115333D01*
X319208Y114958D01*
X319625Y114708D01*
X320000Y114625D01*
Y116375D01*
G01X319500Y117683D02*
X319792Y117933D01*
X319958Y118267D01*
X320000Y118642D01*
X319958Y118975D01*
X319750Y119308D01*
X319500Y119517D01*
X319250Y119558D01*
X318958Y119475D01*
X318750Y119183D01*
X318667Y118892D01*
Y118517D01*
G01Y118892D02*
X318542Y119142D01*
X318333Y119350D01*
X318083Y119433D01*
X317833Y119350D01*
X317625Y119142D01*
X317500Y118767D01*
X317542Y118392D01*
X317708Y118017D01*
G01X329900Y121700D02*
Y108300D01*
G01X337100Y121700D02*
X329900D01*
G01X337100Y108300D02*
Y121700D01*
G01X329900Y108300D02*
X337100D01*
G01X349047Y129020D02*
Y127228D01*
X349214Y126853D01*
X349547Y126603D01*
X349964Y126520D01*
X350381Y126603D01*
X350714Y126853D01*
X350881Y127228D01*
Y129020D01*
G01X352356Y126812D02*
X352647Y126603D01*
X352981Y126520D01*
X353314Y126603D01*
X353606Y126853D01*
X353814Y127228D01*
X353897Y127603D01*
Y128062D01*
X353814Y128437D01*
X353606Y128770D01*
X353356Y128937D01*
X353064Y129020D01*
X352731Y128937D01*
X352481Y128770D01*
X352314Y128520D01*
X352231Y128187D01*
X352314Y127895D01*
X352522Y127603D01*
X352772Y127437D01*
X353064Y127395D01*
X353397Y127478D01*
X353647Y127687D01*
X353897Y128062D01*
G01X356164Y126520D02*
X356456Y126562D01*
X356789Y126687D01*
X356997Y126895D01*
X357081Y127187D01*
X356997Y127478D01*
X356747Y127728D01*
X356372Y127853D01*
X355956D01*
X355706Y127937D01*
X355497Y128145D01*
X355414Y128437D01*
X355539Y128728D01*
X355831Y128937D01*
X356164Y129020D01*
X356497Y128937D01*
X356789Y128728D01*
X356914Y128437D01*
X356831Y128145D01*
X356622Y127937D01*
X356372Y127853D01*
X355956D01*
X355581Y127728D01*
X355331Y127478D01*
X355247Y127187D01*
X355331Y126895D01*
X355539Y126687D01*
X355872Y126562D01*
X356164Y126520D01*
G01X349500Y117000D02*
Y109000D01*
G01Y123000D02*
Y117000D01*
G01Y123000D02*
Y109000D01*
G01X367500Y123000D02*
X349500D01*
G01Y109000D02*
X367500D01*
G01X338333Y102713D02*
Y105213D01*
X339167D01*
X339500Y105088D01*
X339750Y104921D01*
X339958Y104671D01*
X340125Y104380D01*
X340167Y103963D01*
X340125Y103546D01*
X339958Y103255D01*
X339750Y103005D01*
X339500Y102838D01*
X339167Y102713D01*
X338333D01*
G01X342350D02*
Y105213D01*
X341850Y104713D01*
G01Y102713D02*
X342850D01*
G01X344533Y103213D02*
X344783Y102921D01*
X345117Y102755D01*
X345492Y102713D01*
X345825Y102755D01*
X346158Y102963D01*
X346367Y103213D01*
X346408Y103463D01*
X346325Y103755D01*
X346033Y103963D01*
X345742Y104046D01*
X345367D01*
G01X345742D02*
X345992Y104171D01*
X346200Y104380D01*
X346283Y104630D01*
X346200Y104880D01*
X345992Y105088D01*
X345617Y105213D01*
X345242Y105171D01*
X344867Y105005D01*
G01X340767Y170770D02*
X340517Y170895D01*
X340225Y170978D01*
X339892D01*
X339517Y170853D01*
X339225Y170645D01*
X339017Y170395D01*
X338850Y169978D01*
X338808Y169603D01*
X338892Y169228D01*
X339017Y168978D01*
X339267Y168728D01*
X339558Y168561D01*
X339850Y168478D01*
X340142D01*
X340433Y168561D01*
X340683Y168686D01*
X340892Y168853D01*
G01X342950Y168478D02*
Y170978D01*
X342450Y170478D01*
G01Y168478D02*
X343450D01*
G01X346050D02*
X346342Y168520D01*
X346675Y168645D01*
X346883Y168853D01*
X346967Y169145D01*
X346883Y169436D01*
X346633Y169686D01*
X346258Y169811D01*
X345842D01*
X345592Y169895D01*
X345383Y170103D01*
X345300Y170395D01*
X345425Y170686D01*
X345717Y170895D01*
X346050Y170978D01*
X346383Y170895D01*
X346675Y170686D01*
X346800Y170395D01*
X346717Y170103D01*
X346508Y169895D01*
X346258Y169811D01*
X345842D01*
X345467Y169686D01*
X345217Y169436D01*
X345133Y169145D01*
X345217Y168853D01*
X345425Y168645D01*
X345758Y168520D01*
X346050Y168478D01*
G01X348442Y168770D02*
X348733Y168561D01*
X349067Y168478D01*
X349400Y168561D01*
X349692Y168811D01*
X349900Y169186D01*
X349983Y169561D01*
Y170020D01*
X349900Y170395D01*
X349692Y170728D01*
X349442Y170895D01*
X349150Y170978D01*
X348817Y170895D01*
X348567Y170728D01*
X348400Y170478D01*
X348317Y170145D01*
X348400Y169853D01*
X348608Y169561D01*
X348858Y169395D01*
X349150Y169353D01*
X349483Y169436D01*
X349733Y169645D01*
X349983Y170020D01*
G01X339017Y172478D02*
Y174978D01*
X340058D01*
X340392Y174853D01*
X340600Y174686D01*
X340683Y174353D01*
X340600Y174020D01*
X340350Y173811D01*
X340058Y173686D01*
X339017D01*
G01X340058D02*
X340683Y172478D01*
G01X342033Y172853D02*
X342283Y172645D01*
X342575Y172520D01*
X342950Y172478D01*
X343325Y172561D01*
X343617Y172728D01*
X343825Y173020D01*
X343867Y173353D01*
X343783Y173686D01*
X343575Y173895D01*
X343283Y174061D01*
X342992Y174103D01*
X342700Y174061D01*
X342325Y173895D01*
X342450Y174978D01*
X343575D01*
G01X345258Y174561D02*
X345508Y174811D01*
X345800Y174936D01*
X346133Y174978D01*
X346550Y174895D01*
X346842Y174686D01*
X346925Y174436D01*
X346883Y174186D01*
X346717Y173978D01*
X345883Y173561D01*
X345508Y173270D01*
X345258Y172853D01*
X345175Y172478D01*
X346925D01*
G01X348233Y172978D02*
X348483Y172686D01*
X348817Y172520D01*
X349192Y172478D01*
X349525Y172520D01*
X349858Y172728D01*
X350067Y172978D01*
X350108Y173228D01*
X350025Y173520D01*
X349733Y173728D01*
X349442Y173811D01*
X349067D01*
G01X349442D02*
X349692Y173936D01*
X349900Y174145D01*
X349983Y174395D01*
X349900Y174645D01*
X349692Y174853D01*
X349317Y174978D01*
X348942Y174936D01*
X348567Y174770D01*
G01X345782Y195578D02*
Y191578D01*
X353182D01*
G01X336500Y162545D02*
X334000D01*
Y163586D01*
X334125Y163920D01*
X334292Y164128D01*
X334625Y164211D01*
X334958Y164128D01*
X335167Y163878D01*
X335292Y163586D01*
Y162545D01*
G01Y163586D02*
X336500Y164211D01*
G01Y166478D02*
X334000D01*
X334500Y165978D01*
G01X336500D02*
Y166978D01*
G01X335458Y168786D02*
X335167Y169078D01*
X335000Y169328D01*
X334917Y169661D01*
X335000Y169953D01*
X335167Y170161D01*
X335417Y170328D01*
X335708Y170370D01*
X335958Y170328D01*
X336208Y170161D01*
X336417Y169911D01*
X336500Y169620D01*
X336417Y169286D01*
X336167Y168995D01*
X335792Y168828D01*
X335375Y168786D01*
X334833Y168870D01*
X334542Y168995D01*
X334250Y169203D01*
X334042Y169495D01*
X334000Y169786D01*
X334083Y170078D01*
X334292Y170286D01*
G01X345582Y183878D02*
X341582D01*
Y176478D01*
G01X339567Y162978D02*
Y165478D01*
X340608D01*
X340942Y165353D01*
X341150Y165186D01*
X341233Y164853D01*
X341150Y164520D01*
X340900Y164311D01*
X340608Y164186D01*
X339567D01*
G01X340608D02*
X341233Y162978D01*
G01X343500D02*
Y165478D01*
X343000Y164978D01*
G01Y162978D02*
X344000D01*
G01X346600Y165478D02*
X346267Y165395D01*
X346017Y165186D01*
X345850Y164936D01*
X345725Y164603D01*
X345683Y164228D01*
X345725Y163853D01*
X345850Y163520D01*
X346017Y163270D01*
X346267Y163061D01*
X346600Y162978D01*
X346933Y163061D01*
X347183Y163270D01*
X347350Y163520D01*
X347475Y163853D01*
X347517Y164228D01*
X347475Y164603D01*
X347350Y164936D01*
X347183Y165186D01*
X346933Y165395D01*
X346600Y165478D01*
G01X346082Y180678D02*
Y176678D01*
X353482D01*
G01X336882Y204045D02*
X334382D01*
Y205045D01*
X334507Y205378D01*
X334799Y205628D01*
X335132Y205711D01*
X335465Y205628D01*
X335715Y205420D01*
X335840Y205045D01*
Y204045D01*
G01X336882Y207978D02*
X336840Y207645D01*
X336674Y207353D01*
X336424Y207103D01*
X336132Y206936D01*
X335799Y206853D01*
X335465D01*
X335132Y206936D01*
X334840Y207103D01*
X334590Y207353D01*
X334424Y207645D01*
X334382Y207978D01*
X334424Y208311D01*
X334590Y208603D01*
X334840Y208853D01*
X335132Y209020D01*
X335465Y209103D01*
X335799D01*
X336132Y209020D01*
X336424Y208853D01*
X336674Y208603D01*
X336840Y208311D01*
X336882Y207978D01*
G01X336215Y208311D02*
X336882Y208811D01*
G01X336382Y210161D02*
X336674Y210411D01*
X336840Y210745D01*
X336882Y211120D01*
X336840Y211453D01*
X336632Y211786D01*
X336382Y211995D01*
X336132Y212036D01*
X335840Y211953D01*
X335632Y211661D01*
X335549Y211370D01*
Y210995D01*
G01Y211370D02*
X335424Y211620D01*
X335215Y211828D01*
X334965Y211911D01*
X334715Y211828D01*
X334507Y211620D01*
X334382Y211245D01*
X334424Y210870D01*
X334590Y210495D01*
G01X338311Y204368D02*
X357511D01*
Y215568D01*
X338311D01*
Y204368D01*
X338711D01*
G01X352208Y142067D02*
X352083Y141817D01*
X352000Y141525D01*
Y141192D01*
X352125Y140817D01*
X352333Y140525D01*
X352583Y140317D01*
X353000Y140150D01*
X353375Y140108D01*
X353750Y140192D01*
X354000Y140317D01*
X354250Y140567D01*
X354417Y140858D01*
X354500Y141150D01*
Y141442D01*
X354417Y141733D01*
X354292Y141983D01*
X354125Y142192D01*
G01X352417Y143458D02*
X352167Y143708D01*
X352042Y144000D01*
X352000Y144333D01*
X352083Y144750D01*
X352292Y145042D01*
X352542Y145125D01*
X352792Y145083D01*
X353000Y144917D01*
X353417Y144083D01*
X353708Y143708D01*
X354125Y143458D01*
X354500Y143375D01*
Y145125D01*
G01Y147850D02*
X352000D01*
X353792Y146308D01*
Y148392D01*
G01X353458Y149658D02*
X353167Y149950D01*
X353000Y150200D01*
X352917Y150533D01*
X353000Y150825D01*
X353167Y151033D01*
X353417Y151200D01*
X353708Y151242D01*
X353958Y151200D01*
X354208Y151033D01*
X354417Y150783D01*
X354500Y150492D01*
X354417Y150158D01*
X354167Y149867D01*
X353792Y149700D01*
X353375Y149658D01*
X352833Y149742D01*
X352542Y149867D01*
X352250Y150075D01*
X352042Y150367D01*
X352000Y150658D01*
X352083Y150950D01*
X352292Y151158D01*
G01X299099Y174374D02*
Y176874D01*
X300182Y174791D01*
X301265Y176874D01*
Y174374D01*
G01X304115D02*
X302449D01*
Y176874D01*
X304115D01*
G01X303449Y175666D02*
X302449D01*
G01X305590Y176874D02*
X307174D01*
X305590Y174374D01*
X307174D01*
G01X308690Y176874D02*
X310274D01*
X308690Y174374D01*
X310274D01*
G01X312582D02*
Y176874D01*
X312082Y176374D01*
G01Y174374D02*
X313082D01*
G01X292106Y392530D02*
Y178730D01*
X319706D01*
Y392530D01*
X292106D01*
G01X328165Y226178D02*
Y228678D01*
X329206D01*
X329540Y228553D01*
X329748Y228386D01*
X329831Y228053D01*
X329748Y227720D01*
X329498Y227511D01*
X329206Y227386D01*
X328165D01*
G01X329206D02*
X329831Y226178D01*
G01X331181Y226678D02*
X331431Y226386D01*
X331765Y226220D01*
X332140Y226178D01*
X332473Y226220D01*
X332806Y226428D01*
X333015Y226678D01*
X333056Y226928D01*
X332973Y227220D01*
X332681Y227428D01*
X332390Y227511D01*
X332015D01*
G01X332390D02*
X332640Y227636D01*
X332848Y227845D01*
X332931Y228095D01*
X332848Y228345D01*
X332640Y228553D01*
X332265Y228678D01*
X331890Y228636D01*
X331515Y228470D01*
G01X345748Y226017D02*
Y230017D01*
X338348D01*
G01X346082Y259778D02*
Y255778D01*
X353482D01*
G01X353361Y249004D02*
Y253004D01*
X345961D01*
G01X353361Y245004D02*
Y249004D01*
X345961D01*
G01X353362Y240193D02*
Y244193D01*
X345962D01*
G01X328135Y230342D02*
Y232842D01*
X329176D01*
X329510Y232717D01*
X329718Y232550D01*
X329801Y232217D01*
X329718Y231884D01*
X329468Y231675D01*
X329176Y231550D01*
X328135D01*
G01X329176D02*
X329801Y230342D01*
G01X332568D02*
Y232842D01*
X331026Y231050D01*
X333110D01*
G01X338318Y234181D02*
Y230181D01*
X345718D01*
G01X349882Y276478D02*
X345882D01*
Y269078D01*
G01X349882Y263778D02*
Y267778D01*
X342482D01*
G01X338411Y211968D02*
X340511Y210168D01*
X338411Y207968D01*
G01X369105Y229015D02*
Y238115D01*
X347305D01*
Y229015D01*
X369105D01*
G01X336000Y432500D02*
Y396800D01*
X381600D01*
Y380500D01*
X406000D01*
Y470000D01*
X341500D01*
G01X353212Y420086D02*
X352962Y420211D01*
X352670Y420294D01*
X352337D01*
X351962Y420169D01*
X351670Y419961D01*
X351462Y419711D01*
X351295Y419294D01*
X351253Y418919D01*
X351337Y418544D01*
X351462Y418294D01*
X351712Y418044D01*
X352003Y417877D01*
X352295Y417794D01*
X352587D01*
X352878Y417877D01*
X353128Y418002D01*
X353337Y418169D01*
G01X354603Y419877D02*
X354853Y420127D01*
X355145Y420252D01*
X355478Y420294D01*
X355895Y420211D01*
X356187Y420002D01*
X356270Y419752D01*
X356228Y419502D01*
X356062Y419294D01*
X355228Y418877D01*
X354853Y418586D01*
X354603Y418169D01*
X354520Y417794D01*
X356270D01*
G01X358412D02*
X358495Y418336D01*
X358620Y418794D01*
X358787Y419211D01*
X358995Y419669D01*
X359328Y420294D01*
X357662D01*
G01X349017Y409392D02*
X348767Y409517D01*
X348475Y409600D01*
X348142D01*
X347767Y409475D01*
X347475Y409267D01*
X347267Y409017D01*
X347100Y408600D01*
X347058Y408225D01*
X347142Y407850D01*
X347267Y407600D01*
X347517Y407350D01*
X347808Y407183D01*
X348100Y407100D01*
X348392D01*
X348683Y407183D01*
X348933Y407308D01*
X349142Y407475D01*
G01X351700Y407100D02*
Y409600D01*
X350158Y407808D01*
X352242D01*
G01X354300Y409600D02*
X353967Y409517D01*
X353717Y409308D01*
X353550Y409058D01*
X353425Y408725D01*
X353383Y408350D01*
X353425Y407975D01*
X353550Y407642D01*
X353717Y407392D01*
X353967Y407183D01*
X354300Y407100D01*
X354633Y407183D01*
X354883Y407392D01*
X355050Y407642D01*
X355175Y407975D01*
X355217Y408350D01*
X355175Y408725D01*
X355050Y409058D01*
X354883Y409308D01*
X354633Y409517D01*
X354300Y409600D01*
G01X351622Y422206D02*
Y424706D01*
X352663D01*
X352997Y424581D01*
X353205Y424414D01*
X353288Y424081D01*
X353205Y423748D01*
X352955Y423539D01*
X352663Y423414D01*
X351622D01*
G01X352663D02*
X353288Y422206D01*
G01X354638Y422581D02*
X354888Y422373D01*
X355180Y422248D01*
X355555Y422206D01*
X355930Y422289D01*
X356222Y422456D01*
X356430Y422748D01*
X356472Y423081D01*
X356388Y423414D01*
X356180Y423623D01*
X355888Y423789D01*
X355597Y423831D01*
X355305Y423789D01*
X354930Y423623D01*
X355055Y424706D01*
X356180D01*
G01X358655Y422206D02*
Y424706D01*
X358155Y424206D01*
G01Y422206D02*
X359155D01*
G01X341692Y418121D02*
Y420621D01*
X342733D01*
X343067Y420496D01*
X343275Y420329D01*
X343358Y419996D01*
X343275Y419663D01*
X343025Y419454D01*
X342733Y419329D01*
X341692D01*
G01X342733D02*
X343358Y418121D01*
G01X346125D02*
Y420621D01*
X344583Y418829D01*
X346667D01*
G01X348017Y418413D02*
X348308Y418204D01*
X348642Y418121D01*
X348975Y418204D01*
X349267Y418454D01*
X349475Y418829D01*
X349558Y419204D01*
Y419663D01*
X349475Y420038D01*
X349267Y420371D01*
X349017Y420538D01*
X348725Y420621D01*
X348392Y420538D01*
X348142Y420371D01*
X347975Y420121D01*
X347892Y419788D01*
X347975Y419496D01*
X348183Y419204D01*
X348433Y419038D01*
X348725Y418996D01*
X349058Y419079D01*
X349308Y419288D01*
X349558Y419663D01*
G01X345717Y403300D02*
Y405800D01*
X346758D01*
X347092Y405675D01*
X347300Y405508D01*
X347383Y405175D01*
X347300Y404842D01*
X347050Y404633D01*
X346758Y404508D01*
X345717D01*
G01X346758D02*
X347383Y403300D01*
G01X349650D02*
Y405800D01*
X349150Y405300D01*
G01Y403300D02*
X350150D01*
G01X352750Y405800D02*
X352417Y405717D01*
X352167Y405508D01*
X352000Y405258D01*
X351875Y404925D01*
X351833Y404550D01*
X351875Y404175D01*
X352000Y403842D01*
X352167Y403592D01*
X352417Y403383D01*
X352750Y403300D01*
X353083Y403383D01*
X353333Y403592D01*
X353500Y403842D01*
X353625Y404175D01*
X353667Y404550D01*
X353625Y404925D01*
X353500Y405258D01*
X353333Y405508D01*
X353083Y405717D01*
X352750Y405800D01*
G01X354933Y403675D02*
X355183Y403467D01*
X355475Y403342D01*
X355850Y403300D01*
X356225Y403383D01*
X356517Y403550D01*
X356725Y403842D01*
X356767Y404175D01*
X356683Y404508D01*
X356475Y404717D01*
X356183Y404883D01*
X355892Y404925D01*
X355600Y404883D01*
X355225Y404717D01*
X355350Y405800D01*
X356475D01*
G01X347367Y398800D02*
Y401300D01*
X348408D01*
X348742Y401175D01*
X348950Y401008D01*
X349033Y400675D01*
X348950Y400342D01*
X348700Y400133D01*
X348408Y400008D01*
X347367D01*
G01X348408D02*
X349033Y398800D01*
G01X350592Y399092D02*
X350883Y398883D01*
X351217Y398800D01*
X351550Y398883D01*
X351842Y399133D01*
X352050Y399508D01*
X352133Y399883D01*
Y400342D01*
X352050Y400717D01*
X351842Y401050D01*
X351592Y401217D01*
X351300Y401300D01*
X350967Y401217D01*
X350717Y401050D01*
X350550Y400800D01*
X350467Y400467D01*
X350550Y400175D01*
X350758Y399883D01*
X351008Y399717D01*
X351300Y399675D01*
X351633Y399758D01*
X351883Y399967D01*
X352133Y400342D01*
G01X353692Y399092D02*
X353983Y398883D01*
X354317Y398800D01*
X354650Y398883D01*
X354942Y399133D01*
X355150Y399508D01*
X355233Y399883D01*
Y400342D01*
X355150Y400717D01*
X354942Y401050D01*
X354692Y401217D01*
X354400Y401300D01*
X354067Y401217D01*
X353817Y401050D01*
X353650Y400800D01*
X353567Y400467D01*
X353650Y400175D01*
X353858Y399883D01*
X354108Y399717D01*
X354400Y399675D01*
X354733Y399758D01*
X354983Y399967D01*
X355233Y400342D01*
G01X347367Y411000D02*
Y413500D01*
X348408D01*
X348742Y413375D01*
X348950Y413208D01*
X349033Y412875D01*
X348950Y412542D01*
X348700Y412333D01*
X348408Y412208D01*
X347367D01*
G01X348408D02*
X349033Y411000D01*
G01X350592Y411292D02*
X350883Y411083D01*
X351217Y411000D01*
X351550Y411083D01*
X351842Y411333D01*
X352050Y411708D01*
X352133Y412083D01*
Y412542D01*
X352050Y412917D01*
X351842Y413250D01*
X351592Y413417D01*
X351300Y413500D01*
X350967Y413417D01*
X350717Y413250D01*
X350550Y413000D01*
X350467Y412667D01*
X350550Y412375D01*
X350758Y412083D01*
X351008Y411917D01*
X351300Y411875D01*
X351633Y411958D01*
X351883Y412167D01*
X352133Y412542D01*
G01X354400Y411000D02*
X354692Y411042D01*
X355025Y411167D01*
X355233Y411375D01*
X355317Y411667D01*
X355233Y411958D01*
X354983Y412208D01*
X354608Y412333D01*
X354192D01*
X353942Y412417D01*
X353733Y412625D01*
X353650Y412917D01*
X353775Y413208D01*
X354067Y413417D01*
X354400Y413500D01*
X354733Y413417D01*
X355025Y413208D01*
X355150Y412917D01*
X355067Y412625D01*
X354858Y412417D01*
X354608Y412333D01*
X354192D01*
X353817Y412208D01*
X353567Y411958D01*
X353483Y411667D01*
X353567Y411375D01*
X353775Y411167D01*
X354108Y411042D01*
X354400Y411000D01*
G01X295500Y465000D02*
Y458500D01*
X299500D01*
G01X296000Y480000D02*
Y487000D01*
X298785D01*
G01X322963Y512403D02*
X321463Y510903D01*
X324463D01*
X322963Y512403D01*
Y494000D01*
X341500D01*
Y470000D01*
X336000D01*
Y436000D01*
G01X290500Y521000D02*
X301000D01*
Y512892D01*
X314000D01*
Y494500D01*
X303488D01*
Y489900D01*
G01X354267Y458792D02*
X354017Y458917D01*
X353725Y459000D01*
X353392D01*
X353017Y458875D01*
X352725Y458667D01*
X352517Y458417D01*
X352350Y458000D01*
X352308Y457625D01*
X352392Y457250D01*
X352517Y457000D01*
X352767Y456750D01*
X353058Y456583D01*
X353350Y456500D01*
X353642D01*
X353933Y456583D01*
X354183Y456708D01*
X354392Y456875D01*
G01X356450Y456500D02*
Y459000D01*
X355950Y458500D01*
G01Y456500D02*
X356950D01*
G01X358633Y457000D02*
X358883Y456708D01*
X359217Y456542D01*
X359592Y456500D01*
X359925Y456542D01*
X360258Y456750D01*
X360467Y457000D01*
X360508Y457250D01*
X360425Y457542D01*
X360133Y457750D01*
X359842Y457833D01*
X359467D01*
G01X359842D02*
X360092Y457958D01*
X360300Y458167D01*
X360383Y458417D01*
X360300Y458667D01*
X360092Y458875D01*
X359717Y459000D01*
X359342Y458958D01*
X358967Y458792D01*
G01X361733Y456875D02*
X361983Y456667D01*
X362275Y456542D01*
X362650Y456500D01*
X363025Y456583D01*
X363317Y456750D01*
X363525Y457042D01*
X363567Y457375D01*
X363483Y457708D01*
X363275Y457917D01*
X362983Y458083D01*
X362692Y458125D01*
X362400Y458083D01*
X362025Y457917D01*
X362150Y459000D01*
X363275D01*
G01X354317Y462792D02*
X354067Y462917D01*
X353775Y463000D01*
X353442D01*
X353067Y462875D01*
X352775Y462667D01*
X352567Y462417D01*
X352400Y462000D01*
X352358Y461625D01*
X352442Y461250D01*
X352567Y461000D01*
X352817Y460750D01*
X353108Y460583D01*
X353400Y460500D01*
X353692D01*
X353983Y460583D01*
X354233Y460708D01*
X354442Y460875D01*
G01X355583Y461000D02*
X355833Y460708D01*
X356167Y460542D01*
X356542Y460500D01*
X356875Y460542D01*
X357208Y460750D01*
X357417Y461000D01*
X357458Y461250D01*
X357375Y461542D01*
X357083Y461750D01*
X356792Y461833D01*
X356417D01*
G01X356792D02*
X357042Y461958D01*
X357250Y462167D01*
X357333Y462417D01*
X357250Y462667D01*
X357042Y462875D01*
X356667Y463000D01*
X356292Y462958D01*
X355917Y462792D01*
G01X359517Y460500D02*
X359600Y461042D01*
X359725Y461500D01*
X359892Y461917D01*
X360100Y462375D01*
X360433Y463000D01*
X358767D01*
G01X351567Y426500D02*
Y429000D01*
X352608D01*
X352942Y428875D01*
X353150Y428708D01*
X353233Y428375D01*
X353150Y428042D01*
X352900Y427833D01*
X352608Y427708D01*
X351567D01*
G01X352608D02*
X353233Y426500D01*
G01X354583Y426875D02*
X354833Y426667D01*
X355125Y426542D01*
X355500Y426500D01*
X355875Y426583D01*
X356167Y426750D01*
X356375Y427042D01*
X356417Y427375D01*
X356333Y427708D01*
X356125Y427917D01*
X355833Y428083D01*
X355542Y428125D01*
X355250Y428083D01*
X354875Y427917D01*
X355000Y429000D01*
X356125D01*
G01X358600Y426500D02*
X358892Y426542D01*
X359225Y426667D01*
X359433Y426875D01*
X359517Y427167D01*
X359433Y427458D01*
X359183Y427708D01*
X358808Y427833D01*
X358392D01*
X358142Y427917D01*
X357933Y428125D01*
X357850Y428417D01*
X357975Y428708D01*
X358267Y428917D01*
X358600Y429000D01*
X358933Y428917D01*
X359225Y428708D01*
X359350Y428417D01*
X359267Y428125D01*
X359058Y427917D01*
X358808Y427833D01*
X358392D01*
X358017Y427708D01*
X357767Y427458D01*
X357683Y427167D01*
X357767Y426875D01*
X357975Y426667D01*
X358308Y426542D01*
X358600Y426500D01*
G01X293702Y437781D02*
Y440281D01*
X294743D01*
X295077Y440156D01*
X295285Y439989D01*
X295368Y439656D01*
X295285Y439323D01*
X295035Y439114D01*
X294743Y438989D01*
X293702D01*
G01X294743D02*
X295368Y437781D01*
G01X297635D02*
Y440281D01*
X297135Y439781D01*
G01Y437781D02*
X298135D01*
G01X300027Y438073D02*
X300318Y437864D01*
X300652Y437781D01*
X300985Y437864D01*
X301277Y438114D01*
X301485Y438489D01*
X301568Y438864D01*
Y439323D01*
X301485Y439698D01*
X301277Y440031D01*
X301027Y440198D01*
X300735Y440281D01*
X300402Y440198D01*
X300152Y440031D01*
X299985Y439781D01*
X299902Y439448D01*
X299985Y439156D01*
X300193Y438864D01*
X300443Y438698D01*
X300735Y438656D01*
X301068Y438739D01*
X301318Y438948D01*
X301568Y439323D01*
G01X303127Y438073D02*
X303418Y437864D01*
X303752Y437781D01*
X304085Y437864D01*
X304377Y438114D01*
X304585Y438489D01*
X304668Y438864D01*
Y439323D01*
X304585Y439698D01*
X304377Y440031D01*
X304127Y440198D01*
X303835Y440281D01*
X303502Y440198D01*
X303252Y440031D01*
X303085Y439781D01*
X303002Y439448D01*
X303085Y439156D01*
X303293Y438864D01*
X303543Y438698D01*
X303835Y438656D01*
X304168Y438739D01*
X304418Y438948D01*
X304668Y439323D01*
G01X293725Y441662D02*
Y444162D01*
X294766D01*
X295100Y444037D01*
X295308Y443870D01*
X295391Y443537D01*
X295308Y443204D01*
X295058Y442995D01*
X294766Y442870D01*
X293725D01*
G01X294766D02*
X295391Y441662D01*
G01X297658D02*
Y444162D01*
X297158Y443662D01*
G01Y441662D02*
X298158D01*
G01X300050Y441954D02*
X300341Y441745D01*
X300675Y441662D01*
X301008Y441745D01*
X301300Y441995D01*
X301508Y442370D01*
X301591Y442745D01*
Y443204D01*
X301508Y443579D01*
X301300Y443912D01*
X301050Y444079D01*
X300758Y444162D01*
X300425Y444079D01*
X300175Y443912D01*
X300008Y443662D01*
X299925Y443329D01*
X300008Y443037D01*
X300216Y442745D01*
X300466Y442579D01*
X300758Y442537D01*
X301091Y442620D01*
X301341Y442829D01*
X301591Y443204D01*
G01X303858Y441662D02*
X304150Y441704D01*
X304483Y441829D01*
X304691Y442037D01*
X304775Y442329D01*
X304691Y442620D01*
X304441Y442870D01*
X304066Y442995D01*
X303650D01*
X303400Y443079D01*
X303191Y443287D01*
X303108Y443579D01*
X303233Y443870D01*
X303525Y444079D01*
X303858Y444162D01*
X304191Y444079D01*
X304483Y443870D01*
X304608Y443579D01*
X304525Y443287D01*
X304316Y443079D01*
X304066Y442995D01*
X303650D01*
X303275Y442870D01*
X303025Y442620D01*
X302941Y442329D01*
X303025Y442037D01*
X303233Y441829D01*
X303566Y441704D01*
X303858Y441662D01*
G01X293500Y462017D02*
X291000D01*
Y463058D01*
X291125Y463392D01*
X291292Y463600D01*
X291625Y463683D01*
X291958Y463600D01*
X292167Y463350D01*
X292292Y463058D01*
Y462017D01*
G01Y463058D02*
X293500Y463683D01*
G01Y465950D02*
X291000D01*
X291500Y465450D01*
G01X293500D02*
Y466450D01*
G01X293208Y468342D02*
X293417Y468633D01*
X293500Y468967D01*
X293417Y469300D01*
X293167Y469592D01*
X292792Y469800D01*
X292417Y469883D01*
X291958D01*
X291583Y469800D01*
X291250Y469592D01*
X291083Y469342D01*
X291000Y469050D01*
X291083Y468717D01*
X291250Y468467D01*
X291500Y468300D01*
X291833Y468217D01*
X292125Y468300D01*
X292417Y468508D01*
X292583Y468758D01*
X292625Y469050D01*
X292542Y469383D01*
X292333Y469633D01*
X291958Y469883D01*
G01X291000Y472150D02*
X291083Y471817D01*
X291292Y471567D01*
X291542Y471400D01*
X291875Y471275D01*
X292250Y471233D01*
X292625Y471275D01*
X292958Y471400D01*
X293208Y471567D01*
X293417Y471817D01*
X293500Y472150D01*
X293417Y472483D01*
X293208Y472733D01*
X292958Y472900D01*
X292625Y473025D01*
X292250Y473067D01*
X291875Y473025D01*
X291542Y472900D01*
X291292Y472733D01*
X291083Y472483D01*
X291000Y472150D01*
G01X293400Y475017D02*
X290900D01*
Y476058D01*
X291025Y476392D01*
X291192Y476600D01*
X291525Y476683D01*
X291858Y476600D01*
X292067Y476350D01*
X292192Y476058D01*
Y475017D01*
G01Y476058D02*
X293400Y476683D01*
G01Y478950D02*
X290900D01*
X291400Y478450D01*
G01X293400D02*
Y479450D01*
G01Y482050D02*
X293358Y482342D01*
X293233Y482675D01*
X293025Y482883D01*
X292733Y482967D01*
X292442Y482883D01*
X292192Y482633D01*
X292067Y482258D01*
Y481842D01*
X291983Y481592D01*
X291775Y481383D01*
X291483Y481300D01*
X291192Y481425D01*
X290983Y481717D01*
X290900Y482050D01*
X290983Y482383D01*
X291192Y482675D01*
X291483Y482800D01*
X291775Y482717D01*
X291983Y482508D01*
X292067Y482258D01*
Y481842D01*
X292192Y481467D01*
X292442Y481217D01*
X292733Y481133D01*
X293025Y481217D01*
X293233Y481425D01*
X293358Y481758D01*
X293400Y482050D01*
G01X293108Y484442D02*
X293317Y484733D01*
X293400Y485067D01*
X293317Y485400D01*
X293067Y485692D01*
X292692Y485900D01*
X292317Y485983D01*
X291858D01*
X291483Y485900D01*
X291150Y485692D01*
X290983Y485442D01*
X290900Y485150D01*
X290983Y484817D01*
X291150Y484567D01*
X291400Y484400D01*
X291733Y484317D01*
X292025Y484400D01*
X292317Y484608D01*
X292483Y484858D01*
X292525Y485150D01*
X292442Y485483D01*
X292233Y485733D01*
X291858Y485983D01*
G01X293617Y449400D02*
Y451900D01*
X294658D01*
X294992Y451775D01*
X295200Y451608D01*
X295283Y451275D01*
X295200Y450942D01*
X294950Y450733D01*
X294658Y450608D01*
X293617D01*
G01X294658D02*
X295283Y449400D01*
G01X297550D02*
Y451900D01*
X297050Y451400D01*
G01Y449400D02*
X298050D01*
G01X300650D02*
X300942Y449442D01*
X301275Y449567D01*
X301483Y449775D01*
X301567Y450067D01*
X301483Y450358D01*
X301233Y450608D01*
X300858Y450733D01*
X300442D01*
X300192Y450817D01*
X299983Y451025D01*
X299900Y451317D01*
X300025Y451608D01*
X300317Y451817D01*
X300650Y451900D01*
X300983Y451817D01*
X301275Y451608D01*
X301400Y451317D01*
X301317Y451025D01*
X301108Y450817D01*
X300858Y450733D01*
X300442D01*
X300067Y450608D01*
X299817Y450358D01*
X299733Y450067D01*
X299817Y449775D01*
X300025Y449567D01*
X300358Y449442D01*
X300650Y449400D01*
G01X302958Y451483D02*
X303208Y451733D01*
X303500Y451858D01*
X303833Y451900D01*
X304250Y451817D01*
X304542Y451608D01*
X304625Y451358D01*
X304583Y451108D01*
X304417Y450900D01*
X303583Y450483D01*
X303208Y450192D01*
X302958Y449775D01*
X302875Y449400D01*
X304625D01*
G01X293817Y445500D02*
Y448000D01*
X294858D01*
X295192Y447875D01*
X295400Y447708D01*
X295483Y447375D01*
X295400Y447042D01*
X295150Y446833D01*
X294858Y446708D01*
X293817D01*
G01X294858D02*
X295483Y445500D01*
G01X297750D02*
Y448000D01*
X297250Y447500D01*
G01Y445500D02*
X298250D01*
G01X300850D02*
X301142Y445542D01*
X301475Y445667D01*
X301683Y445875D01*
X301767Y446167D01*
X301683Y446458D01*
X301433Y446708D01*
X301058Y446833D01*
X300642D01*
X300392Y446917D01*
X300183Y447125D01*
X300100Y447417D01*
X300225Y447708D01*
X300517Y447917D01*
X300850Y448000D01*
X301183Y447917D01*
X301475Y447708D01*
X301600Y447417D01*
X301517Y447125D01*
X301308Y446917D01*
X301058Y446833D01*
X300642D01*
X300267Y446708D01*
X300017Y446458D01*
X299933Y446167D01*
X300017Y445875D01*
X300225Y445667D01*
X300558Y445542D01*
X300850Y445500D01*
G01X303950D02*
Y448000D01*
X303450Y447500D01*
G01Y445500D02*
X304450D01*
G01X297913Y489144D02*
X295413D01*
Y490185D01*
X295538Y490519D01*
X295705Y490727D01*
X296038Y490810D01*
X296371Y490727D01*
X296580Y490477D01*
X296705Y490185D01*
Y489144D01*
G01Y490185D02*
X297913Y490810D01*
G01X297413Y492160D02*
X297705Y492410D01*
X297871Y492744D01*
X297913Y493119D01*
X297871Y493452D01*
X297663Y493785D01*
X297413Y493994D01*
X297163Y494035D01*
X296871Y493952D01*
X296663Y493660D01*
X296580Y493369D01*
Y492994D01*
G01Y493369D02*
X296455Y493619D01*
X296246Y493827D01*
X295996Y493910D01*
X295746Y493827D01*
X295538Y493619D01*
X295413Y493244D01*
X295455Y492869D01*
X295621Y492494D01*
G01X297913Y496177D02*
X297871Y496469D01*
X297746Y496802D01*
X297538Y497010D01*
X297246Y497094D01*
X296955Y497010D01*
X296705Y496760D01*
X296580Y496385D01*
Y495969D01*
X296496Y495719D01*
X296288Y495510D01*
X295996Y495427D01*
X295705Y495552D01*
X295496Y495844D01*
X295413Y496177D01*
X295496Y496510D01*
X295705Y496802D01*
X295996Y496927D01*
X296288Y496844D01*
X296496Y496635D01*
X296580Y496385D01*
Y495969D01*
X296705Y495594D01*
X296955Y495344D01*
X297246Y495260D01*
X297538Y495344D01*
X297746Y495552D01*
X297871Y495885D01*
X297913Y496177D01*
G01Y499194D02*
X297371Y499277D01*
X296913Y499402D01*
X296496Y499569D01*
X296038Y499777D01*
X295413Y500110D01*
Y498444D01*
G01X301913Y489144D02*
X299413D01*
Y490185D01*
X299538Y490519D01*
X299705Y490727D01*
X300038Y490810D01*
X300371Y490727D01*
X300580Y490477D01*
X300705Y490185D01*
Y489144D01*
G01Y490185D02*
X301913Y490810D01*
G01X301413Y492160D02*
X301705Y492410D01*
X301871Y492744D01*
X301913Y493119D01*
X301871Y493452D01*
X301663Y493785D01*
X301413Y493994D01*
X301163Y494035D01*
X300871Y493952D01*
X300663Y493660D01*
X300580Y493369D01*
Y492994D01*
G01Y493369D02*
X300455Y493619D01*
X300246Y493827D01*
X299996Y493910D01*
X299746Y493827D01*
X299538Y493619D01*
X299413Y493244D01*
X299455Y492869D01*
X299621Y492494D01*
G01X301913Y496177D02*
X301871Y496469D01*
X301746Y496802D01*
X301538Y497010D01*
X301246Y497094D01*
X300955Y497010D01*
X300705Y496760D01*
X300580Y496385D01*
Y495969D01*
X300496Y495719D01*
X300288Y495510D01*
X299996Y495427D01*
X299705Y495552D01*
X299496Y495844D01*
X299413Y496177D01*
X299496Y496510D01*
X299705Y496802D01*
X299996Y496927D01*
X300288Y496844D01*
X300496Y496635D01*
X300580Y496385D01*
Y495969D01*
X300705Y495594D01*
X300955Y495344D01*
X301246Y495260D01*
X301538Y495344D01*
X301746Y495552D01*
X301871Y495885D01*
X301913Y496177D01*
G01X299830Y498485D02*
X299580Y498735D01*
X299455Y499027D01*
X299413Y499360D01*
X299496Y499777D01*
X299705Y500069D01*
X299955Y500152D01*
X300205Y500110D01*
X300413Y499944D01*
X300830Y499110D01*
X301121Y498735D01*
X301538Y498485D01*
X301913Y498402D01*
Y500152D01*
G01X292118Y488825D02*
X289618D01*
Y489866D01*
X289743Y490200D01*
X289910Y490408D01*
X290243Y490491D01*
X290576Y490408D01*
X290785Y490158D01*
X290910Y489866D01*
Y488825D01*
G01Y489866D02*
X292118Y490491D01*
G01X291618Y491841D02*
X291910Y492091D01*
X292076Y492425D01*
X292118Y492800D01*
X292076Y493133D01*
X291868Y493466D01*
X291618Y493675D01*
X291368Y493716D01*
X291076Y493633D01*
X290868Y493341D01*
X290785Y493050D01*
Y492675D01*
G01Y493050D02*
X290660Y493300D01*
X290451Y493508D01*
X290201Y493591D01*
X289951Y493508D01*
X289743Y493300D01*
X289618Y492925D01*
X289660Y492550D01*
X289826Y492175D01*
G01X291618Y494941D02*
X291910Y495191D01*
X292076Y495525D01*
X292118Y495900D01*
X292076Y496233D01*
X291868Y496566D01*
X291618Y496775D01*
X291368Y496816D01*
X291076Y496733D01*
X290868Y496441D01*
X290785Y496150D01*
Y495775D01*
G01Y496150D02*
X290660Y496400D01*
X290451Y496608D01*
X290201Y496691D01*
X289951Y496608D01*
X289743Y496400D01*
X289618Y496025D01*
X289660Y495650D01*
X289826Y495275D01*
G01X291743Y498041D02*
X291951Y498291D01*
X292076Y498583D01*
X292118Y498958D01*
X292035Y499333D01*
X291868Y499625D01*
X291576Y499833D01*
X291243Y499875D01*
X290910Y499791D01*
X290701Y499583D01*
X290535Y499291D01*
X290493Y499000D01*
X290535Y498708D01*
X290701Y498333D01*
X289618Y498458D01*
Y499583D01*
G01X338932Y456541D02*
Y459041D01*
X339973D01*
X340307Y458916D01*
X340515Y458749D01*
X340598Y458416D01*
X340515Y458083D01*
X340265Y457874D01*
X339973Y457749D01*
X338932D01*
G01X339973D02*
X340598Y456541D01*
G01X342782D02*
X342865Y457083D01*
X342990Y457541D01*
X343157Y457958D01*
X343365Y458416D01*
X343698Y459041D01*
X342032D01*
G01X345965Y456541D02*
Y459041D01*
X345465Y458541D01*
G01Y456541D02*
X346465D01*
G01X348982D02*
X349065Y457083D01*
X349190Y457541D01*
X349357Y457958D01*
X349565Y458416D01*
X349898Y459041D01*
X348232D01*
G01X345517Y476500D02*
Y479000D01*
X346558D01*
X346892Y478875D01*
X347100Y478708D01*
X347183Y478375D01*
X347100Y478042D01*
X346850Y477833D01*
X346558Y477708D01*
X345517D01*
G01X346558D02*
X347183Y476500D01*
G01X349367D02*
X349450Y477042D01*
X349575Y477500D01*
X349742Y477917D01*
X349950Y478375D01*
X350283Y479000D01*
X348617D01*
G01X351842Y476792D02*
X352133Y476583D01*
X352467Y476500D01*
X352800Y476583D01*
X353092Y476833D01*
X353300Y477208D01*
X353383Y477583D01*
Y478042D01*
X353300Y478417D01*
X353092Y478750D01*
X352842Y478917D01*
X352550Y479000D01*
X352217Y478917D01*
X351967Y478750D01*
X351800Y478500D01*
X351717Y478167D01*
X351800Y477875D01*
X352008Y477583D01*
X352258Y477417D01*
X352550Y477375D01*
X352883Y477458D01*
X353133Y477667D01*
X353383Y478042D01*
G01X354858Y477542D02*
X355150Y477833D01*
X355400Y478000D01*
X355733Y478083D01*
X356025Y478000D01*
X356233Y477833D01*
X356400Y477583D01*
X356442Y477292D01*
X356400Y477042D01*
X356233Y476792D01*
X355983Y476583D01*
X355692Y476500D01*
X355358Y476583D01*
X355067Y476833D01*
X354900Y477208D01*
X354858Y477625D01*
X354942Y478167D01*
X355067Y478458D01*
X355275Y478750D01*
X355567Y478958D01*
X355858Y479000D01*
X356150Y478917D01*
X356358Y478708D01*
G01X356000Y483517D02*
X353500D01*
Y484558D01*
X353625Y484892D01*
X353792Y485100D01*
X354125Y485183D01*
X354458Y485100D01*
X354667Y484850D01*
X354792Y484558D01*
Y483517D01*
G01Y484558D02*
X356000Y485183D01*
G01Y487367D02*
X355458Y487450D01*
X355000Y487575D01*
X354583Y487742D01*
X354125Y487950D01*
X353500Y488283D01*
Y486617D01*
G01X353917Y489758D02*
X353667Y490008D01*
X353542Y490300D01*
X353500Y490633D01*
X353583Y491050D01*
X353792Y491342D01*
X354042Y491425D01*
X354292Y491383D01*
X354500Y491217D01*
X354917Y490383D01*
X355208Y490008D01*
X355625Y489758D01*
X356000Y489675D01*
Y491425D01*
G01X355625Y492733D02*
X355833Y492983D01*
X355958Y493275D01*
X356000Y493650D01*
X355917Y494025D01*
X355750Y494317D01*
X355458Y494525D01*
X355125Y494567D01*
X354792Y494483D01*
X354583Y494275D01*
X354417Y493983D01*
X354375Y493692D01*
X354417Y493400D01*
X354583Y493025D01*
X353500Y493150D01*
Y494275D01*
G01X338633Y463000D02*
Y461208D01*
X338800Y460833D01*
X339133Y460583D01*
X339550Y460500D01*
X339967Y460583D01*
X340300Y460833D01*
X340467Y461208D01*
Y463000D01*
G01X342650Y460500D02*
Y463000D01*
X342150Y462500D01*
G01Y460500D02*
X343150D01*
G01X345750Y463000D02*
X345417Y462917D01*
X345167Y462708D01*
X345000Y462458D01*
X344875Y462125D01*
X344833Y461750D01*
X344875Y461375D01*
X345000Y461042D01*
X345167Y460792D01*
X345417Y460583D01*
X345750Y460500D01*
X346083Y460583D01*
X346333Y460792D01*
X346500Y461042D01*
X346625Y461375D01*
X346667Y461750D01*
X346625Y462125D01*
X346500Y462458D01*
X346333Y462708D01*
X346083Y462917D01*
X345750Y463000D01*
G01X348058Y462583D02*
X348308Y462833D01*
X348600Y462958D01*
X348933Y463000D01*
X349350Y462917D01*
X349642Y462708D01*
X349725Y462458D01*
X349683Y462208D01*
X349517Y462000D01*
X348683Y461583D01*
X348308Y461292D01*
X348058Y460875D01*
X347975Y460500D01*
X349725D01*
G01X346945Y423927D02*
X348737D01*
X349112Y424094D01*
X349362Y424427D01*
X349445Y424844D01*
X349362Y425261D01*
X349112Y425594D01*
X348737Y425761D01*
X346945D01*
G01X349070Y427027D02*
X349278Y427277D01*
X349403Y427569D01*
X349445Y427944D01*
X349362Y428319D01*
X349195Y428611D01*
X348903Y428819D01*
X348570Y428861D01*
X348237Y428777D01*
X348028Y428569D01*
X347862Y428277D01*
X347820Y427986D01*
X347862Y427694D01*
X348028Y427319D01*
X346945Y427444D01*
Y428569D01*
G01X352000Y438433D02*
X353792D01*
X354167Y438600D01*
X354417Y438933D01*
X354500Y439350D01*
X354417Y439767D01*
X354167Y440100D01*
X353792Y440267D01*
X352000D01*
G01X354500Y442450D02*
X352000D01*
X352500Y441950D01*
G01X354500D02*
Y442950D01*
G01X352000Y445550D02*
X352083Y445217D01*
X352292Y444967D01*
X352542Y444800D01*
X352875Y444675D01*
X353250Y444633D01*
X353625Y444675D01*
X353958Y444800D01*
X354208Y444967D01*
X354417Y445217D01*
X354500Y445550D01*
X354417Y445883D01*
X354208Y446133D01*
X353958Y446300D01*
X353625Y446425D01*
X353250Y446467D01*
X352875Y446425D01*
X352542Y446300D01*
X352292Y446133D01*
X352083Y445883D01*
X352000Y445550D01*
G01X354125Y447733D02*
X354333Y447983D01*
X354458Y448275D01*
X354500Y448650D01*
X354417Y449025D01*
X354250Y449317D01*
X353958Y449525D01*
X353625Y449567D01*
X353292Y449483D01*
X353083Y449275D01*
X352917Y448983D01*
X352875Y448692D01*
X352917Y448400D01*
X353083Y448025D01*
X352000Y448150D01*
Y449275D01*
G01X353033Y521800D02*
Y516053D01*
X343332D01*
Y512892D01*
X314000D01*
G01X386194Y585690D02*
Y581600D01*
X397600D01*
Y560800D01*
X392000D01*
Y543600D01*
X353033D01*
Y528600D01*
G01X302786Y504554D02*
X302536Y504679D01*
X302244Y504762D01*
X301911D01*
X301536Y504637D01*
X301244Y504429D01*
X301036Y504179D01*
X300869Y503762D01*
X300827Y503387D01*
X300911Y503012D01*
X301036Y502762D01*
X301286Y502512D01*
X301577Y502345D01*
X301869Y502262D01*
X302161D01*
X302452Y502345D01*
X302702Y502470D01*
X302911Y502637D01*
G01X304969Y502262D02*
X305261Y502304D01*
X305594Y502429D01*
X305802Y502637D01*
X305886Y502929D01*
X305802Y503220D01*
X305552Y503470D01*
X305177Y503595D01*
X304761D01*
X304511Y503679D01*
X304302Y503887D01*
X304219Y504179D01*
X304344Y504470D01*
X304636Y504679D01*
X304969Y504762D01*
X305302Y504679D01*
X305594Y504470D01*
X305719Y504179D01*
X305636Y503887D01*
X305427Y503679D01*
X305177Y503595D01*
X304761D01*
X304386Y503470D01*
X304136Y503220D01*
X304052Y502929D01*
X304136Y502637D01*
X304344Y502429D01*
X304677Y502304D01*
X304969Y502262D01*
G01X307277Y504345D02*
X307527Y504595D01*
X307819Y504720D01*
X308152Y504762D01*
X308569Y504679D01*
X308861Y504470D01*
X308944Y504220D01*
X308902Y503970D01*
X308736Y503762D01*
X307902Y503345D01*
X307527Y503054D01*
X307277Y502637D01*
X307194Y502262D01*
X308944D01*
G01X289061Y511766D02*
X288811Y511891D01*
X288519Y511974D01*
X288186D01*
X287811Y511849D01*
X287519Y511641D01*
X287311Y511391D01*
X287144Y510974D01*
X287102Y510599D01*
X287186Y510224D01*
X287311Y509974D01*
X287561Y509724D01*
X287852Y509557D01*
X288144Y509474D01*
X288436D01*
X288727Y509557D01*
X288977Y509682D01*
X289186Y509849D01*
G01X290536Y509766D02*
X290827Y509557D01*
X291161Y509474D01*
X291494Y509557D01*
X291786Y509807D01*
X291994Y510182D01*
X292077Y510557D01*
Y511016D01*
X291994Y511391D01*
X291786Y511724D01*
X291536Y511891D01*
X291244Y511974D01*
X290911Y511891D01*
X290661Y511724D01*
X290494Y511474D01*
X290411Y511141D01*
X290494Y510849D01*
X290702Y510557D01*
X290952Y510391D01*
X291244Y510349D01*
X291577Y510432D01*
X291827Y510641D01*
X292077Y511016D01*
G01X293552Y510516D02*
X293844Y510807D01*
X294094Y510974D01*
X294427Y511057D01*
X294719Y510974D01*
X294927Y510807D01*
X295094Y510557D01*
X295136Y510266D01*
X295094Y510016D01*
X294927Y509766D01*
X294677Y509557D01*
X294386Y509474D01*
X294052Y509557D01*
X293761Y509807D01*
X293594Y510182D01*
X293552Y510599D01*
X293636Y511141D01*
X293761Y511432D01*
X293969Y511724D01*
X294261Y511932D01*
X294552Y511974D01*
X294844Y511891D01*
X295052Y511682D01*
G01X287325Y566625D02*
X287200Y566375D01*
X287117Y566083D01*
Y565750D01*
X287242Y565375D01*
X287450Y565083D01*
X287700Y564875D01*
X288117Y564708D01*
X288492Y564666D01*
X288867Y564750D01*
X289117Y564875D01*
X289367Y565125D01*
X289534Y565416D01*
X289617Y565708D01*
Y566000D01*
X289534Y566291D01*
X289409Y566541D01*
X289242Y566750D01*
G01X289617Y568725D02*
X289075Y568808D01*
X288617Y568933D01*
X288200Y569100D01*
X287742Y569308D01*
X287117Y569641D01*
Y567975D01*
G01X289242Y570991D02*
X289450Y571241D01*
X289575Y571533D01*
X289617Y571908D01*
X289534Y572283D01*
X289367Y572575D01*
X289075Y572783D01*
X288742Y572825D01*
X288409Y572741D01*
X288200Y572533D01*
X288034Y572241D01*
X287992Y571950D01*
X288034Y571658D01*
X288200Y571283D01*
X287117Y571408D01*
Y572533D01*
G01X295000Y549300D02*
Y553300D01*
X287600D01*
G01X294755Y544706D02*
Y548706D01*
X287355D01*
G01X348819Y526075D02*
X344819D01*
Y518675D01*
G01X352400Y533900D02*
X348400D01*
Y526500D01*
G01X343100Y545800D02*
Y541800D01*
X350500D01*
G01X340497Y518661D02*
X344497D01*
Y526061D01*
G01X343226Y533909D02*
X339226D01*
Y526509D01*
G01X343100Y534200D02*
X347100D01*
Y541600D01*
G01X332233Y505549D02*
Y508049D01*
X333274D01*
X333608Y507924D01*
X333816Y507757D01*
X333899Y507424D01*
X333816Y507091D01*
X333566Y506882D01*
X333274Y506757D01*
X332233D01*
G01X333274D02*
X333899Y505549D01*
G01X336666D02*
Y508049D01*
X335124Y506257D01*
X337208D01*
G01X338474Y507632D02*
X338724Y507882D01*
X339016Y508007D01*
X339349Y508049D01*
X339766Y507966D01*
X340058Y507757D01*
X340141Y507507D01*
X340099Y507257D01*
X339933Y507049D01*
X339099Y506632D01*
X338724Y506341D01*
X338474Y505924D01*
X338391Y505549D01*
X340141D01*
G01X342366D02*
Y508049D01*
X341866Y507549D01*
G01Y505549D02*
X342866D01*
G01X353200Y509900D02*
Y513900D01*
X345800D01*
G01X327255Y500735D02*
Y503235D01*
X328296D01*
X328630Y503110D01*
X328838Y502943D01*
X328921Y502610D01*
X328838Y502277D01*
X328588Y502068D01*
X328296Y501943D01*
X327255D01*
G01X328296D02*
X328921Y500735D01*
G01X331688D02*
Y503235D01*
X330146Y501443D01*
X332230D01*
G01X333496Y502818D02*
X333746Y503068D01*
X334038Y503193D01*
X334371Y503235D01*
X334788Y503152D01*
X335080Y502943D01*
X335163Y502693D01*
X335121Y502443D01*
X334955Y502235D01*
X334121Y501818D01*
X333746Y501527D01*
X333496Y501110D01*
X333413Y500735D01*
X335163D01*
G01X337388Y503235D02*
X337055Y503152D01*
X336805Y502943D01*
X336638Y502693D01*
X336513Y502360D01*
X336471Y501985D01*
X336513Y501610D01*
X336638Y501277D01*
X336805Y501027D01*
X337055Y500818D01*
X337388Y500735D01*
X337721Y500818D01*
X337971Y501027D01*
X338138Y501277D01*
X338263Y501610D01*
X338305Y501985D01*
X338263Y502360D01*
X338138Y502693D01*
X337971Y502943D01*
X337721Y503152D01*
X337388Y503235D01*
G01X345861Y509831D02*
Y505831D01*
X353261D01*
G01X354517Y499000D02*
Y501500D01*
X355558D01*
X355892Y501375D01*
X356100Y501208D01*
X356183Y500875D01*
X356100Y500542D01*
X355850Y500333D01*
X355558Y500208D01*
X354517D01*
G01X355558D02*
X356183Y499000D01*
G01X358367D02*
X358450Y499542D01*
X358575Y500000D01*
X358742Y500417D01*
X358950Y500875D01*
X359283Y501500D01*
X357617D01*
G01X361550Y499000D02*
Y501500D01*
X361050Y501000D01*
G01Y499000D02*
X362050D01*
G01X363733Y499375D02*
X363983Y499167D01*
X364275Y499042D01*
X364650Y499000D01*
X365025Y499083D01*
X365317Y499250D01*
X365525Y499542D01*
X365567Y499875D01*
X365483Y500208D01*
X365275Y500417D01*
X364983Y500583D01*
X364692Y500625D01*
X364400Y500583D01*
X364025Y500417D01*
X364150Y501500D01*
X365275D01*
G01X353200Y498200D02*
Y502200D01*
X345800D01*
G01X340204Y557544D02*
Y561544D01*
X332804D01*
G01X340264Y553473D02*
Y557473D01*
X332864D01*
G01X340195Y561788D02*
Y565788D01*
X332795D01*
G01X336827Y522553D02*
X332827D01*
Y515153D01*
G01X297486Y506462D02*
Y508962D01*
X298527D01*
X298861Y508837D01*
X299069Y508670D01*
X299152Y508337D01*
X299069Y508004D01*
X298819Y507795D01*
X298527Y507670D01*
X297486D01*
G01X298527D02*
X299152Y506462D01*
G01X301336D02*
X301419Y507004D01*
X301544Y507462D01*
X301711Y507879D01*
X301919Y508337D01*
X302252Y508962D01*
X300586D01*
G01X303727Y507504D02*
X304019Y507795D01*
X304269Y507962D01*
X304602Y508045D01*
X304894Y507962D01*
X305102Y507795D01*
X305269Y507545D01*
X305311Y507254D01*
X305269Y507004D01*
X305102Y506754D01*
X304852Y506545D01*
X304561Y506462D01*
X304227Y506545D01*
X303936Y506795D01*
X303769Y507170D01*
X303727Y507587D01*
X303811Y508129D01*
X303936Y508420D01*
X304144Y508712D01*
X304436Y508920D01*
X304727Y508962D01*
X305019Y508879D01*
X305227Y508670D01*
G01X306827Y507504D02*
X307119Y507795D01*
X307369Y507962D01*
X307702Y508045D01*
X307994Y507962D01*
X308202Y507795D01*
X308369Y507545D01*
X308411Y507254D01*
X308369Y507004D01*
X308202Y506754D01*
X307952Y506545D01*
X307661Y506462D01*
X307327Y506545D01*
X307036Y506795D01*
X306869Y507170D01*
X306827Y507587D01*
X306911Y508129D01*
X307036Y508420D01*
X307244Y508712D01*
X307536Y508920D01*
X307827Y508962D01*
X308119Y508879D01*
X308327Y508670D01*
G01X322500Y531800D02*
X326500D01*
Y539200D01*
G01X318000Y531800D02*
X322000D01*
Y539200D01*
G01X329200Y524000D02*
Y528000D01*
X321800D01*
G01X289144Y508016D02*
X288894Y508141D01*
X288602Y508224D01*
X288269D01*
X287894Y508099D01*
X287602Y507891D01*
X287394Y507641D01*
X287227Y507224D01*
X287185Y506849D01*
X287269Y506474D01*
X287394Y506224D01*
X287644Y505974D01*
X287935Y505807D01*
X288227Y505724D01*
X288519D01*
X288810Y505807D01*
X289060Y505932D01*
X289269Y506099D01*
G01X290619Y506016D02*
X290910Y505807D01*
X291244Y505724D01*
X291577Y505807D01*
X291869Y506057D01*
X292077Y506432D01*
X292160Y506807D01*
Y507266D01*
X292077Y507641D01*
X291869Y507974D01*
X291619Y508141D01*
X291327Y508224D01*
X290994Y508141D01*
X290744Y507974D01*
X290577Y507724D01*
X290494Y507391D01*
X290577Y507099D01*
X290785Y506807D01*
X291035Y506641D01*
X291327Y506599D01*
X291660Y506682D01*
X291910Y506891D01*
X292160Y507266D01*
G01X293510Y506099D02*
X293760Y505891D01*
X294052Y505766D01*
X294427Y505724D01*
X294802Y505807D01*
X295094Y505974D01*
X295302Y506266D01*
X295344Y506599D01*
X295260Y506932D01*
X295052Y507141D01*
X294760Y507307D01*
X294469Y507349D01*
X294177Y507307D01*
X293802Y507141D01*
X293927Y508224D01*
X295052D01*
G01X284645Y543694D02*
Y555094D01*
G01X287478Y504515D02*
Y502015D01*
X289144D01*
G01X291911D02*
Y504515D01*
X290369Y502723D01*
X292453D01*
G01X301419Y525244D02*
Y525394D01*
X302669Y526644D01*
X303869Y525444D01*
Y525194D01*
G01X311419Y525244D02*
X294219D01*
Y535144D01*
X311419D01*
Y525244D01*
G01X339872Y587417D02*
X347440D01*
Y590950D01*
G01X307125Y594333D02*
Y584915D01*
X301264D01*
Y581561D01*
X300011D01*
G01X312925Y596784D02*
X312957Y596816D01*
X324098D01*
Y587417D01*
X337873D01*
G01X351448Y592570D02*
X354234D01*
G01X291819Y606271D02*
X291569Y606396D01*
X291277Y606479D01*
X290944D01*
X290569Y606354D01*
X290277Y606146D01*
X290069Y605896D01*
X289902Y605479D01*
X289860Y605104D01*
X289944Y604729D01*
X290069Y604479D01*
X290319Y604229D01*
X290610Y604062D01*
X290902Y603979D01*
X291194D01*
X291485Y604062D01*
X291735Y604187D01*
X291944Y604354D01*
G01X293210Y606062D02*
X293460Y606312D01*
X293752Y606437D01*
X294085Y606479D01*
X294502Y606396D01*
X294794Y606187D01*
X294877Y605937D01*
X294835Y605687D01*
X294669Y605479D01*
X293835Y605062D01*
X293460Y604771D01*
X293210Y604354D01*
X293127Y603979D01*
X294877D01*
G01X296185Y604479D02*
X296435Y604187D01*
X296769Y604021D01*
X297144Y603979D01*
X297477Y604021D01*
X297810Y604229D01*
X298019Y604479D01*
X298060Y604729D01*
X297977Y605021D01*
X297685Y605229D01*
X297394Y605312D01*
X297019D01*
G01X297394D02*
X297644Y605437D01*
X297852Y605646D01*
X297935Y605896D01*
X297852Y606146D01*
X297644Y606354D01*
X297269Y606479D01*
X296894Y606437D01*
X296519Y606271D01*
G01X300702Y603979D02*
Y606479D01*
X299160Y604687D01*
X301244D01*
G01X322383Y603340D02*
X322133Y603465D01*
X321841Y603548D01*
X321508D01*
X321133Y603423D01*
X320841Y603215D01*
X320633Y602965D01*
X320466Y602548D01*
X320424Y602173D01*
X320508Y601798D01*
X320633Y601548D01*
X320883Y601298D01*
X321174Y601131D01*
X321466Y601048D01*
X321758D01*
X322049Y601131D01*
X322299Y601256D01*
X322508Y601423D01*
G01X325066Y601048D02*
Y603548D01*
X323524Y601756D01*
X325608D01*
G01X328166Y601048D02*
Y603548D01*
X326624Y601756D01*
X328708D01*
G01X322017Y607217D02*
X321767Y607342D01*
X321475Y607425D01*
X321142D01*
X320767Y607300D01*
X320475Y607092D01*
X320267Y606842D01*
X320100Y606425D01*
X320058Y606050D01*
X320142Y605675D01*
X320267Y605425D01*
X320517Y605175D01*
X320808Y605008D01*
X321100Y604925D01*
X321392D01*
X321683Y605008D01*
X321933Y605133D01*
X322142Y605300D01*
G01X323408Y607008D02*
X323658Y607258D01*
X323950Y607383D01*
X324283Y607425D01*
X324700Y607342D01*
X324992Y607133D01*
X325075Y606883D01*
X325033Y606633D01*
X324867Y606425D01*
X324033Y606008D01*
X323658Y605717D01*
X323408Y605300D01*
X323325Y604925D01*
X325075D01*
G01X326383Y605425D02*
X326633Y605133D01*
X326967Y604967D01*
X327342Y604925D01*
X327675Y604967D01*
X328008Y605175D01*
X328217Y605425D01*
X328258Y605675D01*
X328175Y605967D01*
X327883Y606175D01*
X327592Y606258D01*
X327217D01*
G01X327592D02*
X327842Y606383D01*
X328050Y606592D01*
X328133Y606842D01*
X328050Y607092D01*
X327842Y607300D01*
X327467Y607425D01*
X327092Y607383D01*
X326717Y607217D01*
G01X329692Y605217D02*
X329983Y605008D01*
X330317Y604925D01*
X330650Y605008D01*
X330942Y605258D01*
X331150Y605633D01*
X331233Y606008D01*
Y606467D01*
X331150Y606842D01*
X330942Y607175D01*
X330692Y607342D01*
X330400Y607425D01*
X330067Y607342D01*
X329817Y607175D01*
X329650Y606925D01*
X329567Y606592D01*
X329650Y606300D01*
X329858Y606008D01*
X330108Y605842D01*
X330400Y605800D01*
X330733Y605883D01*
X330983Y606092D01*
X331233Y606467D01*
G01X337709Y623897D02*
X337584Y623647D01*
X337501Y623355D01*
Y623022D01*
X337626Y622647D01*
X337834Y622355D01*
X338084Y622147D01*
X338501Y621980D01*
X338876Y621938D01*
X339251Y622022D01*
X339501Y622147D01*
X339751Y622397D01*
X339918Y622688D01*
X340001Y622980D01*
Y623272D01*
X339918Y623563D01*
X339793Y623813D01*
X339626Y624022D01*
G01X337918Y625288D02*
X337668Y625538D01*
X337543Y625830D01*
X337501Y626163D01*
X337584Y626580D01*
X337793Y626872D01*
X338043Y626955D01*
X338293Y626913D01*
X338501Y626747D01*
X338918Y625913D01*
X339209Y625538D01*
X339626Y625288D01*
X340001Y625205D01*
Y626955D01*
G01X339501Y628263D02*
X339793Y628513D01*
X339959Y628847D01*
X340001Y629222D01*
X339959Y629555D01*
X339751Y629888D01*
X339501Y630097D01*
X339251Y630138D01*
X338959Y630055D01*
X338751Y629763D01*
X338668Y629472D01*
Y629097D01*
G01Y629472D02*
X338543Y629722D01*
X338334Y629930D01*
X338084Y630013D01*
X337834Y629930D01*
X337626Y629722D01*
X337501Y629347D01*
X337543Y628972D01*
X337709Y628597D01*
G01X340001Y632280D02*
X339959Y632572D01*
X339834Y632905D01*
X339626Y633113D01*
X339334Y633197D01*
X339043Y633113D01*
X338793Y632863D01*
X338668Y632488D01*
Y632072D01*
X338584Y631822D01*
X338376Y631613D01*
X338084Y631530D01*
X337793Y631655D01*
X337584Y631947D01*
X337501Y632280D01*
X337584Y632613D01*
X337793Y632905D01*
X338084Y633030D01*
X338376Y632947D01*
X338584Y632738D01*
X338668Y632488D01*
Y632072D01*
X338793Y631697D01*
X339043Y631447D01*
X339334Y631363D01*
X339626Y631447D01*
X339834Y631655D01*
X339959Y631988D01*
X340001Y632280D01*
G01X342058Y637482D02*
X341933Y637232D01*
X341850Y636940D01*
Y636607D01*
X341975Y636232D01*
X342183Y635940D01*
X342433Y635732D01*
X342850Y635565D01*
X343225Y635523D01*
X343600Y635607D01*
X343850Y635732D01*
X344100Y635982D01*
X344267Y636273D01*
X344350Y636565D01*
Y636857D01*
X344267Y637148D01*
X344142Y637398D01*
X343975Y637607D01*
G01X342267Y638873D02*
X342017Y639123D01*
X341892Y639415D01*
X341850Y639748D01*
X341933Y640165D01*
X342142Y640457D01*
X342392Y640540D01*
X342642Y640498D01*
X342850Y640332D01*
X343267Y639498D01*
X343558Y639123D01*
X343975Y638873D01*
X344350Y638790D01*
Y640540D01*
G01X343850Y641848D02*
X344142Y642098D01*
X344308Y642432D01*
X344350Y642807D01*
X344308Y643140D01*
X344100Y643473D01*
X343850Y643682D01*
X343600Y643723D01*
X343308Y643640D01*
X343100Y643348D01*
X343017Y643057D01*
Y642682D01*
G01Y643057D02*
X342892Y643307D01*
X342683Y643515D01*
X342433Y643598D01*
X342183Y643515D01*
X341975Y643307D01*
X341850Y642932D01*
X341892Y642557D01*
X342058Y642182D01*
G01X344350Y645782D02*
X343808Y645865D01*
X343350Y645990D01*
X342933Y646157D01*
X342475Y646365D01*
X341850Y646698D01*
Y645032D01*
G01X337811Y611167D02*
X337686Y610917D01*
X337603Y610625D01*
Y610292D01*
X337728Y609917D01*
X337936Y609625D01*
X338186Y609417D01*
X338603Y609250D01*
X338978Y609208D01*
X339353Y609292D01*
X339603Y609417D01*
X339853Y609667D01*
X340020Y609958D01*
X340103Y610250D01*
Y610542D01*
X340020Y610833D01*
X339895Y611083D01*
X339728Y611292D01*
G01X338020Y612558D02*
X337770Y612808D01*
X337645Y613100D01*
X337603Y613433D01*
X337686Y613850D01*
X337895Y614142D01*
X338145Y614225D01*
X338395Y614183D01*
X338603Y614017D01*
X339020Y613183D01*
X339311Y612808D01*
X339728Y612558D01*
X340103Y612475D01*
Y614225D01*
G01X339603Y615533D02*
X339895Y615783D01*
X340061Y616117D01*
X340103Y616492D01*
X340061Y616825D01*
X339853Y617158D01*
X339603Y617367D01*
X339353Y617408D01*
X339061Y617325D01*
X338853Y617033D01*
X338770Y616742D01*
Y616367D01*
G01Y616742D02*
X338645Y616992D01*
X338436Y617200D01*
X338186Y617283D01*
X337936Y617200D01*
X337728Y616992D01*
X337603Y616617D01*
X337645Y616242D01*
X337811Y615867D01*
G01X339061Y618758D02*
X338770Y619050D01*
X338603Y619300D01*
X338520Y619633D01*
X338603Y619925D01*
X338770Y620133D01*
X339020Y620300D01*
X339311Y620342D01*
X339561Y620300D01*
X339811Y620133D01*
X340020Y619883D01*
X340103Y619592D01*
X340020Y619258D01*
X339770Y618967D01*
X339395Y618800D01*
X338978Y618758D01*
X338436Y618842D01*
X338145Y618967D01*
X337853Y619175D01*
X337645Y619467D01*
X337603Y619758D01*
X337686Y620050D01*
X337895Y620258D01*
G01X337908Y637567D02*
X337783Y637317D01*
X337700Y637025D01*
Y636692D01*
X337825Y636317D01*
X338033Y636025D01*
X338283Y635817D01*
X338700Y635650D01*
X339075Y635608D01*
X339450Y635692D01*
X339700Y635817D01*
X339950Y636067D01*
X340117Y636358D01*
X340200Y636650D01*
Y636942D01*
X340117Y637233D01*
X339992Y637483D01*
X339825Y637692D01*
G01X338117Y638958D02*
X337867Y639208D01*
X337742Y639500D01*
X337700Y639833D01*
X337783Y640250D01*
X337992Y640542D01*
X338242Y640625D01*
X338492Y640583D01*
X338700Y640417D01*
X339117Y639583D01*
X339408Y639208D01*
X339825Y638958D01*
X340200Y638875D01*
Y640625D01*
G01X339700Y641933D02*
X339992Y642183D01*
X340158Y642517D01*
X340200Y642892D01*
X340158Y643225D01*
X339950Y643558D01*
X339700Y643767D01*
X339450Y643808D01*
X339158Y643725D01*
X338950Y643433D01*
X338867Y643142D01*
Y642767D01*
G01Y643142D02*
X338742Y643392D01*
X338533Y643600D01*
X338283Y643683D01*
X338033Y643600D01*
X337825Y643392D01*
X337700Y643017D01*
X337742Y642642D01*
X337908Y642267D01*
G01X339825Y645033D02*
X340033Y645283D01*
X340158Y645575D01*
X340200Y645950D01*
X340117Y646325D01*
X339950Y646617D01*
X339658Y646825D01*
X339325Y646867D01*
X338992Y646783D01*
X338783Y646575D01*
X338617Y646283D01*
X338575Y645992D01*
X338617Y645700D01*
X338783Y645325D01*
X337700Y645450D01*
Y646575D01*
G01X285517Y621300D02*
Y623800D01*
X286558D01*
X286892Y623675D01*
X287100Y623508D01*
X287183Y623175D01*
X287100Y622842D01*
X286850Y622633D01*
X286558Y622508D01*
X285517D01*
G01X286558D02*
X287183Y621300D01*
G01X288533Y621675D02*
X288783Y621467D01*
X289075Y621342D01*
X289450Y621300D01*
X289825Y621383D01*
X290117Y621550D01*
X290325Y621842D01*
X290367Y622175D01*
X290283Y622508D01*
X290075Y622717D01*
X289783Y622883D01*
X289492Y622925D01*
X289200Y622883D01*
X288825Y622717D01*
X288950Y623800D01*
X290075D01*
G01X291633Y621800D02*
X291883Y621508D01*
X292217Y621342D01*
X292592Y621300D01*
X292925Y621342D01*
X293258Y621550D01*
X293467Y621800D01*
X293508Y622050D01*
X293425Y622342D01*
X293133Y622550D01*
X292842Y622633D01*
X292467D01*
G01X292842D02*
X293092Y622758D01*
X293300Y622967D01*
X293383Y623217D01*
X293300Y623467D01*
X293092Y623675D01*
X292717Y623800D01*
X292342Y623758D01*
X291967Y623592D01*
G01X295650Y621300D02*
X295942Y621342D01*
X296275Y621467D01*
X296483Y621675D01*
X296567Y621967D01*
X296483Y622258D01*
X296233Y622508D01*
X295858Y622633D01*
X295442D01*
X295192Y622717D01*
X294983Y622925D01*
X294900Y623217D01*
X295025Y623508D01*
X295317Y623717D01*
X295650Y623800D01*
X295983Y623717D01*
X296275Y623508D01*
X296400Y623217D01*
X296317Y622925D01*
X296108Y622717D01*
X295858Y622633D01*
X295442D01*
X295067Y622508D01*
X294817Y622258D01*
X294733Y621967D01*
X294817Y621675D01*
X295025Y621467D01*
X295358Y621342D01*
X295650Y621300D01*
G01X301053Y622550D02*
Y618550D01*
X308453D01*
G01X290069Y607679D02*
Y610179D01*
X291110D01*
X291444Y610054D01*
X291652Y609887D01*
X291735Y609554D01*
X291652Y609221D01*
X291402Y609012D01*
X291110Y608887D01*
X290069D01*
G01X291110D02*
X291735Y607679D01*
G01X293085Y608054D02*
X293335Y607846D01*
X293627Y607721D01*
X294002Y607679D01*
X294377Y607762D01*
X294669Y607929D01*
X294877Y608221D01*
X294919Y608554D01*
X294835Y608887D01*
X294627Y609096D01*
X294335Y609262D01*
X294044Y609304D01*
X293752Y609262D01*
X293377Y609096D01*
X293502Y610179D01*
X294627D01*
G01X296185Y608179D02*
X296435Y607887D01*
X296769Y607721D01*
X297144Y607679D01*
X297477Y607721D01*
X297810Y607929D01*
X298019Y608179D01*
X298060Y608429D01*
X297977Y608721D01*
X297685Y608929D01*
X297394Y609012D01*
X297019D01*
G01X297394D02*
X297644Y609137D01*
X297852Y609346D01*
X297935Y609596D01*
X297852Y609846D01*
X297644Y610054D01*
X297269Y610179D01*
X296894Y610137D01*
X296519Y609971D01*
G01X300119Y607679D02*
X300202Y608221D01*
X300327Y608679D01*
X300494Y609096D01*
X300702Y609554D01*
X301035Y610179D01*
X299369D01*
G01X307400Y614384D02*
Y618384D01*
X300000D01*
G01X345680Y634264D02*
X349680D01*
Y641664D01*
G01X349700Y579000D02*
Y583000D01*
X342300D01*
G01X350480Y582164D02*
X354480D01*
Y589564D01*
G01X290017Y600000D02*
Y602500D01*
X291058D01*
X291392Y602375D01*
X291600Y602208D01*
X291683Y601875D01*
X291600Y601542D01*
X291350Y601333D01*
X291058Y601208D01*
X290017D01*
G01X291058D02*
X291683Y600000D01*
G01X293033Y600500D02*
X293283Y600208D01*
X293617Y600042D01*
X293992Y600000D01*
X294325Y600042D01*
X294658Y600250D01*
X294867Y600500D01*
X294908Y600750D01*
X294825Y601042D01*
X294533Y601250D01*
X294242Y601333D01*
X293867D01*
G01X294242D02*
X294492Y601458D01*
X294700Y601667D01*
X294783Y601917D01*
X294700Y602167D01*
X294492Y602375D01*
X294117Y602500D01*
X293742Y602458D01*
X293367Y602292D01*
G01X297050Y602500D02*
X296717Y602417D01*
X296467Y602208D01*
X296300Y601958D01*
X296175Y601625D01*
X296133Y601250D01*
X296175Y600875D01*
X296300Y600542D01*
X296467Y600292D01*
X296717Y600083D01*
X297050Y600000D01*
X297383Y600083D01*
X297633Y600292D01*
X297800Y600542D01*
X297925Y600875D01*
X297967Y601250D01*
X297925Y601625D01*
X297800Y601958D01*
X297633Y602208D01*
X297383Y602417D01*
X297050Y602500D01*
G01X300067Y600000D02*
X300150Y600542D01*
X300275Y601000D01*
X300442Y601417D01*
X300650Y601875D01*
X300983Y602500D01*
X299317D01*
G01X294315Y594831D02*
Y590831D01*
X301715D01*
G01X288000Y601017D02*
X285500D01*
Y602058D01*
X285625Y602392D01*
X285792Y602600D01*
X286125Y602683D01*
X286458Y602600D01*
X286667Y602350D01*
X286792Y602058D01*
Y601017D01*
G01Y602058D02*
X288000Y602683D01*
G01X287500Y604033D02*
X287792Y604283D01*
X287958Y604617D01*
X288000Y604992D01*
X287958Y605325D01*
X287750Y605658D01*
X287500Y605867D01*
X287250Y605908D01*
X286958Y605825D01*
X286750Y605533D01*
X286667Y605242D01*
Y604867D01*
G01Y605242D02*
X286542Y605492D01*
X286333Y605700D01*
X286083Y605783D01*
X285833Y605700D01*
X285625Y605492D01*
X285500Y605117D01*
X285542Y604742D01*
X285708Y604367D01*
G01X285500Y608050D02*
X285583Y607717D01*
X285792Y607467D01*
X286042Y607300D01*
X286375Y607175D01*
X286750Y607133D01*
X287125Y607175D01*
X287458Y607300D01*
X287708Y607467D01*
X287917Y607717D01*
X288000Y608050D01*
X287917Y608383D01*
X287708Y608633D01*
X287458Y608800D01*
X287125Y608925D01*
X286750Y608967D01*
X286375Y608925D01*
X286042Y608800D01*
X285792Y608633D01*
X285583Y608383D01*
X285500Y608050D01*
G01X287625Y610233D02*
X287833Y610483D01*
X287958Y610775D01*
X288000Y611150D01*
X287917Y611525D01*
X287750Y611817D01*
X287458Y612025D01*
X287125Y612067D01*
X286792Y611983D01*
X286583Y611775D01*
X286417Y611483D01*
X286375Y611192D01*
X286417Y610900D01*
X286583Y610525D01*
X285500Y610650D01*
Y611775D01*
G01X284703Y613011D02*
X288703D01*
Y620411D01*
G01X354680Y583664D02*
X358680D01*
Y591064D01*
G01X309244Y584263D02*
Y580263D01*
X316644D01*
G01X340155Y565922D02*
Y569922D01*
X332755D01*
G01X340199Y570721D02*
Y574721D01*
X332799D01*
G01X337953Y574849D02*
Y578849D01*
X330553D01*
G01X348500Y597867D02*
X346000D01*
Y598908D01*
X346125Y599242D01*
X346292Y599450D01*
X346625Y599533D01*
X346958Y599450D01*
X347167Y599200D01*
X347292Y598908D01*
Y597867D01*
G01Y598908D02*
X348500Y599533D01*
G01X348208Y601092D02*
X348417Y601383D01*
X348500Y601717D01*
X348417Y602050D01*
X348167Y602342D01*
X347792Y602550D01*
X347417Y602633D01*
X346958D01*
X346583Y602550D01*
X346250Y602342D01*
X346083Y602092D01*
X346000Y601800D01*
X346083Y601467D01*
X346250Y601217D01*
X346500Y601050D01*
X346833Y600967D01*
X347125Y601050D01*
X347417Y601258D01*
X347583Y601508D01*
X347625Y601800D01*
X347542Y602133D01*
X347333Y602383D01*
X346958Y602633D01*
G01X346417Y604108D02*
X346167Y604358D01*
X346042Y604650D01*
X346000Y604983D01*
X346083Y605400D01*
X346292Y605692D01*
X346542Y605775D01*
X346792Y605733D01*
X347000Y605567D01*
X347417Y604733D01*
X347708Y604358D01*
X348125Y604108D01*
X348500Y604025D01*
Y605775D01*
G01X342666Y596759D02*
Y592759D01*
X350066D01*
G01X338800Y587500D02*
Y583500D01*
X346200D01*
G01X307300Y596217D02*
X304800D01*
Y597258D01*
X304925Y597592D01*
X305092Y597800D01*
X305425Y597883D01*
X305758Y597800D01*
X305967Y597550D01*
X306092Y597258D01*
Y596217D01*
G01Y597258D02*
X307300Y597883D01*
G01Y600650D02*
X304800D01*
X306592Y599108D01*
Y601192D01*
G01X304800Y603250D02*
X304883Y602917D01*
X305092Y602667D01*
X305342Y602500D01*
X305675Y602375D01*
X306050Y602333D01*
X306425Y602375D01*
X306758Y602500D01*
X307008Y602667D01*
X307217Y602917D01*
X307300Y603250D01*
X307217Y603583D01*
X307008Y603833D01*
X306758Y604000D01*
X306425Y604125D01*
X306050Y604167D01*
X305675Y604125D01*
X305342Y604000D01*
X305092Y603833D01*
X304883Y603583D01*
X304800Y603250D01*
G01X307300Y606350D02*
X307258Y606642D01*
X307133Y606975D01*
X306925Y607183D01*
X306633Y607267D01*
X306342Y607183D01*
X306092Y606933D01*
X305967Y606558D01*
Y606142D01*
X305883Y605892D01*
X305675Y605683D01*
X305383Y605600D01*
X305092Y605725D01*
X304883Y606017D01*
X304800Y606350D01*
X304883Y606683D01*
X305092Y606975D01*
X305383Y607100D01*
X305675Y607017D01*
X305883Y606808D01*
X305967Y606558D01*
Y606142D01*
X306092Y605767D01*
X306342Y605517D01*
X306633Y605433D01*
X306925Y605517D01*
X307133Y605725D01*
X307258Y606058D01*
X307300Y606350D01*
G01X306617Y595281D02*
X302617D01*
Y587881D01*
G01X322212Y585791D02*
X308812D01*
G01X322212Y595791D02*
Y585791D01*
G01X308812Y595791D02*
X322212D01*
G01X308812Y585791D02*
Y595791D01*
G01X342500Y597783D02*
X344292D01*
X344667Y597950D01*
X344917Y598283D01*
X345000Y598700D01*
X344917Y599117D01*
X344667Y599450D01*
X344292Y599617D01*
X342500D01*
G01X345000Y601800D02*
X342500D01*
X343000Y601300D01*
G01X345000D02*
Y602300D01*
G01X342917Y604108D02*
X342667Y604358D01*
X342542Y604650D01*
X342500Y604983D01*
X342583Y605400D01*
X342792Y605692D01*
X343042Y605775D01*
X343292Y605733D01*
X343500Y605567D01*
X343917Y604733D01*
X344208Y604358D01*
X344625Y604108D01*
X345000Y604025D01*
Y605775D01*
G01X327800Y599000D02*
X341200D01*
G01X327800Y589000D02*
Y599000D01*
G01X341200Y589000D02*
X327800D01*
G01X341200Y599000D02*
Y589000D01*
G01X315000Y612917D02*
X312500D01*
Y613958D01*
X312625Y614292D01*
X312792Y614500D01*
X313125Y614583D01*
X313458Y614500D01*
X313667Y614250D01*
X313792Y613958D01*
Y612917D01*
G01Y613958D02*
X315000Y614583D01*
G01X314625Y615933D02*
X314833Y616183D01*
X314958Y616475D01*
X315000Y616850D01*
X314917Y617225D01*
X314750Y617517D01*
X314458Y617725D01*
X314125Y617767D01*
X313792Y617683D01*
X313583Y617475D01*
X313417Y617183D01*
X313375Y616892D01*
X313417Y616600D01*
X313583Y616225D01*
X312500Y616350D01*
Y617475D01*
G01X314500Y619033D02*
X314792Y619283D01*
X314958Y619617D01*
X315000Y619992D01*
X314958Y620325D01*
X314750Y620658D01*
X314500Y620867D01*
X314250Y620908D01*
X313958Y620825D01*
X313750Y620533D01*
X313667Y620242D01*
Y619867D01*
G01Y620242D02*
X313542Y620492D01*
X313333Y620700D01*
X313083Y620783D01*
X312833Y620700D01*
X312625Y620492D01*
X312500Y620117D01*
X312542Y619742D01*
X312708Y619367D01*
G01X313958Y622258D02*
X313667Y622550D01*
X313500Y622800D01*
X313417Y623133D01*
X313500Y623425D01*
X313667Y623633D01*
X313917Y623800D01*
X314208Y623842D01*
X314458Y623800D01*
X314708Y623633D01*
X314917Y623383D01*
X315000Y623092D01*
X314917Y622758D01*
X314667Y622467D01*
X314292Y622300D01*
X313875Y622258D01*
X313333Y622342D01*
X313042Y622467D01*
X312750Y622675D01*
X312542Y622967D01*
X312500Y623258D01*
X312583Y623550D01*
X312792Y623758D01*
G01X308436Y598596D02*
Y603796D01*
G01X315436Y598596D02*
Y606396D01*
G01X308436Y598596D02*
X315436D01*
G01X308436Y611996D02*
Y603296D01*
G01X315436Y611996D02*
X308436D01*
G01X315436Y605596D02*
Y611996D01*
G01X351339Y578279D02*
X372339D01*
Y546629D01*
X361339D01*
Y578279D01*
G01X348973Y632571D02*
Y630779D01*
X349140Y630404D01*
X349473Y630154D01*
X349890Y630071D01*
X350307Y630154D01*
X350640Y630404D01*
X350807Y630779D01*
Y632571D01*
G01X352282Y630363D02*
X352573Y630154D01*
X352907Y630071D01*
X353240Y630154D01*
X353532Y630404D01*
X353740Y630779D01*
X353823Y631154D01*
Y631613D01*
X353740Y631988D01*
X353532Y632321D01*
X353282Y632488D01*
X352990Y632571D01*
X352657Y632488D01*
X352407Y632321D01*
X352240Y632071D01*
X352157Y631738D01*
X352240Y631446D01*
X352448Y631154D01*
X352698Y630988D01*
X352990Y630946D01*
X353323Y631029D01*
X353573Y631238D01*
X353823Y631613D01*
G01X355382Y630363D02*
X355673Y630154D01*
X356007Y630071D01*
X356340Y630154D01*
X356632Y630404D01*
X356840Y630779D01*
X356923Y631154D01*
Y631613D01*
X356840Y631988D01*
X356632Y632321D01*
X356382Y632488D01*
X356090Y632571D01*
X355757Y632488D01*
X355507Y632321D01*
X355340Y632071D01*
X355257Y631738D01*
X355340Y631446D01*
X355548Y631154D01*
X355798Y630988D01*
X356090Y630946D01*
X356423Y631029D01*
X356673Y631238D01*
X356923Y631613D01*
G01X350264Y612520D02*
X348264D01*
G01X354364Y596820D02*
X349364D01*
Y601820D01*
G01X292450Y629750D02*
Y624750D01*
X297450D01*
G01X311418Y626157D02*
Y623157D01*
G01X293857Y633482D02*
X291857D01*
G01X308946Y686853D02*
X311758D01*
Y692951D01*
X309909D01*
Y709982D01*
X325297D01*
Y700377D01*
X345394D01*
Y699871D01*
G01X335181Y700763D02*
X336681Y702263D01*
X333681D01*
X335181Y700763D01*
G01X286369Y666851D02*
Y658892D01*
G01X287840Y655477D02*
X291500D01*
G01X297883D02*
X323418D01*
Y654498D01*
X323419Y654497D01*
X350978D01*
X350979Y654498D01*
Y671934D01*
X350978Y671935D01*
X348238D01*
Y696530D01*
G01X335181Y700763D02*
Y711688D01*
X347100D01*
Y726792D01*
G01X297600Y666902D02*
X300051D01*
Y671528D01*
X301315D01*
Y685889D01*
X304854D01*
G01X299175Y689068D02*
X298925Y689193D01*
X298633Y689276D01*
X298300D01*
X297925Y689151D01*
X297633Y688943D01*
X297425Y688693D01*
X297258Y688276D01*
X297216Y687901D01*
X297300Y687526D01*
X297425Y687276D01*
X297675Y687026D01*
X297966Y686859D01*
X298258Y686776D01*
X298550D01*
X298841Y686859D01*
X299091Y686984D01*
X299300Y687151D01*
G01X301358Y686776D02*
Y689276D01*
X300858Y688776D01*
G01Y686776D02*
X301858D01*
G01X303750Y687068D02*
X304041Y686859D01*
X304375Y686776D01*
X304708Y686859D01*
X305000Y687109D01*
X305208Y687484D01*
X305291Y687859D01*
Y688318D01*
X305208Y688693D01*
X305000Y689026D01*
X304750Y689193D01*
X304458Y689276D01*
X304125Y689193D01*
X303875Y689026D01*
X303708Y688776D01*
X303625Y688443D01*
X303708Y688151D01*
X303916Y687859D01*
X304166Y687693D01*
X304458Y687651D01*
X304791Y687734D01*
X305041Y687943D01*
X305291Y688318D01*
G01X307558Y689276D02*
X307225Y689193D01*
X306975Y688984D01*
X306808Y688734D01*
X306683Y688401D01*
X306641Y688026D01*
X306683Y687651D01*
X306808Y687318D01*
X306975Y687068D01*
X307225Y686859D01*
X307558Y686776D01*
X307891Y686859D01*
X308141Y687068D01*
X308308Y687318D01*
X308433Y687651D01*
X308475Y688026D01*
X308433Y688401D01*
X308308Y688734D01*
X308141Y688984D01*
X307891Y689193D01*
X307558Y689276D01*
G01X285208Y683817D02*
X285083Y683567D01*
X285000Y683275D01*
Y682942D01*
X285125Y682567D01*
X285333Y682275D01*
X285583Y682067D01*
X286000Y681900D01*
X286375Y681858D01*
X286750Y681942D01*
X287000Y682067D01*
X287250Y682317D01*
X287417Y682608D01*
X287500Y682900D01*
Y683192D01*
X287417Y683483D01*
X287292Y683733D01*
X287125Y683942D01*
G01X287500Y685917D02*
X286958Y686000D01*
X286500Y686125D01*
X286083Y686292D01*
X285625Y686500D01*
X285000Y686833D01*
Y685167D01*
G01X287500Y689100D02*
X287458Y689392D01*
X287333Y689725D01*
X287125Y689933D01*
X286833Y690017D01*
X286542Y689933D01*
X286292Y689683D01*
X286167Y689308D01*
Y688892D01*
X286083Y688642D01*
X285875Y688433D01*
X285583Y688350D01*
X285292Y688475D01*
X285083Y688767D01*
X285000Y689100D01*
X285083Y689433D01*
X285292Y689725D01*
X285583Y689850D01*
X285875Y689767D01*
X286083Y689558D01*
X286167Y689308D01*
Y688892D01*
X286292Y688517D01*
X286542Y688267D01*
X286833Y688183D01*
X287125Y688267D01*
X287333Y688475D01*
X287458Y688808D01*
X287500Y689100D01*
G01X287767Y670292D02*
X287517Y670417D01*
X287225Y670500D01*
X286892D01*
X286517Y670375D01*
X286225Y670167D01*
X286017Y669917D01*
X285850Y669500D01*
X285808Y669125D01*
X285892Y668750D01*
X286017Y668500D01*
X286267Y668250D01*
X286558Y668083D01*
X286850Y668000D01*
X287142D01*
X287433Y668083D01*
X287683Y668208D01*
X287892Y668375D01*
G01X289158Y670083D02*
X289408Y670333D01*
X289700Y670458D01*
X290033Y670500D01*
X290450Y670417D01*
X290742Y670208D01*
X290825Y669958D01*
X290783Y669708D01*
X290617Y669500D01*
X289783Y669083D01*
X289408Y668792D01*
X289158Y668375D01*
X289075Y668000D01*
X290825D01*
G01X293550D02*
Y670500D01*
X292008Y668708D01*
X294092D01*
G01X295233Y668375D02*
X295483Y668167D01*
X295775Y668042D01*
X296150Y668000D01*
X296525Y668083D01*
X296817Y668250D01*
X297025Y668542D01*
X297067Y668875D01*
X296983Y669208D01*
X296775Y669417D01*
X296483Y669583D01*
X296192Y669625D01*
X295900Y669583D01*
X295525Y669417D01*
X295650Y670500D01*
X296775D01*
G01X328708Y644267D02*
X328583Y644017D01*
X328500Y643725D01*
Y643392D01*
X328625Y643017D01*
X328833Y642725D01*
X329083Y642517D01*
X329500Y642350D01*
X329875Y642308D01*
X330250Y642392D01*
X330500Y642517D01*
X330750Y642767D01*
X330917Y643058D01*
X331000Y643350D01*
Y643642D01*
X330917Y643933D01*
X330792Y644183D01*
X330625Y644392D01*
G01X328917Y645658D02*
X328667Y645908D01*
X328542Y646200D01*
X328500Y646533D01*
X328583Y646950D01*
X328792Y647242D01*
X329042Y647325D01*
X329292Y647283D01*
X329500Y647117D01*
X329917Y646283D01*
X330208Y645908D01*
X330625Y645658D01*
X331000Y645575D01*
Y647325D01*
G01Y650050D02*
X328500D01*
X330292Y648508D01*
Y650592D01*
G01X328917Y651858D02*
X328667Y652108D01*
X328542Y652400D01*
X328500Y652733D01*
X328583Y653150D01*
X328792Y653442D01*
X329042Y653525D01*
X329292Y653483D01*
X329500Y653317D01*
X329917Y652483D01*
X330208Y652108D01*
X330625Y651858D01*
X331000Y651775D01*
Y653525D01*
G01X326875Y676443D02*
Y680443D01*
X319475D01*
G01X297517Y691000D02*
Y693500D01*
X298558D01*
X298892Y693375D01*
X299100Y693208D01*
X299183Y692875D01*
X299100Y692542D01*
X298850Y692333D01*
X298558Y692208D01*
X297517D01*
G01X298558D02*
X299183Y691000D01*
G01X300533Y691375D02*
X300783Y691167D01*
X301075Y691042D01*
X301450Y691000D01*
X301825Y691083D01*
X302117Y691250D01*
X302325Y691542D01*
X302367Y691875D01*
X302283Y692208D01*
X302075Y692417D01*
X301783Y692583D01*
X301492Y692625D01*
X301200Y692583D01*
X300825Y692417D01*
X300950Y693500D01*
X302075D01*
G01X304550D02*
X304217Y693417D01*
X303967Y693208D01*
X303800Y692958D01*
X303675Y692625D01*
X303633Y692250D01*
X303675Y691875D01*
X303800Y691542D01*
X303967Y691292D01*
X304217Y691083D01*
X304550Y691000D01*
X304883Y691083D01*
X305133Y691292D01*
X305300Y691542D01*
X305425Y691875D01*
X305467Y692250D01*
X305425Y692625D01*
X305300Y692958D01*
X305133Y693208D01*
X304883Y693417D01*
X304550Y693500D01*
G01X306858Y692042D02*
X307150Y692333D01*
X307400Y692500D01*
X307733Y692583D01*
X308025Y692500D01*
X308233Y692333D01*
X308400Y692083D01*
X308442Y691792D01*
X308400Y691542D01*
X308233Y691292D01*
X307983Y691083D01*
X307692Y691000D01*
X307358Y691083D01*
X307067Y691333D01*
X306900Y691708D01*
X306858Y692125D01*
X306942Y692667D01*
X307067Y692958D01*
X307275Y693250D01*
X307567Y693458D01*
X307858Y693500D01*
X308150Y693417D01*
X308358Y693208D01*
G01X289382Y693947D02*
Y689947D01*
X296782D01*
G01X289017Y678500D02*
Y681000D01*
X290058D01*
X290392Y680875D01*
X290600Y680708D01*
X290683Y680375D01*
X290600Y680042D01*
X290350Y679833D01*
X290058Y679708D01*
X289017D01*
G01X290058D02*
X290683Y678500D01*
G01X292033Y678875D02*
X292283Y678667D01*
X292575Y678542D01*
X292950Y678500D01*
X293325Y678583D01*
X293617Y678750D01*
X293825Y679042D01*
X293867Y679375D01*
X293783Y679708D01*
X293575Y679917D01*
X293283Y680083D01*
X292992Y680125D01*
X292700Y680083D01*
X292325Y679917D01*
X292450Y681000D01*
X293575D01*
G01X296050D02*
X295717Y680917D01*
X295467Y680708D01*
X295300Y680458D01*
X295175Y680125D01*
X295133Y679750D01*
X295175Y679375D01*
X295300Y679042D01*
X295467Y678792D01*
X295717Y678583D01*
X296050Y678500D01*
X296383Y678583D01*
X296633Y678792D01*
X296800Y679042D01*
X296925Y679375D01*
X296967Y679750D01*
X296925Y680125D01*
X296800Y680458D01*
X296633Y680708D01*
X296383Y680917D01*
X296050Y681000D01*
G01X298233Y678875D02*
X298483Y678667D01*
X298775Y678542D01*
X299150Y678500D01*
X299525Y678583D01*
X299817Y678750D01*
X300025Y679042D01*
X300067Y679375D01*
X299983Y679708D01*
X299775Y679917D01*
X299483Y680083D01*
X299192Y680125D01*
X298900Y680083D01*
X298525Y679917D01*
X298650Y681000D01*
X299775D01*
G01X296718Y682153D02*
Y686153D01*
X289318D01*
G01X350212Y645566D02*
X347712D01*
Y646607D01*
X347837Y646941D01*
X348004Y647149D01*
X348337Y647232D01*
X348670Y647149D01*
X348879Y646899D01*
X349004Y646607D01*
Y645566D01*
G01Y646607D02*
X350212Y647232D01*
G01X348129Y648707D02*
X347879Y648957D01*
X347754Y649249D01*
X347712Y649582D01*
X347795Y649999D01*
X348004Y650291D01*
X348254Y650374D01*
X348504Y650332D01*
X348712Y650166D01*
X349129Y649332D01*
X349420Y648957D01*
X349837Y648707D01*
X350212Y648624D01*
Y650374D01*
G01Y652599D02*
X350170Y652891D01*
X350045Y653224D01*
X349837Y653432D01*
X349545Y653516D01*
X349254Y653432D01*
X349004Y653182D01*
X348879Y652807D01*
Y652391D01*
X348795Y652141D01*
X348587Y651932D01*
X348295Y651849D01*
X348004Y651974D01*
X347795Y652266D01*
X347712Y652599D01*
X347795Y652932D01*
X348004Y653224D01*
X348295Y653349D01*
X348587Y653266D01*
X348795Y653057D01*
X348879Y652807D01*
Y652391D01*
X349004Y652016D01*
X349254Y651766D01*
X349545Y651682D01*
X349837Y651766D01*
X350045Y651974D01*
X350170Y652307D01*
X350212Y652599D01*
G01X286017Y671500D02*
Y674000D01*
X287058D01*
X287392Y673875D01*
X287600Y673708D01*
X287683Y673375D01*
X287600Y673042D01*
X287350Y672833D01*
X287058Y672708D01*
X286017D01*
G01X287058D02*
X287683Y671500D01*
G01X289033Y671875D02*
X289283Y671667D01*
X289575Y671542D01*
X289950Y671500D01*
X290325Y671583D01*
X290617Y671750D01*
X290825Y672042D01*
X290867Y672375D01*
X290783Y672708D01*
X290575Y672917D01*
X290283Y673083D01*
X289992Y673125D01*
X289700Y673083D01*
X289325Y672917D01*
X289450Y674000D01*
X290575D01*
G01X293550Y671500D02*
Y674000D01*
X292008Y672208D01*
X294092D01*
G01X296150Y671500D02*
Y674000D01*
X295650Y673500D01*
G01Y671500D02*
X296650D01*
G01X301000Y663500D02*
X297000D01*
Y656100D01*
G01X286017Y675000D02*
Y677500D01*
X287058D01*
X287392Y677375D01*
X287600Y677208D01*
X287683Y676875D01*
X287600Y676542D01*
X287350Y676333D01*
X287058Y676208D01*
X286017D01*
G01X287058D02*
X287683Y675000D01*
G01X289033Y675375D02*
X289283Y675167D01*
X289575Y675042D01*
X289950Y675000D01*
X290325Y675083D01*
X290617Y675250D01*
X290825Y675542D01*
X290867Y675875D01*
X290783Y676208D01*
X290575Y676417D01*
X290283Y676583D01*
X289992Y676625D01*
X289700Y676583D01*
X289325Y676417D01*
X289450Y677500D01*
X290575D01*
G01X293550Y675000D02*
Y677500D01*
X292008Y675708D01*
X294092D01*
G01X295358Y677083D02*
X295608Y677333D01*
X295900Y677458D01*
X296233Y677500D01*
X296650Y677417D01*
X296942Y677208D01*
X297025Y676958D01*
X296983Y676708D01*
X296817Y676500D01*
X295983Y676083D01*
X295608Y675792D01*
X295358Y675375D01*
X295275Y675000D01*
X297025D01*
G01X291612Y666929D02*
X287612D01*
Y659529D01*
G01X340200Y674000D02*
Y670000D01*
X347600D01*
G01X340123Y675472D02*
Y679472D01*
X332723D01*
G01X325483Y672407D02*
Y676407D01*
X318083D01*
G01X322100Y669100D02*
Y655100D01*
G01X335100Y669100D02*
X322100D01*
G01X335100Y655100D02*
Y669100D01*
G01X322100Y655100D02*
X335100D01*
G01X350100Y669000D02*
X336100D01*
G01X350100Y656000D02*
Y669000D01*
G01X336100Y656000D02*
X350100D01*
G01X336100Y669000D02*
Y656000D01*
G01X351920Y647316D02*
X351795Y647066D01*
X351712Y646774D01*
Y646441D01*
X351837Y646066D01*
X352045Y645774D01*
X352295Y645566D01*
X352712Y645399D01*
X353087Y645357D01*
X353462Y645441D01*
X353712Y645566D01*
X353962Y645816D01*
X354129Y646107D01*
X354212Y646399D01*
Y646691D01*
X354129Y646982D01*
X354004Y647232D01*
X353837Y647441D01*
G01X354212Y649499D02*
X351712D01*
X352212Y648999D01*
G01X354212D02*
Y649999D01*
G01X353920Y651891D02*
X354129Y652182D01*
X354212Y652516D01*
X354129Y652849D01*
X353879Y653141D01*
X353504Y653349D01*
X353129Y653432D01*
X352670D01*
X352295Y653349D01*
X351962Y653141D01*
X351795Y652891D01*
X351712Y652599D01*
X351795Y652266D01*
X351962Y652016D01*
X352212Y651849D01*
X352545Y651766D01*
X352837Y651849D01*
X353129Y652057D01*
X353295Y652307D01*
X353337Y652599D01*
X353254Y652932D01*
X353045Y653182D01*
X352670Y653432D01*
G01X305600Y672300D02*
Y677500D01*
G01X312600Y672300D02*
Y680100D01*
G01X305600Y672300D02*
X312600D01*
G01X305600Y685700D02*
Y677000D01*
G01X312600Y685700D02*
X305600D01*
G01X312600Y679300D02*
Y685700D01*
G01X348000Y702433D02*
X349792D01*
X350167Y702600D01*
X350417Y702933D01*
X350500Y703350D01*
X350417Y703767D01*
X350167Y704100D01*
X349792Y704267D01*
X348000D01*
G01X350500Y706450D02*
X348000D01*
X348500Y705950D01*
G01X350500D02*
Y706950D01*
G01X348000Y709550D02*
X348083Y709217D01*
X348292Y708967D01*
X348542Y708800D01*
X348875Y708675D01*
X349250Y708633D01*
X349625Y708675D01*
X349958Y708800D01*
X350208Y708967D01*
X350417Y709217D01*
X350500Y709550D01*
X350417Y709883D01*
X350208Y710133D01*
X349958Y710300D01*
X349625Y710425D01*
X349250Y710467D01*
X348875Y710425D01*
X348542Y710300D01*
X348292Y710133D01*
X348083Y709883D01*
X348000Y709550D01*
G01X349458Y711858D02*
X349167Y712150D01*
X349000Y712400D01*
X348917Y712733D01*
X349000Y713025D01*
X349167Y713233D01*
X349417Y713400D01*
X349708Y713442D01*
X349958Y713400D01*
X350208Y713233D01*
X350417Y712983D01*
X350500Y712692D01*
X350417Y712358D01*
X350167Y712067D01*
X349792Y711900D01*
X349375Y711858D01*
X348833Y711942D01*
X348542Y712067D01*
X348250Y712275D01*
X348042Y712567D01*
X348000Y712858D01*
X348083Y713150D01*
X348292Y713358D01*
G01X353300Y707700D02*
Y699700D01*
G01Y713700D02*
Y707700D01*
G01Y713700D02*
Y699700D01*
G01D02*
X371300D01*
G01X300752Y697627D02*
Y694627D01*
G01X327000Y642517D02*
X324500D01*
Y643517D01*
X324625Y643850D01*
X324917Y644100D01*
X325250Y644183D01*
X325583Y644100D01*
X325833Y643892D01*
X325958Y643517D01*
Y642517D01*
G01X324500Y645533D02*
X326292D01*
X326667Y645700D01*
X326917Y646033D01*
X327000Y646450D01*
X326917Y646867D01*
X326667Y647200D01*
X326292Y647367D01*
X324500D01*
G01X327000Y649550D02*
X324500D01*
X325000Y649050D01*
G01X327000D02*
Y650050D01*
G01Y652650D02*
X324500D01*
X325000Y652150D01*
G01X327000D02*
Y653150D01*
G01X297450Y652450D02*
X292450D01*
Y647450D01*
G01X320150D02*
Y652450D01*
X315150D01*
G01X301182Y651043D02*
Y654043D01*
G01X318743Y643718D02*
X320743D01*
G01X312690Y726382D02*
Y718103D01*
G01X343309Y734945D02*
Y753209D01*
X313364D01*
G03X313354Y753199I0J-10D01*
G01Y739874D01*
X311521D01*
Y729000D01*
G01X327067Y711688D02*
X335181D01*
G01X327933Y737914D02*
X327683Y738039D01*
X327391Y738122D01*
X327058D01*
X326683Y737997D01*
X326391Y737789D01*
X326183Y737539D01*
X326016Y737122D01*
X325974Y736747D01*
X326058Y736372D01*
X326183Y736122D01*
X326433Y735872D01*
X326724Y735705D01*
X327016Y735622D01*
X327308D01*
X327599Y735705D01*
X327849Y735830D01*
X328058Y735997D01*
G01X330116Y735622D02*
Y738122D01*
X329616Y737622D01*
G01Y735622D02*
X330616D01*
G01X332424Y737705D02*
X332674Y737955D01*
X332966Y738080D01*
X333299Y738122D01*
X333716Y738039D01*
X334008Y737830D01*
X334091Y737580D01*
X334049Y737330D01*
X333883Y737122D01*
X333049Y736705D01*
X332674Y736414D01*
X332424Y735997D01*
X332341Y735622D01*
X334091D01*
G01X335399Y735997D02*
X335649Y735789D01*
X335941Y735664D01*
X336316Y735622D01*
X336691Y735705D01*
X336983Y735872D01*
X337191Y736164D01*
X337233Y736497D01*
X337149Y736830D01*
X336941Y737039D01*
X336649Y737205D01*
X336358Y737247D01*
X336066Y737205D01*
X335691Y737039D01*
X335816Y738122D01*
X336941D01*
G01X309308Y744567D02*
X309183Y744317D01*
X309100Y744025D01*
Y743692D01*
X309225Y743317D01*
X309433Y743025D01*
X309683Y742817D01*
X310100Y742650D01*
X310475Y742608D01*
X310850Y742692D01*
X311100Y742817D01*
X311350Y743067D01*
X311517Y743358D01*
X311600Y743650D01*
Y743942D01*
X311517Y744233D01*
X311392Y744483D01*
X311225Y744692D01*
G01X311600Y746750D02*
X309100D01*
X309600Y746250D01*
G01X311600D02*
Y747250D01*
G01X311308Y749142D02*
X311517Y749433D01*
X311600Y749767D01*
X311517Y750100D01*
X311267Y750392D01*
X310892Y750600D01*
X310517Y750683D01*
X310058D01*
X309683Y750600D01*
X309350Y750392D01*
X309183Y750142D01*
X309100Y749850D01*
X309183Y749517D01*
X309350Y749267D01*
X309600Y749100D01*
X309933Y749017D01*
X310225Y749100D01*
X310517Y749308D01*
X310683Y749558D01*
X310725Y749850D01*
X310642Y750183D01*
X310433Y750433D01*
X310058Y750683D01*
G01X311600Y752950D02*
X311558Y753242D01*
X311433Y753575D01*
X311225Y753783D01*
X310933Y753867D01*
X310642Y753783D01*
X310392Y753533D01*
X310267Y753158D01*
Y752742D01*
X310183Y752492D01*
X309975Y752283D01*
X309683Y752200D01*
X309392Y752325D01*
X309183Y752617D01*
X309100Y752950D01*
X309183Y753283D01*
X309392Y753575D01*
X309683Y753700D01*
X309975Y753617D01*
X310183Y753408D01*
X310267Y753158D01*
Y752742D01*
X310392Y752367D01*
X310642Y752117D01*
X310933Y752033D01*
X311225Y752117D01*
X311433Y752325D01*
X311558Y752658D01*
X311600Y752950D01*
G01X317000Y729229D02*
X316875Y728979D01*
X316792Y728687D01*
Y728354D01*
X316917Y727979D01*
X317125Y727687D01*
X317375Y727479D01*
X317792Y727312D01*
X318167Y727270D01*
X318542Y727354D01*
X318792Y727479D01*
X319042Y727729D01*
X319209Y728020D01*
X319292Y728312D01*
Y728604D01*
X319209Y728895D01*
X319084Y729145D01*
X318917Y729354D01*
G01X319292Y731412D02*
X316792D01*
X317292Y730912D01*
G01X319292D02*
Y731912D01*
G01X319000Y733804D02*
X319209Y734095D01*
X319292Y734429D01*
X319209Y734762D01*
X318959Y735054D01*
X318584Y735262D01*
X318209Y735345D01*
X317750D01*
X317375Y735262D01*
X317042Y735054D01*
X316875Y734804D01*
X316792Y734512D01*
X316875Y734179D01*
X317042Y733929D01*
X317292Y733762D01*
X317625Y733679D01*
X317917Y733762D01*
X318209Y733970D01*
X318375Y734220D01*
X318417Y734512D01*
X318334Y734845D01*
X318125Y735095D01*
X317750Y735345D01*
G01X318917Y736695D02*
X319125Y736945D01*
X319250Y737237D01*
X319292Y737612D01*
X319209Y737987D01*
X319042Y738279D01*
X318750Y738487D01*
X318417Y738529D01*
X318084Y738445D01*
X317875Y738237D01*
X317709Y737945D01*
X317667Y737654D01*
X317709Y737362D01*
X317875Y736987D01*
X316792Y737112D01*
Y738237D01*
G01X329801Y715987D02*
X329676Y715737D01*
X329593Y715445D01*
Y715112D01*
X329718Y714737D01*
X329926Y714445D01*
X330176Y714237D01*
X330593Y714070D01*
X330968Y714028D01*
X331343Y714112D01*
X331593Y714237D01*
X331843Y714487D01*
X332010Y714778D01*
X332093Y715070D01*
Y715362D01*
X332010Y715653D01*
X331885Y715903D01*
X331718Y716112D01*
G01X330010Y717378D02*
X329760Y717628D01*
X329635Y717920D01*
X329593Y718253D01*
X329676Y718670D01*
X329885Y718962D01*
X330135Y719045D01*
X330385Y719003D01*
X330593Y718837D01*
X331010Y718003D01*
X331301Y717628D01*
X331718Y717378D01*
X332093Y717295D01*
Y719045D01*
G01Y721770D02*
X329593D01*
X331385Y720228D01*
Y722312D01*
G01X332093Y724870D02*
X329593D01*
X331385Y723328D01*
Y725412D01*
G01X333656Y715924D02*
X333531Y715674D01*
X333448Y715382D01*
Y715049D01*
X333573Y714674D01*
X333781Y714382D01*
X334031Y714174D01*
X334448Y714007D01*
X334823Y713965D01*
X335198Y714049D01*
X335448Y714174D01*
X335698Y714424D01*
X335865Y714715D01*
X335948Y715007D01*
Y715299D01*
X335865Y715590D01*
X335740Y715840D01*
X335573Y716049D01*
G01X333865Y717315D02*
X333615Y717565D01*
X333490Y717857D01*
X333448Y718190D01*
X333531Y718607D01*
X333740Y718899D01*
X333990Y718982D01*
X334240Y718940D01*
X334448Y718774D01*
X334865Y717940D01*
X335156Y717565D01*
X335573Y717315D01*
X335948Y717232D01*
Y718982D01*
G01Y721707D02*
X333448D01*
X335240Y720165D01*
Y722249D01*
G01X335448Y723390D02*
X335740Y723640D01*
X335906Y723974D01*
X335948Y724349D01*
X335906Y724682D01*
X335698Y725015D01*
X335448Y725224D01*
X335198Y725265D01*
X334906Y725182D01*
X334698Y724890D01*
X334615Y724599D01*
Y724224D01*
G01Y724599D02*
X334490Y724849D01*
X334281Y725057D01*
X334031Y725140D01*
X333781Y725057D01*
X333573Y724849D01*
X333448Y724474D01*
X333490Y724099D01*
X333656Y723724D01*
G01X302780Y744330D02*
X302655Y744080D01*
X302572Y743788D01*
Y743455D01*
X302697Y743080D01*
X302905Y742788D01*
X303155Y742580D01*
X303572Y742413D01*
X303947Y742371D01*
X304322Y742455D01*
X304572Y742580D01*
X304822Y742830D01*
X304989Y743121D01*
X305072Y743413D01*
Y743705D01*
X304989Y743996D01*
X304864Y744246D01*
X304697Y744455D01*
G01X302989Y745721D02*
X302739Y745971D01*
X302614Y746263D01*
X302572Y746596D01*
X302655Y747013D01*
X302864Y747305D01*
X303114Y747388D01*
X303364Y747346D01*
X303572Y747180D01*
X303989Y746346D01*
X304280Y745971D01*
X304697Y745721D01*
X305072Y745638D01*
Y747388D01*
G01X302572Y749613D02*
X302655Y749280D01*
X302864Y749030D01*
X303114Y748863D01*
X303447Y748738D01*
X303822Y748696D01*
X304197Y748738D01*
X304530Y748863D01*
X304780Y749030D01*
X304989Y749280D01*
X305072Y749613D01*
X304989Y749946D01*
X304780Y750196D01*
X304530Y750363D01*
X304197Y750488D01*
X303822Y750530D01*
X303447Y750488D01*
X303114Y750363D01*
X302864Y750196D01*
X302655Y749946D01*
X302572Y749613D01*
G01Y752713D02*
X302655Y752380D01*
X302864Y752130D01*
X303114Y751963D01*
X303447Y751838D01*
X303822Y751796D01*
X304197Y751838D01*
X304530Y751963D01*
X304780Y752130D01*
X304989Y752380D01*
X305072Y752713D01*
X304989Y753046D01*
X304780Y753296D01*
X304530Y753463D01*
X304197Y753588D01*
X303822Y753630D01*
X303447Y753588D01*
X303114Y753463D01*
X302864Y753296D01*
X302655Y753046D01*
X302572Y752713D01*
G01X293098Y744657D02*
X292973Y744407D01*
X292890Y744115D01*
Y743782D01*
X293015Y743407D01*
X293223Y743115D01*
X293473Y742907D01*
X293890Y742740D01*
X294265Y742698D01*
X294640Y742782D01*
X294890Y742907D01*
X295140Y743157D01*
X295307Y743448D01*
X295390Y743740D01*
Y744032D01*
X295307Y744323D01*
X295182Y744573D01*
X295015Y744782D01*
G01X295390Y746840D02*
X292890D01*
X293390Y746340D01*
G01X295390D02*
Y747340D01*
G01X295098Y749232D02*
X295307Y749523D01*
X295390Y749857D01*
X295307Y750190D01*
X295057Y750482D01*
X294682Y750690D01*
X294307Y750773D01*
X293848D01*
X293473Y750690D01*
X293140Y750482D01*
X292973Y750232D01*
X292890Y749940D01*
X292973Y749607D01*
X293140Y749357D01*
X293390Y749190D01*
X293723Y749107D01*
X294015Y749190D01*
X294307Y749398D01*
X294473Y749648D01*
X294515Y749940D01*
X294432Y750273D01*
X294223Y750523D01*
X293848Y750773D01*
G01X295098Y752332D02*
X295307Y752623D01*
X295390Y752957D01*
X295307Y753290D01*
X295057Y753582D01*
X294682Y753790D01*
X294307Y753873D01*
X293848D01*
X293473Y753790D01*
X293140Y753582D01*
X292973Y753332D01*
X292890Y753040D01*
X292973Y752707D01*
X293140Y752457D01*
X293390Y752290D01*
X293723Y752207D01*
X294015Y752290D01*
X294307Y752498D01*
X294473Y752748D01*
X294515Y753040D01*
X294432Y753373D01*
X294223Y753623D01*
X293848Y753873D01*
G01X323916Y741921D02*
X323666Y742046D01*
X323374Y742129D01*
X323041D01*
X322666Y742004D01*
X322374Y741796D01*
X322166Y741546D01*
X321999Y741129D01*
X321957Y740754D01*
X322041Y740379D01*
X322166Y740129D01*
X322416Y739879D01*
X322707Y739712D01*
X322999Y739629D01*
X323291D01*
X323582Y739712D01*
X323832Y739837D01*
X324041Y740004D01*
G01X326099Y739629D02*
Y742129D01*
X325599Y741629D01*
G01Y739629D02*
X326599D01*
G01X328491Y739921D02*
X328782Y739712D01*
X329116Y739629D01*
X329449Y739712D01*
X329741Y739962D01*
X329949Y740337D01*
X330032Y740712D01*
Y741171D01*
X329949Y741546D01*
X329741Y741879D01*
X329491Y742046D01*
X329199Y742129D01*
X328866Y742046D01*
X328616Y741879D01*
X328449Y741629D01*
X328366Y741296D01*
X328449Y741004D01*
X328657Y740712D01*
X328907Y740546D01*
X329199Y740504D01*
X329532Y740587D01*
X329782Y740796D01*
X330032Y741171D01*
G01X332799Y739629D02*
Y742129D01*
X331257Y740337D01*
X333341D01*
G01X314658Y742417D02*
X314533Y742167D01*
X314450Y741875D01*
Y741542D01*
X314575Y741167D01*
X314783Y740875D01*
X315033Y740667D01*
X315450Y740500D01*
X315825Y740458D01*
X316200Y740542D01*
X316450Y740667D01*
X316700Y740917D01*
X316867Y741208D01*
X316950Y741500D01*
Y741792D01*
X316867Y742083D01*
X316742Y742333D01*
X316575Y742542D01*
G01X316950Y744600D02*
X314450D01*
X314950Y744100D01*
G01X316950D02*
Y745100D01*
G01X316658Y746992D02*
X316867Y747283D01*
X316950Y747617D01*
X316867Y747950D01*
X316617Y748242D01*
X316242Y748450D01*
X315867Y748533D01*
X315408D01*
X315033Y748450D01*
X314700Y748242D01*
X314533Y747992D01*
X314450Y747700D01*
X314533Y747367D01*
X314700Y747117D01*
X314950Y746950D01*
X315283Y746867D01*
X315575Y746950D01*
X315867Y747158D01*
X316033Y747408D01*
X316075Y747700D01*
X315992Y748033D01*
X315783Y748283D01*
X315408Y748533D01*
G01X316450Y749883D02*
X316742Y750133D01*
X316908Y750467D01*
X316950Y750842D01*
X316908Y751175D01*
X316700Y751508D01*
X316450Y751717D01*
X316200Y751758D01*
X315908Y751675D01*
X315700Y751383D01*
X315617Y751092D01*
Y750717D01*
G01Y751092D02*
X315492Y751342D01*
X315283Y751550D01*
X315033Y751633D01*
X314783Y751550D01*
X314575Y751342D01*
X314450Y750967D01*
X314492Y750592D01*
X314658Y750217D01*
G01X318658Y742417D02*
X318533Y742167D01*
X318450Y741875D01*
Y741542D01*
X318575Y741167D01*
X318783Y740875D01*
X319033Y740667D01*
X319450Y740500D01*
X319825Y740458D01*
X320200Y740542D01*
X320450Y740667D01*
X320700Y740917D01*
X320867Y741208D01*
X320950Y741500D01*
Y741792D01*
X320867Y742083D01*
X320742Y742333D01*
X320575Y742542D01*
G01X320950Y744600D02*
X318450D01*
X318950Y744100D01*
G01X320950D02*
Y745100D01*
G01X320658Y746992D02*
X320867Y747283D01*
X320950Y747617D01*
X320867Y747950D01*
X320617Y748242D01*
X320242Y748450D01*
X319867Y748533D01*
X319408D01*
X319033Y748450D01*
X318700Y748242D01*
X318533Y747992D01*
X318450Y747700D01*
X318533Y747367D01*
X318700Y747117D01*
X318950Y746950D01*
X319283Y746867D01*
X319575Y746950D01*
X319867Y747158D01*
X320033Y747408D01*
X320075Y747700D01*
X319992Y748033D01*
X319783Y748283D01*
X319408Y748533D01*
G01X318867Y750008D02*
X318617Y750258D01*
X318492Y750550D01*
X318450Y750883D01*
X318533Y751300D01*
X318742Y751592D01*
X318992Y751675D01*
X319242Y751633D01*
X319450Y751467D01*
X319867Y750633D01*
X320158Y750258D01*
X320575Y750008D01*
X320950Y749925D01*
Y751675D01*
G01X323916Y746219D02*
X323666Y746344D01*
X323374Y746427D01*
X323041D01*
X322666Y746302D01*
X322374Y746094D01*
X322166Y745844D01*
X321999Y745427D01*
X321957Y745052D01*
X322041Y744677D01*
X322166Y744427D01*
X322416Y744177D01*
X322707Y744010D01*
X322999Y743927D01*
X323291D01*
X323582Y744010D01*
X323832Y744135D01*
X324041Y744302D01*
G01X326099Y743927D02*
Y746427D01*
X325599Y745927D01*
G01Y743927D02*
X326599D01*
G01X328491Y744219D02*
X328782Y744010D01*
X329116Y743927D01*
X329449Y744010D01*
X329741Y744260D01*
X329949Y744635D01*
X330032Y745010D01*
Y745469D01*
X329949Y745844D01*
X329741Y746177D01*
X329491Y746344D01*
X329199Y746427D01*
X328866Y746344D01*
X328616Y746177D01*
X328449Y745927D01*
X328366Y745594D01*
X328449Y745302D01*
X328657Y745010D01*
X328907Y744844D01*
X329199Y744802D01*
X329532Y744885D01*
X329782Y745094D01*
X330032Y745469D01*
G01X332299Y743927D02*
Y746427D01*
X331799Y745927D01*
G01Y743927D02*
X332799D01*
G01X321211Y731376D02*
Y733876D01*
X322252D01*
X322586Y733751D01*
X322794Y733584D01*
X322877Y733251D01*
X322794Y732918D01*
X322544Y732709D01*
X322252Y732584D01*
X321211D01*
G01X322252D02*
X322877Y731376D01*
G01X325644D02*
Y733876D01*
X324102Y732084D01*
X326186D01*
G01X327327Y731751D02*
X327577Y731543D01*
X327869Y731418D01*
X328244Y731376D01*
X328619Y731459D01*
X328911Y731626D01*
X329119Y731918D01*
X329161Y732251D01*
X329077Y732584D01*
X328869Y732793D01*
X328577Y732959D01*
X328286Y733001D01*
X327994Y732959D01*
X327619Y732793D01*
X327744Y733876D01*
X328869D01*
G01X331344Y731376D02*
Y733876D01*
X330844Y733376D01*
G01Y731376D02*
X331844D01*
G01X324349Y714521D02*
X321849D01*
Y715562D01*
X321974Y715896D01*
X322141Y716104D01*
X322474Y716187D01*
X322807Y716104D01*
X323016Y715854D01*
X323141Y715562D01*
Y714521D01*
G01Y715562D02*
X324349Y716187D01*
G01X323974Y717537D02*
X324182Y717787D01*
X324307Y718079D01*
X324349Y718454D01*
X324266Y718829D01*
X324099Y719121D01*
X323807Y719329D01*
X323474Y719371D01*
X323141Y719287D01*
X322932Y719079D01*
X322766Y718787D01*
X322724Y718496D01*
X322766Y718204D01*
X322932Y717829D01*
X321849Y717954D01*
Y719079D01*
G01X323849Y720637D02*
X324141Y720887D01*
X324307Y721221D01*
X324349Y721596D01*
X324307Y721929D01*
X324099Y722262D01*
X323849Y722471D01*
X323599Y722512D01*
X323307Y722429D01*
X323099Y722137D01*
X323016Y721846D01*
Y721471D01*
G01Y721846D02*
X322891Y722096D01*
X322682Y722304D01*
X322432Y722387D01*
X322182Y722304D01*
X321974Y722096D01*
X321849Y721721D01*
X321891Y721346D01*
X322057Y720971D01*
G01X324057Y723946D02*
X324266Y724237D01*
X324349Y724571D01*
X324266Y724904D01*
X324016Y725196D01*
X323641Y725404D01*
X323266Y725487D01*
X322807D01*
X322432Y725404D01*
X322099Y725196D01*
X321932Y724946D01*
X321849Y724654D01*
X321932Y724321D01*
X322099Y724071D01*
X322349Y723904D01*
X322682Y723821D01*
X322974Y723904D01*
X323266Y724112D01*
X323432Y724362D01*
X323474Y724654D01*
X323391Y724987D01*
X323182Y725237D01*
X322807Y725487D01*
G01X291639Y740417D02*
X289139D01*
Y741458D01*
X289264Y741792D01*
X289431Y742000D01*
X289764Y742083D01*
X290097Y742000D01*
X290306Y741750D01*
X290431Y741458D01*
Y740417D01*
G01Y741458D02*
X291639Y742083D01*
G01X291264Y743433D02*
X291472Y743683D01*
X291597Y743975D01*
X291639Y744350D01*
X291556Y744725D01*
X291389Y745017D01*
X291097Y745225D01*
X290764Y745267D01*
X290431Y745183D01*
X290222Y744975D01*
X290056Y744683D01*
X290014Y744392D01*
X290056Y744100D01*
X290222Y743725D01*
X289139Y743850D01*
Y744975D01*
G01Y747450D02*
X289222Y747117D01*
X289431Y746867D01*
X289681Y746700D01*
X290014Y746575D01*
X290389Y746533D01*
X290764Y746575D01*
X291097Y746700D01*
X291347Y746867D01*
X291556Y747117D01*
X291639Y747450D01*
X291556Y747783D01*
X291347Y748033D01*
X291097Y748200D01*
X290764Y748325D01*
X290389Y748367D01*
X290014Y748325D01*
X289681Y748200D01*
X289431Y748033D01*
X289222Y747783D01*
X289139Y747450D01*
G01X291639Y750467D02*
X291097Y750550D01*
X290639Y750675D01*
X290222Y750842D01*
X289764Y751050D01*
X289139Y751383D01*
Y749717D01*
G01X293700Y735600D02*
X289700D01*
Y728200D01*
G01X316732Y714364D02*
X314232D01*
Y715405D01*
X314357Y715739D01*
X314524Y715947D01*
X314857Y716030D01*
X315190Y715947D01*
X315399Y715697D01*
X315524Y715405D01*
Y714364D01*
G01Y715405D02*
X316732Y716030D01*
G01X316357Y717380D02*
X316565Y717630D01*
X316690Y717922D01*
X316732Y718297D01*
X316649Y718672D01*
X316482Y718964D01*
X316190Y719172D01*
X315857Y719214D01*
X315524Y719130D01*
X315315Y718922D01*
X315149Y718630D01*
X315107Y718339D01*
X315149Y718047D01*
X315315Y717672D01*
X314232Y717797D01*
Y718922D01*
G01X316732Y721897D02*
X314232D01*
X316024Y720355D01*
Y722439D01*
G01X314232Y724497D02*
X314315Y724164D01*
X314524Y723914D01*
X314774Y723747D01*
X315107Y723622D01*
X315482Y723580D01*
X315857Y723622D01*
X316190Y723747D01*
X316440Y723914D01*
X316649Y724164D01*
X316732Y724497D01*
X316649Y724830D01*
X316440Y725080D01*
X316190Y725247D01*
X315857Y725372D01*
X315482Y725414D01*
X315107Y725372D01*
X314774Y725247D01*
X314524Y725080D01*
X314315Y724830D01*
X314232Y724497D01*
G01X287559Y740437D02*
X285059D01*
Y741478D01*
X285184Y741812D01*
X285351Y742020D01*
X285684Y742103D01*
X286017Y742020D01*
X286226Y741770D01*
X286351Y741478D01*
Y740437D01*
G01Y741478D02*
X287559Y742103D01*
G01X287184Y743453D02*
X287392Y743703D01*
X287517Y743995D01*
X287559Y744370D01*
X287476Y744745D01*
X287309Y745037D01*
X287017Y745245D01*
X286684Y745287D01*
X286351Y745203D01*
X286142Y744995D01*
X285976Y744703D01*
X285934Y744412D01*
X285976Y744120D01*
X286142Y743745D01*
X285059Y743870D01*
Y744995D01*
G01Y747470D02*
X285142Y747137D01*
X285351Y746887D01*
X285601Y746720D01*
X285934Y746595D01*
X286309Y746553D01*
X286684Y746595D01*
X287017Y746720D01*
X287267Y746887D01*
X287476Y747137D01*
X287559Y747470D01*
X287476Y747803D01*
X287267Y748053D01*
X287017Y748220D01*
X286684Y748345D01*
X286309Y748387D01*
X285934Y748345D01*
X285601Y748220D01*
X285351Y748053D01*
X285142Y747803D01*
X285059Y747470D01*
G01X287559Y750570D02*
X287517Y750862D01*
X287392Y751195D01*
X287184Y751403D01*
X286892Y751487D01*
X286601Y751403D01*
X286351Y751153D01*
X286226Y750778D01*
Y750362D01*
X286142Y750112D01*
X285934Y749903D01*
X285642Y749820D01*
X285351Y749945D01*
X285142Y750237D01*
X285059Y750570D01*
X285142Y750903D01*
X285351Y751195D01*
X285642Y751320D01*
X285934Y751237D01*
X286142Y751028D01*
X286226Y750778D01*
Y750362D01*
X286351Y749987D01*
X286601Y749737D01*
X286892Y749653D01*
X287184Y749737D01*
X287392Y749945D01*
X287517Y750278D01*
X287559Y750570D01*
G01X289620Y735620D02*
X285620D01*
Y728220D01*
G01X333330Y726702D02*
Y729202D01*
X334371D01*
X334705Y729077D01*
X334913Y728910D01*
X334996Y728577D01*
X334913Y728244D01*
X334663Y728035D01*
X334371Y727910D01*
X333330D01*
G01X334371D02*
X334996Y726702D01*
G01X337180D02*
X337263Y727244D01*
X337388Y727702D01*
X337555Y728119D01*
X337763Y728577D01*
X338096Y729202D01*
X336430D01*
G01X339571Y728785D02*
X339821Y729035D01*
X340113Y729160D01*
X340446Y729202D01*
X340863Y729119D01*
X341155Y728910D01*
X341238Y728660D01*
X341196Y728410D01*
X341030Y728202D01*
X340196Y727785D01*
X339821Y727494D01*
X339571Y727077D01*
X339488Y726702D01*
X341238D01*
G01X342671Y727744D02*
X342963Y728035D01*
X343213Y728202D01*
X343546Y728285D01*
X343838Y728202D01*
X344046Y728035D01*
X344213Y727785D01*
X344255Y727494D01*
X344213Y727244D01*
X344046Y726994D01*
X343796Y726785D01*
X343505Y726702D01*
X343171Y726785D01*
X342880Y727035D01*
X342713Y727410D01*
X342671Y727827D01*
X342755Y728369D01*
X342880Y728660D01*
X343088Y728952D01*
X343380Y729160D01*
X343671Y729202D01*
X343963Y729119D01*
X344171Y728910D01*
G01X333372Y730853D02*
Y733353D01*
X334413D01*
X334747Y733228D01*
X334955Y733061D01*
X335038Y732728D01*
X334955Y732395D01*
X334705Y732186D01*
X334413Y732061D01*
X333372D01*
G01X334413D02*
X335038Y730853D01*
G01X337222D02*
X337305Y731395D01*
X337430Y731853D01*
X337597Y732270D01*
X337805Y732728D01*
X338138Y733353D01*
X336472D01*
G01X339613Y732936D02*
X339863Y733186D01*
X340155Y733311D01*
X340488Y733353D01*
X340905Y733270D01*
X341197Y733061D01*
X341280Y732811D01*
X341238Y732561D01*
X341072Y732353D01*
X340238Y731936D01*
X339863Y731645D01*
X339613Y731228D01*
X339530Y730853D01*
X341280D01*
G01X342588Y731353D02*
X342838Y731061D01*
X343172Y730895D01*
X343547Y730853D01*
X343880Y730895D01*
X344213Y731103D01*
X344422Y731353D01*
X344463Y731603D01*
X344380Y731895D01*
X344088Y732103D01*
X343797Y732186D01*
X343422D01*
G01X343797D02*
X344047Y732311D01*
X344255Y732520D01*
X344338Y732770D01*
X344255Y733020D01*
X344047Y733228D01*
X343672Y733353D01*
X343297Y733311D01*
X342922Y733145D01*
G01X321276Y727231D02*
Y729731D01*
X322317D01*
X322651Y729606D01*
X322859Y729439D01*
X322942Y729106D01*
X322859Y728773D01*
X322609Y728564D01*
X322317Y728439D01*
X321276D01*
G01X322317D02*
X322942Y727231D01*
G01X324417Y728273D02*
X324709Y728564D01*
X324959Y728731D01*
X325292Y728814D01*
X325584Y728731D01*
X325792Y728564D01*
X325959Y728314D01*
X326001Y728023D01*
X325959Y727773D01*
X325792Y727523D01*
X325542Y727314D01*
X325251Y727231D01*
X324917Y727314D01*
X324626Y727564D01*
X324459Y727939D01*
X324417Y728356D01*
X324501Y728898D01*
X324626Y729189D01*
X324834Y729481D01*
X325126Y729689D01*
X325417Y729731D01*
X325709Y729648D01*
X325917Y729439D01*
G01X327392Y727606D02*
X327642Y727398D01*
X327934Y727273D01*
X328309Y727231D01*
X328684Y727314D01*
X328976Y727481D01*
X329184Y727773D01*
X329226Y728106D01*
X329142Y728439D01*
X328934Y728648D01*
X328642Y728814D01*
X328351Y728856D01*
X328059Y728814D01*
X327684Y728648D01*
X327809Y729731D01*
X328934D01*
G01X331409Y727231D02*
Y729731D01*
X330909Y729231D01*
G01Y727231D02*
X331909D01*
G01X340094Y714093D02*
X340052Y713760D01*
X339886Y713468D01*
X339636Y713218D01*
X339344Y713051D01*
X339011Y712968D01*
X338677D01*
X338344Y713051D01*
X338052Y713218D01*
X337802Y713468D01*
X337636Y713760D01*
X337594Y714093D01*
X337636Y714426D01*
X337802Y714718D01*
X338052Y714968D01*
X338344Y715135D01*
X338677Y715218D01*
X339011D01*
X339344Y715135D01*
X339636Y714968D01*
X339886Y714718D01*
X340052Y714426D01*
X340094Y714093D01*
G01X339427Y714426D02*
X340094Y714926D01*
G01Y717193D02*
X337594D01*
X338094Y716693D01*
G01X340094D02*
Y717693D01*
G01Y720293D02*
X337594D01*
X338094Y719793D01*
G01X340094D02*
Y720793D01*
G01X344483Y714788D02*
X344441Y714455D01*
X344275Y714163D01*
X344025Y713913D01*
X343733Y713746D01*
X343400Y713663D01*
X343066D01*
X342733Y713746D01*
X342441Y713913D01*
X342191Y714163D01*
X342025Y714455D01*
X341983Y714788D01*
X342025Y715121D01*
X342191Y715413D01*
X342441Y715663D01*
X342733Y715830D01*
X343066Y715913D01*
X343400D01*
X343733Y715830D01*
X344025Y715663D01*
X344275Y715413D01*
X344441Y715121D01*
X344483Y714788D01*
G01X343816Y715121D02*
X344483Y715621D01*
G01Y717888D02*
X341983D01*
X342483Y717388D01*
G01X344483D02*
Y718388D01*
G01X342400Y720196D02*
X342150Y720446D01*
X342025Y720738D01*
X341983Y721071D01*
X342066Y721488D01*
X342275Y721780D01*
X342525Y721863D01*
X342775Y721821D01*
X342983Y721655D01*
X343400Y720821D01*
X343691Y720446D01*
X344108Y720196D01*
X344483Y720113D01*
Y721863D01*
G01X318106Y718256D02*
X317981Y718006D01*
X317898Y717714D01*
Y717381D01*
X318023Y717006D01*
X318231Y716714D01*
X318481Y716506D01*
X318898Y716339D01*
X319273Y716297D01*
X319648Y716381D01*
X319898Y716506D01*
X320148Y716756D01*
X320315Y717047D01*
X320398Y717339D01*
Y717631D01*
X320315Y717922D01*
X320190Y718172D01*
X320023Y718381D01*
G01X318315Y719647D02*
X318065Y719897D01*
X317940Y720189D01*
X317898Y720522D01*
X317981Y720939D01*
X318190Y721231D01*
X318440Y721314D01*
X318690Y721272D01*
X318898Y721106D01*
X319315Y720272D01*
X319606Y719897D01*
X320023Y719647D01*
X320398Y719564D01*
Y721314D01*
G01Y724039D02*
X317898D01*
X319690Y722497D01*
Y724581D01*
G01X320398Y726639D02*
X317898D01*
X318398Y726139D01*
G01X320398D02*
Y727139D01*
G01X315057Y727542D02*
X312557D01*
Y728583D01*
X312682Y728917D01*
X312849Y729125D01*
X313182Y729208D01*
X313515Y729125D01*
X313724Y728875D01*
X313849Y728583D01*
Y727542D01*
G01Y728583D02*
X315057Y729208D01*
G01X314682Y730558D02*
X314890Y730808D01*
X315015Y731100D01*
X315057Y731475D01*
X314974Y731850D01*
X314807Y732142D01*
X314515Y732350D01*
X314182Y732392D01*
X313849Y732308D01*
X313640Y732100D01*
X313474Y731808D01*
X313432Y731517D01*
X313474Y731225D01*
X313640Y730850D01*
X312557Y730975D01*
Y732100D01*
G01Y734575D02*
X312640Y734242D01*
X312849Y733992D01*
X313099Y733825D01*
X313432Y733700D01*
X313807Y733658D01*
X314182Y733700D01*
X314515Y733825D01*
X314765Y733992D01*
X314974Y734242D01*
X315057Y734575D01*
X314974Y734908D01*
X314765Y735158D01*
X314515Y735325D01*
X314182Y735450D01*
X313807Y735492D01*
X313432Y735450D01*
X313099Y735325D01*
X312849Y735158D01*
X312640Y734908D01*
X312557Y734575D01*
G01X315057Y738175D02*
X312557D01*
X314349Y736633D01*
Y738717D01*
G01X371300Y713700D02*
X353300D01*
G01X325881Y715957D02*
X325756Y715707D01*
X325673Y715415D01*
Y715082D01*
X325798Y714707D01*
X326006Y714415D01*
X326256Y714207D01*
X326673Y714040D01*
X327048Y713998D01*
X327423Y714082D01*
X327673Y714207D01*
X327923Y714457D01*
X328090Y714748D01*
X328173Y715040D01*
Y715332D01*
X328090Y715623D01*
X327965Y715873D01*
X327798Y716082D01*
G01Y717223D02*
X328006Y717473D01*
X328131Y717765D01*
X328173Y718140D01*
X328090Y718515D01*
X327923Y718807D01*
X327631Y719015D01*
X327298Y719057D01*
X326965Y718973D01*
X326756Y718765D01*
X326590Y718473D01*
X326548Y718182D01*
X326590Y717890D01*
X326756Y717515D01*
X325673Y717640D01*
Y718765D01*
G01X326090Y720448D02*
X325840Y720698D01*
X325715Y720990D01*
X325673Y721323D01*
X325756Y721740D01*
X325965Y722032D01*
X326215Y722115D01*
X326465Y722073D01*
X326673Y721907D01*
X327090Y721073D01*
X327381Y720698D01*
X327798Y720448D01*
X328173Y720365D01*
Y722115D01*
G01Y724840D02*
X325673D01*
X327465Y723298D01*
Y725382D01*
G01X309484Y718920D02*
Y723920D01*
X304484D01*
G01X290516Y722513D02*
Y725513D01*
G01X308077Y715188D02*
X310077D01*
G01X427217Y20988D02*
X426967Y21113D01*
X426675Y21196D01*
X426342D01*
X425967Y21071D01*
X425675Y20863D01*
X425467Y20613D01*
X425300Y20196D01*
X425258Y19821D01*
X425342Y19446D01*
X425467Y19196D01*
X425717Y18946D01*
X426008Y18779D01*
X426300Y18696D01*
X426592D01*
X426883Y18779D01*
X427133Y18904D01*
X427342Y19071D01*
G01X429400Y18696D02*
Y21196D01*
X428900Y20696D01*
G01Y18696D02*
X429900D01*
G01X431583Y19196D02*
X431833Y18904D01*
X432167Y18738D01*
X432542Y18696D01*
X432875Y18738D01*
X433208Y18946D01*
X433417Y19196D01*
X433458Y19446D01*
X433375Y19738D01*
X433083Y19946D01*
X432792Y20029D01*
X432417D01*
G01X432792D02*
X433042Y20154D01*
X433250Y20363D01*
X433333Y20613D01*
X433250Y20863D01*
X433042Y21071D01*
X432667Y21196D01*
X432292Y21154D01*
X431917Y20988D01*
G01X435600Y18696D02*
Y21196D01*
X435100Y20696D01*
G01Y18696D02*
X436100D01*
G01X422017Y57000D02*
Y59500D01*
X423058D01*
X423392Y59375D01*
X423600Y59208D01*
X423683Y58875D01*
X423600Y58542D01*
X423350Y58333D01*
X423058Y58208D01*
X422017D01*
G01X423058D02*
X423683Y57000D01*
G01X426450D02*
Y59500D01*
X424908Y57708D01*
X426992D01*
G01X428133Y57375D02*
X428383Y57167D01*
X428675Y57042D01*
X429050Y57000D01*
X429425Y57083D01*
X429717Y57250D01*
X429925Y57542D01*
X429967Y57875D01*
X429883Y58208D01*
X429675Y58417D01*
X429383Y58583D01*
X429092Y58625D01*
X428800Y58583D01*
X428425Y58417D01*
X428550Y59500D01*
X429675D01*
G01X432650Y57000D02*
Y59500D01*
X431108Y57708D01*
X433192D01*
G01X425417Y6296D02*
Y8796D01*
X426458D01*
X426792Y8671D01*
X427000Y8504D01*
X427083Y8171D01*
X427000Y7838D01*
X426750Y7629D01*
X426458Y7504D01*
X425417D01*
G01X426458D02*
X427083Y6296D01*
G01X429850D02*
Y8796D01*
X428308Y7004D01*
X430392D01*
G01X431533Y6671D02*
X431783Y6463D01*
X432075Y6338D01*
X432450Y6296D01*
X432825Y6379D01*
X433117Y6546D01*
X433325Y6838D01*
X433367Y7171D01*
X433283Y7504D01*
X433075Y7713D01*
X432783Y7879D01*
X432492Y7921D01*
X432200Y7879D01*
X431825Y7713D01*
X431950Y8796D01*
X433075D01*
G01X434758Y7338D02*
X435050Y7629D01*
X435300Y7796D01*
X435633Y7879D01*
X435925Y7796D01*
X436133Y7629D01*
X436300Y7379D01*
X436342Y7088D01*
X436300Y6838D01*
X436133Y6588D01*
X435883Y6379D01*
X435592Y6296D01*
X435258Y6379D01*
X434967Y6629D01*
X434800Y7004D01*
X434758Y7421D01*
X434842Y7963D01*
X434967Y8254D01*
X435175Y8546D01*
X435467Y8754D01*
X435758Y8796D01*
X436050Y8713D01*
X436258Y8504D01*
G01X425517Y14796D02*
Y17296D01*
X426558D01*
X426892Y17171D01*
X427100Y17004D01*
X427183Y16671D01*
X427100Y16338D01*
X426850Y16129D01*
X426558Y16004D01*
X425517D01*
G01X426558D02*
X427183Y14796D01*
G01X429950D02*
Y17296D01*
X428408Y15504D01*
X430492D01*
G01X431633Y15171D02*
X431883Y14963D01*
X432175Y14838D01*
X432550Y14796D01*
X432925Y14879D01*
X433217Y15046D01*
X433425Y15338D01*
X433467Y15671D01*
X433383Y16004D01*
X433175Y16213D01*
X432883Y16379D01*
X432592Y16421D01*
X432300Y16379D01*
X431925Y16213D01*
X432050Y17296D01*
X433175D01*
G01X434942Y15088D02*
X435233Y14879D01*
X435567Y14796D01*
X435900Y14879D01*
X436192Y15129D01*
X436400Y15504D01*
X436483Y15879D01*
Y16338D01*
X436400Y16713D01*
X436192Y17046D01*
X435942Y17213D01*
X435650Y17296D01*
X435317Y17213D01*
X435067Y17046D01*
X434900Y16796D01*
X434817Y16463D01*
X434900Y16171D01*
X435108Y15879D01*
X435358Y15713D01*
X435650Y15671D01*
X435983Y15754D01*
X436233Y15963D01*
X436483Y16338D01*
G01X425517Y10496D02*
Y12996D01*
X426558D01*
X426892Y12871D01*
X427100Y12704D01*
X427183Y12371D01*
X427100Y12038D01*
X426850Y11829D01*
X426558Y11704D01*
X425517D01*
G01X426558D02*
X427183Y10496D01*
G01X429950D02*
Y12996D01*
X428408Y11204D01*
X430492D01*
G01X431758Y11538D02*
X432050Y11829D01*
X432300Y11996D01*
X432633Y12079D01*
X432925Y11996D01*
X433133Y11829D01*
X433300Y11579D01*
X433342Y11288D01*
X433300Y11038D01*
X433133Y10788D01*
X432883Y10579D01*
X432592Y10496D01*
X432258Y10579D01*
X431967Y10829D01*
X431800Y11204D01*
X431758Y11621D01*
X431842Y12163D01*
X431967Y12454D01*
X432175Y12746D01*
X432467Y12954D01*
X432758Y12996D01*
X433050Y12913D01*
X433258Y12704D01*
G01X435650Y12996D02*
X435317Y12913D01*
X435067Y12704D01*
X434900Y12454D01*
X434775Y12121D01*
X434733Y11746D01*
X434775Y11371D01*
X434900Y11038D01*
X435067Y10788D01*
X435317Y10579D01*
X435650Y10496D01*
X435983Y10579D01*
X436233Y10788D01*
X436400Y11038D01*
X436525Y11371D01*
X436567Y11746D01*
X436525Y12121D01*
X436400Y12454D01*
X436233Y12704D01*
X435983Y12913D01*
X435650Y12996D01*
G01X425632Y22845D02*
Y25345D01*
X426673D01*
X427007Y25220D01*
X427215Y25053D01*
X427298Y24720D01*
X427215Y24387D01*
X426965Y24178D01*
X426673Y24053D01*
X425632D01*
G01X426673D02*
X427298Y22845D01*
G01X430065D02*
Y25345D01*
X428523Y23553D01*
X430607D01*
G01X431873Y23887D02*
X432165Y24178D01*
X432415Y24345D01*
X432748Y24428D01*
X433040Y24345D01*
X433248Y24178D01*
X433415Y23928D01*
X433457Y23637D01*
X433415Y23387D01*
X433248Y23137D01*
X432998Y22928D01*
X432707Y22845D01*
X432373Y22928D01*
X432082Y23178D01*
X431915Y23553D01*
X431873Y23970D01*
X431957Y24512D01*
X432082Y24803D01*
X432290Y25095D01*
X432582Y25303D01*
X432873Y25345D01*
X433165Y25262D01*
X433373Y25053D01*
G01X434973Y24928D02*
X435223Y25178D01*
X435515Y25303D01*
X435848Y25345D01*
X436265Y25262D01*
X436557Y25053D01*
X436640Y24803D01*
X436598Y24553D01*
X436432Y24345D01*
X435598Y23928D01*
X435223Y23637D01*
X434973Y23220D01*
X434890Y22845D01*
X436640D01*
G01X423324Y63441D02*
X423074Y63566D01*
X422782Y63649D01*
X422449D01*
X422074Y63524D01*
X421782Y63316D01*
X421574Y63066D01*
X421407Y62649D01*
X421365Y62274D01*
X421449Y61899D01*
X421574Y61649D01*
X421824Y61399D01*
X422115Y61232D01*
X422407Y61149D01*
X422699D01*
X422990Y61232D01*
X423240Y61357D01*
X423449Y61524D01*
G01X425507Y61149D02*
Y63649D01*
X425007Y63149D01*
G01Y61149D02*
X426007D01*
G01X429107D02*
Y63649D01*
X427565Y61857D01*
X429649D01*
G01X431707Y61149D02*
X431999Y61191D01*
X432332Y61316D01*
X432540Y61524D01*
X432624Y61816D01*
X432540Y62107D01*
X432290Y62357D01*
X431915Y62482D01*
X431499D01*
X431249Y62566D01*
X431040Y62774D01*
X430957Y63066D01*
X431082Y63357D01*
X431374Y63566D01*
X431707Y63649D01*
X432040Y63566D01*
X432332Y63357D01*
X432457Y63066D01*
X432374Y62774D01*
X432165Y62566D01*
X431915Y62482D01*
X431499D01*
X431124Y62357D01*
X430874Y62107D01*
X430790Y61816D01*
X430874Y61524D01*
X431082Y61316D01*
X431415Y61191D01*
X431707Y61149D01*
G01X370933Y40580D02*
Y43080D01*
X371767D01*
X372100Y42955D01*
X372350Y42788D01*
X372558Y42538D01*
X372725Y42247D01*
X372767Y41830D01*
X372725Y41413D01*
X372558Y41122D01*
X372350Y40872D01*
X372100Y40705D01*
X371767Y40580D01*
X370933D01*
G01X374950D02*
Y43080D01*
X374450Y42580D01*
G01Y40580D02*
X375450D01*
G01X377133Y40955D02*
X377383Y40747D01*
X377675Y40622D01*
X378050Y40580D01*
X378425Y40663D01*
X378717Y40830D01*
X378925Y41122D01*
X378967Y41455D01*
X378883Y41788D01*
X378675Y41997D01*
X378383Y42163D01*
X378092Y42205D01*
X377800Y42163D01*
X377425Y41997D01*
X377550Y43080D01*
X378675D01*
G01X370933Y36380D02*
Y38880D01*
X371767D01*
X372100Y38755D01*
X372350Y38588D01*
X372558Y38338D01*
X372725Y38047D01*
X372767Y37630D01*
X372725Y37213D01*
X372558Y36922D01*
X372350Y36672D01*
X372100Y36505D01*
X371767Y36380D01*
X370933D01*
G01X374950D02*
Y38880D01*
X374450Y38380D01*
G01Y36380D02*
X375450D01*
G01X378550D02*
Y38880D01*
X377008Y37088D01*
X379092D01*
G01X377500Y56883D02*
X375000D01*
Y57717D01*
X375125Y58050D01*
X375292Y58300D01*
X375542Y58508D01*
X375833Y58675D01*
X376250Y58717D01*
X376667Y58675D01*
X376958Y58508D01*
X377208Y58300D01*
X377375Y58050D01*
X377500Y57717D01*
Y56883D01*
G01Y60900D02*
X375000D01*
X375500Y60400D01*
G01X377500D02*
Y61400D01*
G01Y64000D02*
X377458Y64292D01*
X377333Y64625D01*
X377125Y64833D01*
X376833Y64917D01*
X376542Y64833D01*
X376292Y64583D01*
X376167Y64208D01*
Y63792D01*
X376083Y63542D01*
X375875Y63333D01*
X375583Y63250D01*
X375292Y63375D01*
X375083Y63667D01*
X375000Y64000D01*
X375083Y64333D01*
X375292Y64625D01*
X375583Y64750D01*
X375875Y64667D01*
X376083Y64458D01*
X376167Y64208D01*
Y63792D01*
X376292Y63417D01*
X376542Y63167D01*
X376833Y63083D01*
X377125Y63167D01*
X377333Y63375D01*
X377458Y63708D01*
X377500Y64000D01*
G01X374208Y116167D02*
X374083Y115917D01*
X374000Y115625D01*
Y115292D01*
X374125Y114917D01*
X374333Y114625D01*
X374583Y114417D01*
X375000Y114250D01*
X375375Y114208D01*
X375750Y114292D01*
X376000Y114417D01*
X376250Y114667D01*
X376417Y114958D01*
X376500Y115250D01*
Y115542D01*
X376417Y115833D01*
X376292Y116083D01*
X376125Y116292D01*
G01X376500Y118350D02*
X374000D01*
X374500Y117850D01*
G01X376500D02*
Y118850D01*
G01X421559Y73873D02*
Y76373D01*
X422600D01*
X422934Y76248D01*
X423142Y76081D01*
X423225Y75748D01*
X423142Y75415D01*
X422892Y75206D01*
X422600Y75081D01*
X421559D01*
G01X422600D02*
X423225Y73873D01*
G01X425992D02*
Y76373D01*
X424450Y74581D01*
X426534D01*
G01X427675Y74248D02*
X427925Y74040D01*
X428217Y73915D01*
X428592Y73873D01*
X428967Y73956D01*
X429259Y74123D01*
X429467Y74415D01*
X429509Y74748D01*
X429425Y75081D01*
X429217Y75290D01*
X428925Y75456D01*
X428634Y75498D01*
X428342Y75456D01*
X427967Y75290D01*
X428092Y76373D01*
X429217D01*
G01X431692Y73873D02*
X431984Y73915D01*
X432317Y74040D01*
X432525Y74248D01*
X432609Y74540D01*
X432525Y74831D01*
X432275Y75081D01*
X431900Y75206D01*
X431484D01*
X431234Y75290D01*
X431025Y75498D01*
X430942Y75790D01*
X431067Y76081D01*
X431359Y76290D01*
X431692Y76373D01*
X432025Y76290D01*
X432317Y76081D01*
X432442Y75790D01*
X432359Y75498D01*
X432150Y75290D01*
X431900Y75206D01*
X431484D01*
X431109Y75081D01*
X430859Y74831D01*
X430775Y74540D01*
X430859Y74248D01*
X431067Y74040D01*
X431400Y73915D01*
X431692Y73873D01*
G01X404000Y68567D02*
X401500D01*
Y69608D01*
X401625Y69942D01*
X401792Y70150D01*
X402125Y70233D01*
X402458Y70150D01*
X402667Y69900D01*
X402792Y69608D01*
Y68567D01*
G01Y69608D02*
X404000Y70233D01*
G01Y73000D02*
X401500D01*
X403292Y71458D01*
Y73542D01*
G01X402958Y74808D02*
X402667Y75100D01*
X402500Y75350D01*
X402417Y75683D01*
X402500Y75975D01*
X402667Y76183D01*
X402917Y76350D01*
X403208Y76392D01*
X403458Y76350D01*
X403708Y76183D01*
X403917Y75933D01*
X404000Y75642D01*
X403917Y75308D01*
X403667Y75017D01*
X403292Y74850D01*
X402875Y74808D01*
X402333Y74892D01*
X402042Y75017D01*
X401750Y75225D01*
X401542Y75517D01*
X401500Y75808D01*
X401583Y76100D01*
X401792Y76308D01*
G01X385458Y68749D02*
X389458D01*
Y76149D01*
G01X408000Y68567D02*
X405500D01*
Y69608D01*
X405625Y69942D01*
X405792Y70150D01*
X406125Y70233D01*
X406458Y70150D01*
X406667Y69900D01*
X406792Y69608D01*
Y68567D01*
G01Y69608D02*
X408000Y70233D01*
G01X407500Y71583D02*
X407792Y71833D01*
X407958Y72167D01*
X408000Y72542D01*
X407958Y72875D01*
X407750Y73208D01*
X407500Y73417D01*
X407250Y73458D01*
X406958Y73375D01*
X406750Y73083D01*
X406667Y72792D01*
Y72417D01*
G01Y72792D02*
X406542Y73042D01*
X406333Y73250D01*
X406083Y73333D01*
X405833Y73250D01*
X405625Y73042D01*
X405500Y72667D01*
X405542Y72292D01*
X405708Y71917D01*
G01X408000Y75600D02*
X407958Y75892D01*
X407833Y76225D01*
X407625Y76433D01*
X407333Y76517D01*
X407042Y76433D01*
X406792Y76183D01*
X406667Y75808D01*
Y75392D01*
X406583Y75142D01*
X406375Y74933D01*
X406083Y74850D01*
X405792Y74975D01*
X405583Y75267D01*
X405500Y75600D01*
X405583Y75933D01*
X405792Y76225D01*
X406083Y76350D01*
X406375Y76267D01*
X406583Y76058D01*
X406667Y75808D01*
Y75392D01*
X406792Y75017D01*
X407042Y74767D01*
X407333Y74683D01*
X407625Y74767D01*
X407833Y74975D01*
X407958Y75308D01*
X408000Y75600D01*
G01X389458Y68749D02*
X393458D01*
Y76149D01*
G01X423322Y68097D02*
X423072Y68222D01*
X422780Y68305D01*
X422447D01*
X422072Y68180D01*
X421780Y67972D01*
X421572Y67722D01*
X421405Y67305D01*
X421363Y66930D01*
X421447Y66555D01*
X421572Y66305D01*
X421822Y66055D01*
X422113Y65888D01*
X422405Y65805D01*
X422697D01*
X422988Y65888D01*
X423238Y66013D01*
X423447Y66180D01*
G01X425505Y65805D02*
Y68305D01*
X425005Y67805D01*
G01Y65805D02*
X426005D01*
G01X429105D02*
Y68305D01*
X427563Y66513D01*
X429647D01*
G01X431622Y65805D02*
X431705Y66347D01*
X431830Y66805D01*
X431997Y67222D01*
X432205Y67680D01*
X432538Y68305D01*
X430872D01*
G01X423313Y72253D02*
X423063Y72378D01*
X422771Y72461D01*
X422438D01*
X422063Y72336D01*
X421771Y72128D01*
X421563Y71878D01*
X421396Y71461D01*
X421354Y71086D01*
X421438Y70711D01*
X421563Y70461D01*
X421813Y70211D01*
X422104Y70044D01*
X422396Y69961D01*
X422688D01*
X422979Y70044D01*
X423229Y70169D01*
X423438Y70336D01*
G01X425496Y69961D02*
Y72461D01*
X424996Y71961D01*
G01Y69961D02*
X425996D01*
G01X429096D02*
Y72461D01*
X427554Y70669D01*
X429638D01*
G01X430988Y70253D02*
X431279Y70044D01*
X431613Y69961D01*
X431946Y70044D01*
X432238Y70294D01*
X432446Y70669D01*
X432529Y71044D01*
Y71503D01*
X432446Y71878D01*
X432238Y72211D01*
X431988Y72378D01*
X431696Y72461D01*
X431363Y72378D01*
X431113Y72211D01*
X430946Y71961D01*
X430863Y71628D01*
X430946Y71336D01*
X431154Y71044D01*
X431404Y70878D01*
X431696Y70836D01*
X432029Y70919D01*
X432279Y71128D01*
X432529Y71503D01*
G01X416299Y188977D02*
X559999D01*
Y112116D01*
X416299D01*
Y188977D01*
G01X367500Y109000D02*
Y123000D01*
G01X397500Y68617D02*
X400000D01*
Y70283D01*
G01Y72550D02*
X397500D01*
X398000Y72050D01*
G01X400000D02*
Y73050D01*
G01X393658Y66349D02*
X385258D01*
Y78549D01*
X393658D01*
Y66349D01*
G01X376700Y129700D02*
Y140900D01*
G01X358700Y129700D02*
X376700D01*
G01X358700Y140900D02*
Y129700D01*
G01X369933Y96780D02*
Y99280D01*
X370767D01*
X371100Y99155D01*
X371350Y98988D01*
X371558Y98738D01*
X371725Y98447D01*
X371767Y98030D01*
X371725Y97613D01*
X371558Y97322D01*
X371350Y97072D01*
X371100Y96905D01*
X370767Y96780D01*
X369933D01*
G01X373950D02*
Y99280D01*
X373450Y98780D01*
G01Y96780D02*
X374450D01*
G01X376967D02*
X377050Y97322D01*
X377175Y97780D01*
X377342Y98197D01*
X377550Y98655D01*
X377883Y99280D01*
X376217D01*
G01X370033Y92380D02*
Y94880D01*
X370867D01*
X371200Y94755D01*
X371450Y94588D01*
X371658Y94338D01*
X371825Y94047D01*
X371867Y93630D01*
X371825Y93213D01*
X371658Y92922D01*
X371450Y92672D01*
X371200Y92505D01*
X370867Y92380D01*
X370033D01*
G01X374050D02*
Y94880D01*
X373550Y94380D01*
G01Y92380D02*
X374550D01*
G01X376358Y93422D02*
X376650Y93713D01*
X376900Y93880D01*
X377233Y93963D01*
X377525Y93880D01*
X377733Y93713D01*
X377900Y93463D01*
X377942Y93172D01*
X377900Y92922D01*
X377733Y92672D01*
X377483Y92463D01*
X377192Y92380D01*
X376858Y92463D01*
X376567Y92713D01*
X376400Y93088D01*
X376358Y93505D01*
X376442Y94047D01*
X376567Y94338D01*
X376775Y94630D01*
X377067Y94838D01*
X377358Y94880D01*
X377650Y94797D01*
X377858Y94588D01*
G01X378300Y69283D02*
X375800D01*
Y70117D01*
X375925Y70450D01*
X376092Y70700D01*
X376342Y70908D01*
X376633Y71075D01*
X377050Y71117D01*
X377467Y71075D01*
X377758Y70908D01*
X378008Y70700D01*
X378175Y70450D01*
X378300Y70117D01*
Y69283D01*
G01Y73300D02*
X375800D01*
X376300Y72800D01*
G01X378300D02*
Y73800D01*
G01X378008Y75692D02*
X378217Y75983D01*
X378300Y76317D01*
X378217Y76650D01*
X377967Y76942D01*
X377592Y77150D01*
X377217Y77233D01*
X376758D01*
X376383Y77150D01*
X376050Y76942D01*
X375883Y76692D01*
X375800Y76400D01*
X375883Y76067D01*
X376050Y75817D01*
X376300Y75650D01*
X376633Y75567D01*
X376925Y75650D01*
X377217Y75858D01*
X377383Y76108D01*
X377425Y76400D01*
X377342Y76733D01*
X377133Y76983D01*
X376758Y77233D01*
G01X387408Y188267D02*
X387283Y188017D01*
X387200Y187725D01*
Y187392D01*
X387325Y187017D01*
X387533Y186725D01*
X387783Y186517D01*
X388200Y186350D01*
X388575Y186308D01*
X388950Y186392D01*
X389200Y186517D01*
X389450Y186767D01*
X389617Y187058D01*
X389700Y187350D01*
Y187642D01*
X389617Y187933D01*
X389492Y188183D01*
X389325Y188392D01*
G01Y189533D02*
X389533Y189783D01*
X389658Y190075D01*
X389700Y190450D01*
X389617Y190825D01*
X389450Y191117D01*
X389158Y191325D01*
X388825Y191367D01*
X388492Y191283D01*
X388283Y191075D01*
X388117Y190783D01*
X388075Y190492D01*
X388117Y190200D01*
X388283Y189825D01*
X387200Y189950D01*
Y191075D01*
G01Y193550D02*
X387283Y193217D01*
X387492Y192967D01*
X387742Y192800D01*
X388075Y192675D01*
X388450Y192633D01*
X388825Y192675D01*
X389158Y192800D01*
X389408Y192967D01*
X389617Y193217D01*
X389700Y193550D01*
X389617Y193883D01*
X389408Y194133D01*
X389158Y194300D01*
X388825Y194425D01*
X388450Y194467D01*
X388075Y194425D01*
X387742Y194300D01*
X387492Y194133D01*
X387283Y193883D01*
X387200Y193550D01*
G01X389700Y196567D02*
X389158Y196650D01*
X388700Y196775D01*
X388283Y196942D01*
X387825Y197150D01*
X387200Y197483D01*
Y195817D01*
G01X388767Y202592D02*
X388517Y202717D01*
X388225Y202800D01*
X387892D01*
X387517Y202675D01*
X387225Y202467D01*
X387017Y202217D01*
X386850Y201800D01*
X386808Y201425D01*
X386892Y201050D01*
X387017Y200800D01*
X387267Y200550D01*
X387558Y200383D01*
X387850Y200300D01*
X388142D01*
X388433Y200383D01*
X388683Y200508D01*
X388892Y200675D01*
G01X390950Y200300D02*
Y202800D01*
X390450Y202300D01*
G01Y200300D02*
X391450D01*
G01X394050D02*
X394342Y200342D01*
X394675Y200467D01*
X394883Y200675D01*
X394967Y200967D01*
X394883Y201258D01*
X394633Y201508D01*
X394258Y201633D01*
X393842D01*
X393592Y201717D01*
X393383Y201925D01*
X393300Y202217D01*
X393425Y202508D01*
X393717Y202717D01*
X394050Y202800D01*
X394383Y202717D01*
X394675Y202508D01*
X394800Y202217D01*
X394717Y201925D01*
X394508Y201717D01*
X394258Y201633D01*
X393842D01*
X393467Y201508D01*
X393217Y201258D01*
X393133Y200967D01*
X393217Y200675D01*
X393425Y200467D01*
X393758Y200342D01*
X394050Y200300D01*
G01X396358Y201342D02*
X396650Y201633D01*
X396900Y201800D01*
X397233Y201883D01*
X397525Y201800D01*
X397733Y201633D01*
X397900Y201383D01*
X397942Y201092D01*
X397900Y200842D01*
X397733Y200592D01*
X397483Y200383D01*
X397192Y200300D01*
X396858Y200383D01*
X396567Y200633D01*
X396400Y201008D01*
X396358Y201425D01*
X396442Y201967D01*
X396567Y202258D01*
X396775Y202550D01*
X397067Y202758D01*
X397358Y202800D01*
X397650Y202717D01*
X397858Y202508D01*
G01X396300Y176017D02*
X393800D01*
Y177058D01*
X393925Y177392D01*
X394092Y177600D01*
X394425Y177683D01*
X394758Y177600D01*
X394967Y177350D01*
X395092Y177058D01*
Y176017D01*
G01Y177058D02*
X396300Y177683D01*
G01X395925Y179033D02*
X396133Y179283D01*
X396258Y179575D01*
X396300Y179950D01*
X396217Y180325D01*
X396050Y180617D01*
X395758Y180825D01*
X395425Y180867D01*
X395092Y180783D01*
X394883Y180575D01*
X394717Y180283D01*
X394675Y179992D01*
X394717Y179700D01*
X394883Y179325D01*
X393800Y179450D01*
Y180575D01*
G01Y183050D02*
X393883Y182717D01*
X394092Y182467D01*
X394342Y182300D01*
X394675Y182175D01*
X395050Y182133D01*
X395425Y182175D01*
X395758Y182300D01*
X396008Y182467D01*
X396217Y182717D01*
X396300Y183050D01*
X396217Y183383D01*
X396008Y183633D01*
X395758Y183800D01*
X395425Y183925D01*
X395050Y183967D01*
X394675Y183925D01*
X394342Y183800D01*
X394092Y183633D01*
X393883Y183383D01*
X393800Y183050D01*
G01Y186150D02*
X393883Y185817D01*
X394092Y185567D01*
X394342Y185400D01*
X394675Y185275D01*
X395050Y185233D01*
X395425Y185275D01*
X395758Y185400D01*
X396008Y185567D01*
X396217Y185817D01*
X396300Y186150D01*
X396217Y186483D01*
X396008Y186733D01*
X395758Y186900D01*
X395425Y187025D01*
X395050Y187067D01*
X394675Y187025D01*
X394342Y186900D01*
X394092Y186733D01*
X393883Y186483D01*
X393800Y186150D01*
G01X376883Y186553D02*
X372883D01*
Y179153D01*
G01X384200Y186217D02*
X381700D01*
Y187258D01*
X381825Y187592D01*
X381992Y187800D01*
X382325Y187883D01*
X382658Y187800D01*
X382867Y187550D01*
X382992Y187258D01*
Y186217D01*
G01Y187258D02*
X384200Y187883D01*
G01X383825Y189233D02*
X384033Y189483D01*
X384158Y189775D01*
X384200Y190150D01*
X384117Y190525D01*
X383950Y190817D01*
X383658Y191025D01*
X383325Y191067D01*
X382992Y190983D01*
X382783Y190775D01*
X382617Y190483D01*
X382575Y190192D01*
X382617Y189900D01*
X382783Y189525D01*
X381700Y189650D01*
Y190775D01*
G01Y193250D02*
X381783Y192917D01*
X381992Y192667D01*
X382242Y192500D01*
X382575Y192375D01*
X382950Y192333D01*
X383325Y192375D01*
X383658Y192500D01*
X383908Y192667D01*
X384117Y192917D01*
X384200Y193250D01*
X384117Y193583D01*
X383908Y193833D01*
X383658Y194000D01*
X383325Y194125D01*
X382950Y194167D01*
X382575Y194125D01*
X382242Y194000D01*
X381992Y193833D01*
X381783Y193583D01*
X381700Y193250D01*
G01X383700Y195433D02*
X383992Y195683D01*
X384158Y196017D01*
X384200Y196392D01*
X384158Y196725D01*
X383950Y197058D01*
X383700Y197267D01*
X383450Y197308D01*
X383158Y197225D01*
X382950Y196933D01*
X382867Y196642D01*
Y196267D01*
G01Y196642D02*
X382742Y196892D01*
X382533Y197100D01*
X382283Y197183D01*
X382033Y197100D01*
X381825Y196892D01*
X381700Y196517D01*
X381742Y196142D01*
X381908Y195767D01*
G01X358382Y188200D02*
X362382D01*
Y195600D01*
G01X377083Y209800D02*
Y208008D01*
X377250Y207633D01*
X377583Y207383D01*
X378000Y207300D01*
X378417Y207383D01*
X378750Y207633D01*
X378917Y208008D01*
Y209800D01*
G01X380183Y207800D02*
X380433Y207508D01*
X380767Y207342D01*
X381142Y207300D01*
X381475Y207342D01*
X381808Y207550D01*
X382017Y207800D01*
X382058Y208050D01*
X381975Y208342D01*
X381683Y208550D01*
X381392Y208633D01*
X381017D01*
G01X381392D02*
X381642Y208758D01*
X381850Y208967D01*
X381933Y209217D01*
X381850Y209467D01*
X381642Y209675D01*
X381267Y209800D01*
X380892Y209758D01*
X380517Y209592D01*
G01X384200Y207300D02*
X384492Y207342D01*
X384825Y207467D01*
X385033Y207675D01*
X385117Y207967D01*
X385033Y208258D01*
X384783Y208508D01*
X384408Y208633D01*
X383992D01*
X383742Y208717D01*
X383533Y208925D01*
X383450Y209217D01*
X383575Y209508D01*
X383867Y209717D01*
X384200Y209800D01*
X384533Y209717D01*
X384825Y209508D01*
X384950Y209217D01*
X384867Y208925D01*
X384658Y208717D01*
X384408Y208633D01*
X383992D01*
X383617Y208508D01*
X383367Y208258D01*
X383283Y207967D01*
X383367Y207675D01*
X383575Y207467D01*
X383908Y207342D01*
X384200Y207300D01*
G01X361535Y200099D02*
Y213499D01*
G01X371535Y200099D02*
X361535D01*
G01X371535Y213499D02*
Y200099D01*
G01X381567Y176200D02*
Y178700D01*
X382567D01*
X382900Y178575D01*
X383150Y178283D01*
X383233Y177950D01*
X383150Y177617D01*
X382942Y177367D01*
X382567Y177242D01*
X381567D01*
G01X385500Y176200D02*
X385167Y176242D01*
X384875Y176408D01*
X384625Y176658D01*
X384458Y176950D01*
X384375Y177283D01*
Y177617D01*
X384458Y177950D01*
X384625Y178242D01*
X384875Y178492D01*
X385167Y178658D01*
X385500Y178700D01*
X385833Y178658D01*
X386125Y178492D01*
X386375Y178242D01*
X386542Y177950D01*
X386625Y177617D01*
Y177283D01*
X386542Y176950D01*
X386375Y176658D01*
X386125Y176408D01*
X385833Y176242D01*
X385500Y176200D01*
G01X385833Y176867D02*
X386333Y176200D01*
G01X387808Y178283D02*
X388058Y178533D01*
X388350Y178658D01*
X388683Y178700D01*
X389100Y178617D01*
X389392Y178408D01*
X389475Y178158D01*
X389433Y177908D01*
X389267Y177700D01*
X388433Y177283D01*
X388058Y176992D01*
X387808Y176575D01*
X387725Y176200D01*
X389475D01*
G01X358259Y169344D02*
X372259D01*
G01X358259Y182344D02*
Y169344D01*
G01X372259Y182344D02*
X358259D01*
G01X372259Y169344D02*
Y182344D01*
G01X382367Y183892D02*
X382117Y184017D01*
X381825Y184100D01*
X381492D01*
X381117Y183975D01*
X380825Y183767D01*
X380617Y183517D01*
X380450Y183100D01*
X380408Y182725D01*
X380492Y182350D01*
X380617Y182100D01*
X380867Y181850D01*
X381158Y181683D01*
X381450Y181600D01*
X381742D01*
X382033Y181683D01*
X382283Y181808D01*
X382492Y181975D01*
G01X383758Y183683D02*
X384008Y183933D01*
X384300Y184058D01*
X384633Y184100D01*
X385050Y184017D01*
X385342Y183808D01*
X385425Y183558D01*
X385383Y183308D01*
X385217Y183100D01*
X384383Y182683D01*
X384008Y182392D01*
X383758Y181975D01*
X383675Y181600D01*
X385425D01*
G01X387650D02*
Y184100D01*
X387150Y183600D01*
G01Y181600D02*
X388150D01*
G01X390042Y181892D02*
X390333Y181683D01*
X390667Y181600D01*
X391000Y181683D01*
X391292Y181933D01*
X391500Y182308D01*
X391583Y182683D01*
Y183142D01*
X391500Y183517D01*
X391292Y183850D01*
X391042Y184017D01*
X390750Y184100D01*
X390417Y184017D01*
X390167Y183850D01*
X390000Y183600D01*
X389917Y183267D01*
X390000Y182975D01*
X390208Y182683D01*
X390458Y182517D01*
X390750Y182475D01*
X391083Y182558D01*
X391333Y182767D01*
X391583Y183142D01*
G01X376700Y168100D02*
Y156900D01*
G01X358700Y168100D02*
X376700D01*
G01X358700Y156900D02*
Y168100D01*
G01X387517Y227478D02*
Y229978D01*
X388558D01*
X388892Y229853D01*
X389100Y229686D01*
X389183Y229353D01*
X389100Y229020D01*
X388850Y228811D01*
X388558Y228686D01*
X387517D01*
G01X388558D02*
X389183Y227478D01*
G01X390533Y227853D02*
X390783Y227645D01*
X391075Y227520D01*
X391450Y227478D01*
X391825Y227561D01*
X392117Y227728D01*
X392325Y228020D01*
X392367Y228353D01*
X392283Y228686D01*
X392075Y228895D01*
X391783Y229061D01*
X391492Y229103D01*
X391200Y229061D01*
X390825Y228895D01*
X390950Y229978D01*
X392075D01*
G01X394550D02*
X394217Y229895D01*
X393967Y229686D01*
X393800Y229436D01*
X393675Y229103D01*
X393633Y228728D01*
X393675Y228353D01*
X393800Y228020D01*
X393967Y227770D01*
X394217Y227561D01*
X394550Y227478D01*
X394883Y227561D01*
X395133Y227770D01*
X395300Y228020D01*
X395425Y228353D01*
X395467Y228728D01*
X395425Y229103D01*
X395300Y229436D01*
X395133Y229686D01*
X394883Y229895D01*
X394550Y229978D01*
G01X396858Y229561D02*
X397108Y229811D01*
X397400Y229936D01*
X397733Y229978D01*
X398150Y229895D01*
X398442Y229686D01*
X398525Y229436D01*
X398483Y229186D01*
X398317Y228978D01*
X397483Y228561D01*
X397108Y228270D01*
X396858Y227853D01*
X396775Y227478D01*
X398525D01*
G01X365280Y247508D02*
Y243508D01*
X372680D01*
G01X380410Y235667D02*
Y238167D01*
X381451D01*
X381785Y238042D01*
X381993Y237875D01*
X382076Y237542D01*
X381993Y237209D01*
X381743Y237000D01*
X381451Y236875D01*
X380410D01*
G01X381451D02*
X382076Y235667D01*
G01X383635Y235959D02*
X383926Y235750D01*
X384260Y235667D01*
X384593Y235750D01*
X384885Y236000D01*
X385093Y236375D01*
X385176Y236750D01*
Y237209D01*
X385093Y237584D01*
X384885Y237917D01*
X384635Y238084D01*
X384343Y238167D01*
X384010Y238084D01*
X383760Y237917D01*
X383593Y237667D01*
X383510Y237334D01*
X383593Y237042D01*
X383801Y236750D01*
X384051Y236584D01*
X384343Y236542D01*
X384676Y236625D01*
X384926Y236834D01*
X385176Y237209D01*
G01X380328Y231460D02*
Y233960D01*
X381369D01*
X381703Y233835D01*
X381911Y233668D01*
X381994Y233335D01*
X381911Y233002D01*
X381661Y232793D01*
X381369Y232668D01*
X380328D01*
G01X381369D02*
X381994Y231460D01*
G01X384261D02*
X384553Y231502D01*
X384886Y231627D01*
X385094Y231835D01*
X385178Y232127D01*
X385094Y232418D01*
X384844Y232668D01*
X384469Y232793D01*
X384053D01*
X383803Y232877D01*
X383594Y233085D01*
X383511Y233377D01*
X383636Y233668D01*
X383928Y233877D01*
X384261Y233960D01*
X384594Y233877D01*
X384886Y233668D01*
X385011Y233377D01*
X384928Y233085D01*
X384719Y232877D01*
X384469Y232793D01*
X384053D01*
X383678Y232668D01*
X383428Y232418D01*
X383344Y232127D01*
X383428Y231835D01*
X383636Y231627D01*
X383969Y231502D01*
X384261Y231460D01*
G01X380617Y227478D02*
Y229978D01*
X381658D01*
X381992Y229853D01*
X382200Y229686D01*
X382283Y229353D01*
X382200Y229020D01*
X381950Y228811D01*
X381658Y228686D01*
X380617D01*
G01X381658D02*
X382283Y227478D01*
G01X384467D02*
X384550Y228020D01*
X384675Y228478D01*
X384842Y228895D01*
X385050Y229353D01*
X385383Y229978D01*
X383717D01*
G01X380617Y223478D02*
Y225978D01*
X381658D01*
X381992Y225853D01*
X382200Y225686D01*
X382283Y225353D01*
X382200Y225020D01*
X381950Y224811D01*
X381658Y224686D01*
X380617D01*
G01X381658D02*
X382283Y223478D01*
G01X383633Y223853D02*
X383883Y223645D01*
X384175Y223520D01*
X384550Y223478D01*
X384925Y223561D01*
X385217Y223728D01*
X385425Y224020D01*
X385467Y224353D01*
X385383Y224686D01*
X385175Y224895D01*
X384883Y225061D01*
X384592Y225103D01*
X384300Y225061D01*
X383925Y224895D01*
X384050Y225978D01*
X385175D01*
G01X379067Y243978D02*
Y246478D01*
X380108D01*
X380442Y246353D01*
X380650Y246186D01*
X380733Y245853D01*
X380650Y245520D01*
X380400Y245311D01*
X380108Y245186D01*
X379067D01*
G01X380108D02*
X380733Y243978D01*
G01X383000D02*
Y246478D01*
X382500Y245978D01*
G01Y243978D02*
X383500D01*
G01X385183Y244353D02*
X385433Y244145D01*
X385725Y244020D01*
X386100Y243978D01*
X386475Y244061D01*
X386767Y244228D01*
X386975Y244520D01*
X387017Y244853D01*
X386933Y245186D01*
X386725Y245395D01*
X386433Y245561D01*
X386142Y245603D01*
X385850Y245561D01*
X385475Y245395D01*
X385600Y246478D01*
X386725D01*
G01X379067Y239978D02*
Y242478D01*
X380108D01*
X380442Y242353D01*
X380650Y242186D01*
X380733Y241853D01*
X380650Y241520D01*
X380400Y241311D01*
X380108Y241186D01*
X379067D01*
G01X380108D02*
X380733Y239978D01*
G01X383000D02*
Y242478D01*
X382500Y241978D01*
G01Y239978D02*
X383500D01*
G01X386600D02*
Y242478D01*
X385058Y240686D01*
X387142D01*
G01X384517Y214978D02*
Y217478D01*
X385558D01*
X385892Y217353D01*
X386100Y217186D01*
X386183Y216853D01*
X386100Y216520D01*
X385850Y216311D01*
X385558Y216186D01*
X384517D01*
G01X385558D02*
X386183Y214978D01*
G01X388367D02*
X388450Y215520D01*
X388575Y215978D01*
X388742Y216395D01*
X388950Y216853D01*
X389283Y217478D01*
X387617D01*
G01X390758Y217061D02*
X391008Y217311D01*
X391300Y217436D01*
X391633Y217478D01*
X392050Y217395D01*
X392342Y217186D01*
X392425Y216936D01*
X392383Y216686D01*
X392217Y216478D01*
X391383Y216061D01*
X391008Y215770D01*
X390758Y215353D01*
X390675Y214978D01*
X392425D01*
G01X394567D02*
X394650Y215520D01*
X394775Y215978D01*
X394942Y216395D01*
X395150Y216853D01*
X395483Y217478D01*
X393817D01*
G01X360481Y227861D02*
Y223861D01*
X367881D01*
G01X361535Y213499D02*
X371535D01*
G01X384533Y219478D02*
Y221978D01*
X385367D01*
X385700Y221853D01*
X385950Y221686D01*
X386158Y221436D01*
X386325Y221145D01*
X386367Y220728D01*
X386325Y220311D01*
X386158Y220020D01*
X385950Y219770D01*
X385700Y219603D01*
X385367Y219478D01*
X384533D01*
G01X389050D02*
Y221978D01*
X387508Y220186D01*
X389592D01*
G01X387517Y223478D02*
Y225978D01*
X388558D01*
X388892Y225853D01*
X389100Y225686D01*
X389183Y225353D01*
X389100Y225020D01*
X388850Y224811D01*
X388558Y224686D01*
X387517D01*
G01X388558D02*
X389183Y223478D01*
G01X391367D02*
X391450Y224020D01*
X391575Y224478D01*
X391742Y224895D01*
X391950Y225353D01*
X392283Y225978D01*
X390617D01*
G01X394550Y223478D02*
Y225978D01*
X394050Y225478D01*
G01Y223478D02*
X395050D01*
G01X396942Y223770D02*
X397233Y223561D01*
X397567Y223478D01*
X397900Y223561D01*
X398192Y223811D01*
X398400Y224186D01*
X398483Y224561D01*
Y225020D01*
X398400Y225395D01*
X398192Y225728D01*
X397942Y225895D01*
X397650Y225978D01*
X397317Y225895D01*
X397067Y225728D01*
X396900Y225478D01*
X396817Y225145D01*
X396900Y224853D01*
X397108Y224561D01*
X397358Y224395D01*
X397650Y224353D01*
X397983Y224436D01*
X398233Y224645D01*
X398483Y225020D01*
G01X365280Y243308D02*
Y239308D01*
X372680D01*
G01X368317Y401792D02*
X368067Y401917D01*
X367775Y402000D01*
X367442D01*
X367067Y401875D01*
X366775Y401667D01*
X366567Y401417D01*
X366400Y401000D01*
X366358Y400625D01*
X366442Y400250D01*
X366567Y400000D01*
X366817Y399750D01*
X367108Y399583D01*
X367400Y399500D01*
X367692D01*
X367983Y399583D01*
X368233Y399708D01*
X368442Y399875D01*
G01X369583Y400000D02*
X369833Y399708D01*
X370167Y399542D01*
X370542Y399500D01*
X370875Y399542D01*
X371208Y399750D01*
X371417Y400000D01*
X371458Y400250D01*
X371375Y400542D01*
X371083Y400750D01*
X370792Y400833D01*
X370417D01*
G01X370792D02*
X371042Y400958D01*
X371250Y401167D01*
X371333Y401417D01*
X371250Y401667D01*
X371042Y401875D01*
X370667Y402000D01*
X370292Y401958D01*
X369917Y401792D01*
G01X372808Y401583D02*
X373058Y401833D01*
X373350Y401958D01*
X373683Y402000D01*
X374100Y401917D01*
X374392Y401708D01*
X374475Y401458D01*
X374433Y401208D01*
X374267Y401000D01*
X373433Y400583D01*
X373058Y400292D01*
X372808Y399875D01*
X372725Y399500D01*
X374475D01*
G01X399700Y385617D02*
X397200D01*
Y386658D01*
X397325Y386992D01*
X397492Y387200D01*
X397825Y387283D01*
X398158Y387200D01*
X398367Y386950D01*
X398492Y386658D01*
Y385617D01*
G01Y386658D02*
X399700Y387283D01*
G01Y389550D02*
X397200D01*
X397700Y389050D01*
G01X399700D02*
Y390050D01*
G01X399200Y391733D02*
X399492Y391983D01*
X399658Y392317D01*
X399700Y392692D01*
X399658Y393025D01*
X399450Y393358D01*
X399200Y393567D01*
X398950Y393608D01*
X398658Y393525D01*
X398450Y393233D01*
X398367Y392942D01*
Y392567D01*
G01Y392942D02*
X398242Y393192D01*
X398033Y393400D01*
X397783Y393483D01*
X397533Y393400D01*
X397325Y393192D01*
X397200Y392817D01*
X397242Y392442D01*
X397408Y392067D01*
G01X399700Y395750D02*
X399658Y396042D01*
X399533Y396375D01*
X399325Y396583D01*
X399033Y396667D01*
X398742Y396583D01*
X398492Y396333D01*
X398367Y395958D01*
Y395542D01*
X398283Y395292D01*
X398075Y395083D01*
X397783Y395000D01*
X397492Y395125D01*
X397283Y395417D01*
X397200Y395750D01*
X397283Y396083D01*
X397492Y396375D01*
X397783Y396500D01*
X398075Y396417D01*
X398283Y396208D01*
X398367Y395958D01*
Y395542D01*
X398492Y395167D01*
X398742Y394917D01*
X399033Y394833D01*
X399325Y394917D01*
X399533Y395125D01*
X399658Y395458D01*
X399700Y395750D01*
G01X399500Y398917D02*
X397000D01*
Y399958D01*
X397125Y400292D01*
X397292Y400500D01*
X397625Y400583D01*
X397958Y400500D01*
X398167Y400250D01*
X398292Y399958D01*
Y398917D01*
G01Y399958D02*
X399500Y400583D01*
G01Y402850D02*
X397000D01*
X397500Y402350D01*
G01X399500D02*
Y403350D01*
G01X399000Y405033D02*
X399292Y405283D01*
X399458Y405617D01*
X399500Y405992D01*
X399458Y406325D01*
X399250Y406658D01*
X399000Y406867D01*
X398750Y406908D01*
X398458Y406825D01*
X398250Y406533D01*
X398167Y406242D01*
Y405867D01*
G01Y406242D02*
X398042Y406492D01*
X397833Y406700D01*
X397583Y406783D01*
X397333Y406700D01*
X397125Y406492D01*
X397000Y406117D01*
X397042Y405742D01*
X397208Y405367D01*
G01X399500Y408967D02*
X398958Y409050D01*
X398500Y409175D01*
X398083Y409342D01*
X397625Y409550D01*
X397000Y409883D01*
Y408217D01*
G01X389817Y416200D02*
Y418700D01*
X390858D01*
X391192Y418575D01*
X391400Y418408D01*
X391483Y418075D01*
X391400Y417742D01*
X391150Y417533D01*
X390858Y417408D01*
X389817D01*
G01X390858D02*
X391483Y416200D01*
G01X393750D02*
Y418700D01*
X393250Y418200D01*
G01Y416200D02*
X394250D01*
G01X395933Y416700D02*
X396183Y416408D01*
X396517Y416242D01*
X396892Y416200D01*
X397225Y416242D01*
X397558Y416450D01*
X397767Y416700D01*
X397808Y416950D01*
X397725Y417242D01*
X397433Y417450D01*
X397142Y417533D01*
X396767D01*
G01X397142D02*
X397392Y417658D01*
X397600Y417867D01*
X397683Y418117D01*
X397600Y418367D01*
X397392Y418575D01*
X397017Y418700D01*
X396642Y418658D01*
X396267Y418492D01*
G01X399158Y417242D02*
X399450Y417533D01*
X399700Y417700D01*
X400033Y417783D01*
X400325Y417700D01*
X400533Y417533D01*
X400700Y417283D01*
X400742Y416992D01*
X400700Y416742D01*
X400533Y416492D01*
X400283Y416283D01*
X399992Y416200D01*
X399658Y416283D01*
X399367Y416533D01*
X399200Y416908D01*
X399158Y417325D01*
X399242Y417867D01*
X399367Y418158D01*
X399575Y418450D01*
X399867Y418658D01*
X400158Y418700D01*
X400450Y418617D01*
X400658Y418408D01*
G01X395700Y385617D02*
X393200D01*
Y386658D01*
X393325Y386992D01*
X393492Y387200D01*
X393825Y387283D01*
X394158Y387200D01*
X394367Y386950D01*
X394492Y386658D01*
Y385617D01*
G01Y386658D02*
X395700Y387283D01*
G01Y389550D02*
X393200D01*
X393700Y389050D01*
G01X395700D02*
Y390050D01*
G01X395200Y391733D02*
X395492Y391983D01*
X395658Y392317D01*
X395700Y392692D01*
X395658Y393025D01*
X395450Y393358D01*
X395200Y393567D01*
X394950Y393608D01*
X394658Y393525D01*
X394450Y393233D01*
X394367Y392942D01*
Y392567D01*
G01Y392942D02*
X394242Y393192D01*
X394033Y393400D01*
X393783Y393483D01*
X393533Y393400D01*
X393325Y393192D01*
X393200Y392817D01*
X393242Y392442D01*
X393408Y392067D01*
G01X395325Y394833D02*
X395533Y395083D01*
X395658Y395375D01*
X395700Y395750D01*
X395617Y396125D01*
X395450Y396417D01*
X395158Y396625D01*
X394825Y396667D01*
X394492Y396583D01*
X394283Y396375D01*
X394117Y396083D01*
X394075Y395792D01*
X394117Y395500D01*
X394283Y395125D01*
X393200Y395250D01*
Y396375D01*
G01X394900Y398717D02*
X392400D01*
Y399758D01*
X392525Y400092D01*
X392692Y400300D01*
X393025Y400383D01*
X393358Y400300D01*
X393567Y400050D01*
X393692Y399758D01*
Y398717D01*
G01Y399758D02*
X394900Y400383D01*
G01Y402650D02*
X392400D01*
X392900Y402150D01*
G01X394900D02*
Y403150D01*
G01X394400Y404833D02*
X394692Y405083D01*
X394858Y405417D01*
X394900Y405792D01*
X394858Y406125D01*
X394650Y406458D01*
X394400Y406667D01*
X394150Y406708D01*
X393858Y406625D01*
X393650Y406333D01*
X393567Y406042D01*
Y405667D01*
G01Y406042D02*
X393442Y406292D01*
X393233Y406500D01*
X392983Y406583D01*
X392733Y406500D01*
X392525Y406292D01*
X392400Y405917D01*
X392442Y405542D01*
X392608Y405167D01*
G01X394900Y409350D02*
X392400D01*
X394192Y407808D01*
Y409892D01*
G01X389817Y411700D02*
Y414200D01*
X390858D01*
X391192Y414075D01*
X391400Y413908D01*
X391483Y413575D01*
X391400Y413242D01*
X391150Y413033D01*
X390858Y412908D01*
X389817D01*
G01X390858D02*
X391483Y411700D01*
G01X393750D02*
Y414200D01*
X393250Y413700D01*
G01Y411700D02*
X394250D01*
G01X395933Y412200D02*
X396183Y411908D01*
X396517Y411742D01*
X396892Y411700D01*
X397225Y411742D01*
X397558Y411950D01*
X397767Y412200D01*
X397808Y412450D01*
X397725Y412742D01*
X397433Y412950D01*
X397142Y413033D01*
X396767D01*
G01X397142D02*
X397392Y413158D01*
X397600Y413367D01*
X397683Y413617D01*
X397600Y413867D01*
X397392Y414075D01*
X397017Y414200D01*
X396642Y414158D01*
X396267Y413992D01*
G01X399033Y412200D02*
X399283Y411908D01*
X399617Y411742D01*
X399992Y411700D01*
X400325Y411742D01*
X400658Y411950D01*
X400867Y412200D01*
X400908Y412450D01*
X400825Y412742D01*
X400533Y412950D01*
X400242Y413033D01*
X399867D01*
G01X400242D02*
X400492Y413158D01*
X400700Y413367D01*
X400783Y413617D01*
X400700Y413867D01*
X400492Y414075D01*
X400117Y414200D01*
X399742Y414158D01*
X399367Y413992D01*
G01X391600Y384717D02*
X389100D01*
Y385758D01*
X389225Y386092D01*
X389392Y386300D01*
X389725Y386383D01*
X390058Y386300D01*
X390267Y386050D01*
X390392Y385758D01*
Y384717D01*
G01Y385758D02*
X391600Y386383D01*
G01X391100Y387733D02*
X391392Y387983D01*
X391558Y388317D01*
X391600Y388692D01*
X391558Y389025D01*
X391350Y389358D01*
X391100Y389567D01*
X390850Y389608D01*
X390558Y389525D01*
X390350Y389233D01*
X390267Y388942D01*
Y388567D01*
G01Y388942D02*
X390142Y389192D01*
X389933Y389400D01*
X389683Y389483D01*
X389433Y389400D01*
X389225Y389192D01*
X389100Y388817D01*
X389142Y388442D01*
X389308Y388067D01*
G01X391600Y392250D02*
X389100D01*
X390892Y390708D01*
Y392792D01*
G01X391308Y394142D02*
X391517Y394433D01*
X391600Y394767D01*
X391517Y395100D01*
X391267Y395392D01*
X390892Y395600D01*
X390517Y395683D01*
X390058D01*
X389683Y395600D01*
X389350Y395392D01*
X389183Y395142D01*
X389100Y394850D01*
X389183Y394517D01*
X389350Y394267D01*
X389600Y394100D01*
X389933Y394017D01*
X390225Y394100D01*
X390517Y394308D01*
X390683Y394558D01*
X390725Y394850D01*
X390642Y395183D01*
X390433Y395433D01*
X390058Y395683D01*
G01X380000Y404067D02*
X377500D01*
Y405108D01*
X377625Y405442D01*
X377792Y405650D01*
X378125Y405733D01*
X378458Y405650D01*
X378667Y405400D01*
X378792Y405108D01*
Y404067D01*
G01Y405108D02*
X380000Y405733D01*
G01X379708Y407292D02*
X379917Y407583D01*
X380000Y407917D01*
X379917Y408250D01*
X379667Y408542D01*
X379292Y408750D01*
X378917Y408833D01*
X378458D01*
X378083Y408750D01*
X377750Y408542D01*
X377583Y408292D01*
X377500Y408000D01*
X377583Y407667D01*
X377750Y407417D01*
X378000Y407250D01*
X378333Y407167D01*
X378625Y407250D01*
X378917Y407458D01*
X379083Y407708D01*
X379125Y408000D01*
X379042Y408333D01*
X378833Y408583D01*
X378458Y408833D01*
G01X379625Y410183D02*
X379833Y410433D01*
X379958Y410725D01*
X380000Y411100D01*
X379917Y411475D01*
X379750Y411767D01*
X379458Y411975D01*
X379125Y412017D01*
X378792Y411933D01*
X378583Y411725D01*
X378417Y411433D01*
X378375Y411142D01*
X378417Y410850D01*
X378583Y410475D01*
X377500Y410600D01*
Y411725D01*
G01X375000Y404067D02*
X372500D01*
Y405108D01*
X372625Y405442D01*
X372792Y405650D01*
X373125Y405733D01*
X373458Y405650D01*
X373667Y405400D01*
X373792Y405108D01*
Y404067D01*
G01Y405108D02*
X375000Y405733D01*
G01X374500Y407083D02*
X374792Y407333D01*
X374958Y407667D01*
X375000Y408042D01*
X374958Y408375D01*
X374750Y408708D01*
X374500Y408917D01*
X374250Y408958D01*
X373958Y408875D01*
X373750Y408583D01*
X373667Y408292D01*
Y407917D01*
G01Y408292D02*
X373542Y408542D01*
X373333Y408750D01*
X373083Y408833D01*
X372833Y408750D01*
X372625Y408542D01*
X372500Y408167D01*
X372542Y407792D01*
X372708Y407417D01*
G01X374708Y410392D02*
X374917Y410683D01*
X375000Y411017D01*
X374917Y411350D01*
X374667Y411642D01*
X374292Y411850D01*
X373917Y411933D01*
X373458D01*
X373083Y411850D01*
X372750Y411642D01*
X372583Y411392D01*
X372500Y411100D01*
X372583Y410767D01*
X372750Y410517D01*
X373000Y410350D01*
X373333Y410267D01*
X373625Y410350D01*
X373917Y410558D01*
X374083Y410808D01*
X374125Y411100D01*
X374042Y411433D01*
X373833Y411683D01*
X373458Y411933D01*
G01X377517Y399500D02*
Y402000D01*
X378558D01*
X378892Y401875D01*
X379100Y401708D01*
X379183Y401375D01*
X379100Y401042D01*
X378850Y400833D01*
X378558Y400708D01*
X377517D01*
G01X378558D02*
X379183Y399500D01*
G01X381450D02*
Y402000D01*
X380950Y401500D01*
G01Y399500D02*
X381950D01*
G01X384550Y402000D02*
X384217Y401917D01*
X383967Y401708D01*
X383800Y401458D01*
X383675Y401125D01*
X383633Y400750D01*
X383675Y400375D01*
X383800Y400042D01*
X383967Y399792D01*
X384217Y399583D01*
X384550Y399500D01*
X384883Y399583D01*
X385133Y399792D01*
X385300Y400042D01*
X385425Y400375D01*
X385467Y400750D01*
X385425Y401125D01*
X385300Y401458D01*
X385133Y401708D01*
X384883Y401917D01*
X384550Y402000D01*
G01X386858Y401583D02*
X387108Y401833D01*
X387400Y401958D01*
X387733Y402000D01*
X388150Y401917D01*
X388442Y401708D01*
X388525Y401458D01*
X388483Y401208D01*
X388317Y401000D01*
X387483Y400583D01*
X387108Y400292D01*
X386858Y399875D01*
X386775Y399500D01*
X388525D01*
G01X360383Y408200D02*
Y406408D01*
X360550Y406033D01*
X360883Y405783D01*
X361300Y405700D01*
X361717Y405783D01*
X362050Y406033D01*
X362217Y406408D01*
Y408200D01*
G01X364400Y405700D02*
Y408200D01*
X363900Y407700D01*
G01Y405700D02*
X364900D01*
G01X366792Y405992D02*
X367083Y405783D01*
X367417Y405700D01*
X367750Y405783D01*
X368042Y406033D01*
X368250Y406408D01*
X368333Y406783D01*
Y407242D01*
X368250Y407617D01*
X368042Y407950D01*
X367792Y408117D01*
X367500Y408200D01*
X367167Y408117D01*
X366917Y407950D01*
X366750Y407700D01*
X366667Y407367D01*
X366750Y407075D01*
X366958Y406783D01*
X367208Y406617D01*
X367500Y406575D01*
X367833Y406658D01*
X368083Y406867D01*
X368333Y407242D01*
G01X384748Y456590D02*
X384498Y456715D01*
X384206Y456798D01*
X383873D01*
X383498Y456673D01*
X383206Y456465D01*
X382998Y456215D01*
X382831Y455798D01*
X382789Y455423D01*
X382873Y455048D01*
X382998Y454798D01*
X383248Y454548D01*
X383539Y454381D01*
X383831Y454298D01*
X384123D01*
X384414Y454381D01*
X384664Y454506D01*
X384873Y454673D01*
G01X386931Y454298D02*
Y456798D01*
X386431Y456298D01*
G01Y454298D02*
X387431D01*
G01X389239Y456381D02*
X389489Y456631D01*
X389781Y456756D01*
X390114Y456798D01*
X390531Y456715D01*
X390823Y456506D01*
X390906Y456256D01*
X390864Y456006D01*
X390698Y455798D01*
X389864Y455381D01*
X389489Y455090D01*
X389239Y454673D01*
X389156Y454298D01*
X390906D01*
G01X393048D02*
X393131Y454840D01*
X393256Y455298D01*
X393423Y455715D01*
X393631Y456173D01*
X393964Y456798D01*
X392298D01*
G01X380015Y490071D02*
X379890Y489821D01*
X379807Y489529D01*
Y489196D01*
X379932Y488821D01*
X380140Y488529D01*
X380390Y488321D01*
X380807Y488154D01*
X381182Y488112D01*
X381557Y488196D01*
X381807Y488321D01*
X382057Y488571D01*
X382224Y488862D01*
X382307Y489154D01*
Y489446D01*
X382224Y489737D01*
X382099Y489987D01*
X381932Y490196D01*
G01Y491337D02*
X382140Y491587D01*
X382265Y491879D01*
X382307Y492254D01*
X382224Y492629D01*
X382057Y492921D01*
X381765Y493129D01*
X381432Y493171D01*
X381099Y493087D01*
X380890Y492879D01*
X380724Y492587D01*
X380682Y492296D01*
X380724Y492004D01*
X380890Y491629D01*
X379807Y491754D01*
Y492879D01*
G01X380224Y494562D02*
X379974Y494812D01*
X379849Y495104D01*
X379807Y495437D01*
X379890Y495854D01*
X380099Y496146D01*
X380349Y496229D01*
X380599Y496187D01*
X380807Y496021D01*
X381224Y495187D01*
X381515Y494812D01*
X381932Y494562D01*
X382307Y494479D01*
Y496229D01*
G01X380224Y497662D02*
X379974Y497912D01*
X379849Y498204D01*
X379807Y498537D01*
X379890Y498954D01*
X380099Y499246D01*
X380349Y499329D01*
X380599Y499287D01*
X380807Y499121D01*
X381224Y498287D01*
X381515Y497912D01*
X381932Y497662D01*
X382307Y497579D01*
Y499329D01*
G01X389400Y460667D02*
X386900D01*
Y461708D01*
X387025Y462042D01*
X387192Y462250D01*
X387525Y462333D01*
X387858Y462250D01*
X388067Y462000D01*
X388192Y461708D01*
Y460667D01*
G01Y461708D02*
X389400Y462333D01*
G01X387317Y463808D02*
X387067Y464058D01*
X386942Y464350D01*
X386900Y464683D01*
X386983Y465100D01*
X387192Y465392D01*
X387442Y465475D01*
X387692Y465433D01*
X387900Y465267D01*
X388317Y464433D01*
X388608Y464058D01*
X389025Y463808D01*
X389400Y463725D01*
Y465475D01*
G01X389025Y466783D02*
X389233Y467033D01*
X389358Y467325D01*
X389400Y467700D01*
X389317Y468075D01*
X389150Y468367D01*
X388858Y468575D01*
X388525Y468617D01*
X388192Y468533D01*
X387983Y468325D01*
X387817Y468033D01*
X387775Y467742D01*
X387817Y467450D01*
X387983Y467075D01*
X386900Y467200D01*
Y468325D01*
G01X387633Y424817D02*
X385133D01*
Y425858D01*
X385258Y426192D01*
X385425Y426400D01*
X385758Y426483D01*
X386091Y426400D01*
X386300Y426150D01*
X386425Y425858D01*
Y424817D01*
G01Y425858D02*
X387633Y426483D01*
G01X385550Y427958D02*
X385300Y428208D01*
X385175Y428500D01*
X385133Y428833D01*
X385216Y429250D01*
X385425Y429542D01*
X385675Y429625D01*
X385925Y429583D01*
X386133Y429417D01*
X386550Y428583D01*
X386841Y428208D01*
X387258Y427958D01*
X387633Y427875D01*
Y429625D01*
G01Y431767D02*
X387091Y431850D01*
X386633Y431975D01*
X386216Y432142D01*
X385758Y432350D01*
X385133Y432683D01*
Y431017D01*
G01X386591Y434158D02*
X386300Y434450D01*
X386133Y434700D01*
X386050Y435033D01*
X386133Y435325D01*
X386300Y435533D01*
X386550Y435700D01*
X386841Y435742D01*
X387091Y435700D01*
X387341Y435533D01*
X387550Y435283D01*
X387633Y434992D01*
X387550Y434658D01*
X387300Y434367D01*
X386925Y434200D01*
X386508Y434158D01*
X385966Y434242D01*
X385675Y434367D01*
X385383Y434575D01*
X385175Y434867D01*
X385133Y435158D01*
X385216Y435450D01*
X385425Y435658D01*
G01X391734Y425117D02*
X389234D01*
Y426158D01*
X389359Y426492D01*
X389526Y426700D01*
X389859Y426783D01*
X390192Y426700D01*
X390401Y426450D01*
X390526Y426158D01*
Y425117D01*
G01Y426158D02*
X391734Y426783D01*
G01Y429550D02*
X389234D01*
X391026Y428008D01*
Y430092D01*
G01X389651Y431358D02*
X389401Y431608D01*
X389276Y431900D01*
X389234Y432233D01*
X389317Y432650D01*
X389526Y432942D01*
X389776Y433025D01*
X390026Y432983D01*
X390234Y432817D01*
X390651Y431983D01*
X390942Y431608D01*
X391359Y431358D01*
X391734Y431275D01*
Y433025D01*
G01X391234Y434333D02*
X391526Y434583D01*
X391692Y434917D01*
X391734Y435292D01*
X391692Y435625D01*
X391484Y435958D01*
X391234Y436167D01*
X390984Y436208D01*
X390692Y436125D01*
X390484Y435833D01*
X390401Y435542D01*
Y435167D01*
G01Y435542D02*
X390276Y435792D01*
X390067Y436000D01*
X389817Y436083D01*
X389567Y436000D01*
X389359Y435792D01*
X389234Y435417D01*
X389276Y435042D01*
X389442Y434667D01*
G01X363717Y461900D02*
Y464400D01*
X364758D01*
X365092Y464275D01*
X365300Y464108D01*
X365383Y463775D01*
X365300Y463442D01*
X365050Y463233D01*
X364758Y463108D01*
X363717D01*
G01X364758D02*
X365383Y461900D01*
G01X368150D02*
Y464400D01*
X366608Y462608D01*
X368692D01*
G01X369958Y463983D02*
X370208Y464233D01*
X370500Y464358D01*
X370833Y464400D01*
X371250Y464317D01*
X371542Y464108D01*
X371625Y463858D01*
X371583Y463608D01*
X371417Y463400D01*
X370583Y462983D01*
X370208Y462692D01*
X369958Y462275D01*
X369875Y461900D01*
X371625D01*
G01X373058Y463983D02*
X373308Y464233D01*
X373600Y464358D01*
X373933Y464400D01*
X374350Y464317D01*
X374642Y464108D01*
X374725Y463858D01*
X374683Y463608D01*
X374517Y463400D01*
X373683Y462983D01*
X373308Y462692D01*
X373058Y462275D01*
X372975Y461900D01*
X374725D01*
G01X397000Y460767D02*
X394500D01*
Y461808D01*
X394625Y462142D01*
X394792Y462350D01*
X395125Y462433D01*
X395458Y462350D01*
X395667Y462100D01*
X395792Y461808D01*
Y460767D01*
G01Y461808D02*
X397000Y462433D01*
G01Y465200D02*
X394500D01*
X396292Y463658D01*
Y465742D01*
G01X397000Y467800D02*
X394500D01*
X395000Y467300D01*
G01X397000D02*
Y468300D01*
G01X401200Y460267D02*
X398700D01*
Y461308D01*
X398825Y461642D01*
X398992Y461850D01*
X399325Y461933D01*
X399658Y461850D01*
X399867Y461600D01*
X399992Y461308D01*
Y460267D01*
G01Y461308D02*
X401200Y461933D01*
G01X400700Y463283D02*
X400992Y463533D01*
X401158Y463867D01*
X401200Y464242D01*
X401158Y464575D01*
X400950Y464908D01*
X400700Y465117D01*
X400450Y465158D01*
X400158Y465075D01*
X399950Y464783D01*
X399867Y464492D01*
Y464117D01*
G01Y464492D02*
X399742Y464742D01*
X399533Y464950D01*
X399283Y465033D01*
X399033Y464950D01*
X398825Y464742D01*
X398700Y464367D01*
X398742Y463992D01*
X398908Y463617D01*
G01X401200Y467800D02*
X398700D01*
X400492Y466258D01*
Y468342D01*
G01X381000Y460267D02*
X378500D01*
Y461308D01*
X378625Y461642D01*
X378792Y461850D01*
X379125Y461933D01*
X379458Y461850D01*
X379667Y461600D01*
X379792Y461308D01*
Y460267D01*
G01Y461308D02*
X381000Y461933D01*
G01X380500Y463283D02*
X380792Y463533D01*
X380958Y463867D01*
X381000Y464242D01*
X380958Y464575D01*
X380750Y464908D01*
X380500Y465117D01*
X380250Y465158D01*
X379958Y465075D01*
X379750Y464783D01*
X379667Y464492D01*
Y464117D01*
G01Y464492D02*
X379542Y464742D01*
X379333Y464950D01*
X379083Y465033D01*
X378833Y464950D01*
X378625Y464742D01*
X378500Y464367D01*
X378542Y463992D01*
X378708Y463617D01*
G01X380500Y466383D02*
X380792Y466633D01*
X380958Y466967D01*
X381000Y467342D01*
X380958Y467675D01*
X380750Y468008D01*
X380500Y468217D01*
X380250Y468258D01*
X379958Y468175D01*
X379750Y467883D01*
X379667Y467592D01*
Y467217D01*
G01Y467592D02*
X379542Y467842D01*
X379333Y468050D01*
X379083Y468133D01*
X378833Y468050D01*
X378625Y467842D01*
X378500Y467467D01*
X378542Y467092D01*
X378708Y466717D01*
G01X404900Y460267D02*
X402400D01*
Y461308D01*
X402525Y461642D01*
X402692Y461850D01*
X403025Y461933D01*
X403358Y461850D01*
X403567Y461600D01*
X403692Y461308D01*
Y460267D01*
G01Y461308D02*
X404900Y461933D01*
G01X402817Y463408D02*
X402567Y463658D01*
X402442Y463950D01*
X402400Y464283D01*
X402483Y464700D01*
X402692Y464992D01*
X402942Y465075D01*
X403192Y465033D01*
X403400Y464867D01*
X403817Y464033D01*
X404108Y463658D01*
X404525Y463408D01*
X404900Y463325D01*
Y465075D01*
G01X404608Y466592D02*
X404817Y466883D01*
X404900Y467217D01*
X404817Y467550D01*
X404567Y467842D01*
X404192Y468050D01*
X403817Y468133D01*
X403358D01*
X402983Y468050D01*
X402650Y467842D01*
X402483Y467592D01*
X402400Y467300D01*
X402483Y466967D01*
X402650Y466717D01*
X402900Y466550D01*
X403233Y466467D01*
X403525Y466550D01*
X403817Y466758D01*
X403983Y467008D01*
X404025Y467300D01*
X403942Y467633D01*
X403733Y467883D01*
X403358Y468133D01*
G01X383649Y438169D02*
Y440669D01*
X384690D01*
X385024Y440544D01*
X385232Y440377D01*
X385315Y440044D01*
X385232Y439711D01*
X384982Y439502D01*
X384690Y439377D01*
X383649D01*
G01X384690D02*
X385315Y438169D01*
G01X388082D02*
Y440669D01*
X386540Y438877D01*
X388624D01*
G01X389890Y440252D02*
X390140Y440502D01*
X390432Y440627D01*
X390765Y440669D01*
X391182Y440586D01*
X391474Y440377D01*
X391557Y440127D01*
X391515Y439877D01*
X391349Y439669D01*
X390515Y439252D01*
X390140Y438961D01*
X389890Y438544D01*
X389807Y438169D01*
X391557D01*
G01X393782D02*
X394074Y438211D01*
X394407Y438336D01*
X394615Y438544D01*
X394699Y438836D01*
X394615Y439127D01*
X394365Y439377D01*
X393990Y439502D01*
X393574D01*
X393324Y439586D01*
X393115Y439794D01*
X393032Y440086D01*
X393157Y440377D01*
X393449Y440586D01*
X393782Y440669D01*
X394115Y440586D01*
X394407Y440377D01*
X394532Y440086D01*
X394449Y439794D01*
X394240Y439586D01*
X393990Y439502D01*
X393574D01*
X393199Y439377D01*
X392949Y439127D01*
X392865Y438836D01*
X392949Y438544D01*
X393157Y438336D01*
X393490Y438211D01*
X393782Y438169D01*
G01X385580Y460531D02*
X383080D01*
Y461572D01*
X383205Y461906D01*
X383372Y462114D01*
X383705Y462197D01*
X384038Y462114D01*
X384247Y461864D01*
X384372Y461572D01*
Y460531D01*
G01Y461572D02*
X385580Y462197D01*
G01X383497Y463672D02*
X383247Y463922D01*
X383122Y464214D01*
X383080Y464547D01*
X383163Y464964D01*
X383372Y465256D01*
X383622Y465339D01*
X383872Y465297D01*
X384080Y465131D01*
X384497Y464297D01*
X384788Y463922D01*
X385205Y463672D01*
X385580Y463589D01*
Y465339D01*
G01Y468064D02*
X383080D01*
X384872Y466522D01*
Y468606D01*
G01X384154Y442427D02*
Y444927D01*
X385195D01*
X385529Y444802D01*
X385737Y444635D01*
X385820Y444302D01*
X385737Y443969D01*
X385487Y443760D01*
X385195Y443635D01*
X384154D01*
G01X385195D02*
X385820Y442427D01*
G01X388587D02*
Y444927D01*
X387045Y443135D01*
X389129D01*
G01X390395Y444510D02*
X390645Y444760D01*
X390937Y444885D01*
X391270Y444927D01*
X391687Y444844D01*
X391979Y444635D01*
X392062Y444385D01*
X392020Y444135D01*
X391854Y443927D01*
X391020Y443510D01*
X390645Y443219D01*
X390395Y442802D01*
X390312Y442427D01*
X392062D01*
G01X394204D02*
X394287Y442969D01*
X394412Y443427D01*
X394579Y443844D01*
X394787Y444302D01*
X395120Y444927D01*
X393454D01*
G01X382998Y450698D02*
Y453198D01*
X384039D01*
X384373Y453073D01*
X384581Y452906D01*
X384664Y452573D01*
X384581Y452240D01*
X384331Y452031D01*
X384039Y451906D01*
X382998D01*
G01X384039D02*
X384664Y450698D01*
G01X387431D02*
Y453198D01*
X385889Y451406D01*
X387973D01*
G01X389239Y452781D02*
X389489Y453031D01*
X389781Y453156D01*
X390114Y453198D01*
X390531Y453115D01*
X390823Y452906D01*
X390906Y452656D01*
X390864Y452406D01*
X390698Y452198D01*
X389864Y451781D01*
X389489Y451490D01*
X389239Y451073D01*
X389156Y450698D01*
X390906D01*
G01X392339Y451740D02*
X392631Y452031D01*
X392881Y452198D01*
X393214Y452281D01*
X393506Y452198D01*
X393714Y452031D01*
X393881Y451781D01*
X393923Y451490D01*
X393881Y451240D01*
X393714Y450990D01*
X393464Y450781D01*
X393173Y450698D01*
X392839Y450781D01*
X392548Y451031D01*
X392381Y451406D01*
X392339Y451823D01*
X392423Y452365D01*
X392548Y452656D01*
X392756Y452948D01*
X393048Y453156D01*
X393339Y453198D01*
X393631Y453115D01*
X393839Y452906D01*
G01X358188Y437232D02*
Y439732D01*
X359229D01*
X359563Y439607D01*
X359771Y439440D01*
X359854Y439107D01*
X359771Y438774D01*
X359521Y438565D01*
X359229Y438440D01*
X358188D01*
G01X359229D02*
X359854Y437232D01*
G01X361204Y437732D02*
X361454Y437440D01*
X361788Y437274D01*
X362163Y437232D01*
X362496Y437274D01*
X362829Y437482D01*
X363038Y437732D01*
X363079Y437982D01*
X362996Y438274D01*
X362704Y438482D01*
X362413Y438565D01*
X362038D01*
G01X362413D02*
X362663Y438690D01*
X362871Y438899D01*
X362954Y439149D01*
X362871Y439399D01*
X362663Y439607D01*
X362288Y439732D01*
X361913Y439690D01*
X361538Y439524D01*
G01X364429Y439315D02*
X364679Y439565D01*
X364971Y439690D01*
X365304Y439732D01*
X365721Y439649D01*
X366013Y439440D01*
X366096Y439190D01*
X366054Y438940D01*
X365888Y438732D01*
X365054Y438315D01*
X364679Y438024D01*
X364429Y437607D01*
X364346Y437232D01*
X366096D01*
G01X367613Y437524D02*
X367904Y437315D01*
X368238Y437232D01*
X368571Y437315D01*
X368863Y437565D01*
X369071Y437940D01*
X369154Y438315D01*
Y438774D01*
X369071Y439149D01*
X368863Y439482D01*
X368613Y439649D01*
X368321Y439732D01*
X367988Y439649D01*
X367738Y439482D01*
X367571Y439232D01*
X367488Y438899D01*
X367571Y438607D01*
X367779Y438315D01*
X368029Y438149D01*
X368321Y438107D01*
X368654Y438190D01*
X368904Y438399D01*
X369154Y438774D01*
G01X358109Y433228D02*
Y435728D01*
X359150D01*
X359484Y435603D01*
X359692Y435436D01*
X359775Y435103D01*
X359692Y434770D01*
X359442Y434561D01*
X359150Y434436D01*
X358109D01*
G01X359150D02*
X359775Y433228D01*
G01X361250Y434270D02*
X361542Y434561D01*
X361792Y434728D01*
X362125Y434811D01*
X362417Y434728D01*
X362625Y434561D01*
X362792Y434311D01*
X362834Y434020D01*
X362792Y433770D01*
X362625Y433520D01*
X362375Y433311D01*
X362084Y433228D01*
X361750Y433311D01*
X361459Y433561D01*
X361292Y433936D01*
X361250Y434353D01*
X361334Y434895D01*
X361459Y435186D01*
X361667Y435478D01*
X361959Y435686D01*
X362250Y435728D01*
X362542Y435645D01*
X362750Y435436D01*
G01X365142Y433228D02*
Y435728D01*
X364642Y435228D01*
G01Y433228D02*
X365642D01*
G01X368159D02*
X368242Y433770D01*
X368367Y434228D01*
X368534Y434645D01*
X368742Y435103D01*
X369075Y435728D01*
X367409D01*
G01X371017Y472100D02*
Y474600D01*
X372058D01*
X372392Y474475D01*
X372600Y474308D01*
X372683Y473975D01*
X372600Y473642D01*
X372350Y473433D01*
X372058Y473308D01*
X371017D01*
G01X372058D02*
X372683Y472100D01*
G01X374867D02*
X374950Y472642D01*
X375075Y473100D01*
X375242Y473517D01*
X375450Y473975D01*
X375783Y474600D01*
X374117D01*
G01X377342Y472392D02*
X377633Y472183D01*
X377967Y472100D01*
X378300Y472183D01*
X378592Y472433D01*
X378800Y472808D01*
X378883Y473183D01*
Y473642D01*
X378800Y474017D01*
X378592Y474350D01*
X378342Y474517D01*
X378050Y474600D01*
X377717Y474517D01*
X377467Y474350D01*
X377300Y474100D01*
X377217Y473767D01*
X377300Y473475D01*
X377508Y473183D01*
X377758Y473017D01*
X378050Y472975D01*
X378383Y473058D01*
X378633Y473267D01*
X378883Y473642D01*
G01X381067Y472100D02*
X381150Y472642D01*
X381275Y473100D01*
X381442Y473517D01*
X381650Y473975D01*
X381983Y474600D01*
X380317D01*
G01X362261Y477491D02*
Y473491D01*
X369661D01*
G01X357602Y482368D02*
Y478368D01*
X365002D01*
G01X358517Y445000D02*
Y447500D01*
X359558D01*
X359892Y447375D01*
X360100Y447208D01*
X360183Y446875D01*
X360100Y446542D01*
X359850Y446333D01*
X359558Y446208D01*
X358517D01*
G01X359558D02*
X360183Y445000D01*
G01X362450D02*
Y447500D01*
X361950Y447000D01*
G01Y445000D02*
X362950D01*
G01X364633Y445500D02*
X364883Y445208D01*
X365217Y445042D01*
X365592Y445000D01*
X365925Y445042D01*
X366258Y445250D01*
X366467Y445500D01*
X366508Y445750D01*
X366425Y446042D01*
X366133Y446250D01*
X365842Y446333D01*
X365467D01*
G01X365842D02*
X366092Y446458D01*
X366300Y446667D01*
X366383Y446917D01*
X366300Y447167D01*
X366092Y447375D01*
X365717Y447500D01*
X365342Y447458D01*
X364967Y447292D01*
G01X368650Y445000D02*
Y447500D01*
X368150Y447000D01*
G01Y445000D02*
X369150D01*
G01X361917Y449000D02*
Y451500D01*
X362958D01*
X363292Y451375D01*
X363500Y451208D01*
X363583Y450875D01*
X363500Y450542D01*
X363250Y450333D01*
X362958Y450208D01*
X361917D01*
G01X362958D02*
X363583Y449000D01*
G01X365850D02*
Y451500D01*
X365350Y451000D01*
G01Y449000D02*
X366350D01*
G01X368033Y449500D02*
X368283Y449208D01*
X368617Y449042D01*
X368992Y449000D01*
X369325Y449042D01*
X369658Y449250D01*
X369867Y449500D01*
X369908Y449750D01*
X369825Y450042D01*
X369533Y450250D01*
X369242Y450333D01*
X368867D01*
G01X369242D02*
X369492Y450458D01*
X369700Y450667D01*
X369783Y450917D01*
X369700Y451167D01*
X369492Y451375D01*
X369117Y451500D01*
X368742Y451458D01*
X368367Y451292D01*
G01X372050Y451500D02*
X371717Y451417D01*
X371467Y451208D01*
X371300Y450958D01*
X371175Y450625D01*
X371133Y450250D01*
X371175Y449875D01*
X371300Y449542D01*
X371467Y449292D01*
X371717Y449083D01*
X372050Y449000D01*
X372383Y449083D01*
X372633Y449292D01*
X372800Y449542D01*
X372925Y449875D01*
X372967Y450250D01*
X372925Y450625D01*
X372800Y450958D01*
X372633Y451208D01*
X372383Y451417D01*
X372050Y451500D01*
G01X358314Y441278D02*
Y443778D01*
X359355D01*
X359689Y443653D01*
X359897Y443486D01*
X359980Y443153D01*
X359897Y442820D01*
X359647Y442611D01*
X359355Y442486D01*
X358314D01*
G01X359355D02*
X359980Y441278D01*
G01X362247D02*
Y443778D01*
X361747Y443278D01*
G01Y441278D02*
X362747D01*
G01X364430Y441778D02*
X364680Y441486D01*
X365014Y441320D01*
X365389Y441278D01*
X365722Y441320D01*
X366055Y441528D01*
X366264Y441778D01*
X366305Y442028D01*
X366222Y442320D01*
X365930Y442528D01*
X365639Y442611D01*
X365264D01*
G01X365639D02*
X365889Y442736D01*
X366097Y442945D01*
X366180Y443195D01*
X366097Y443445D01*
X365889Y443653D01*
X365514Y443778D01*
X365139Y443736D01*
X364764Y443570D01*
G01X367655Y443361D02*
X367905Y443611D01*
X368197Y443736D01*
X368530Y443778D01*
X368947Y443695D01*
X369239Y443486D01*
X369322Y443236D01*
X369280Y442986D01*
X369114Y442778D01*
X368280Y442361D01*
X367905Y442070D01*
X367655Y441653D01*
X367572Y441278D01*
X369322D01*
G01X359217Y452500D02*
Y455000D01*
X360258D01*
X360592Y454875D01*
X360800Y454708D01*
X360883Y454375D01*
X360800Y454042D01*
X360550Y453833D01*
X360258Y453708D01*
X359217D01*
G01X360258D02*
X360883Y452500D01*
G01X363150D02*
Y455000D01*
X362650Y454500D01*
G01Y452500D02*
X363650D01*
G01X365458Y454583D02*
X365708Y454833D01*
X366000Y454958D01*
X366333Y455000D01*
X366750Y454917D01*
X367042Y454708D01*
X367125Y454458D01*
X367083Y454208D01*
X366917Y454000D01*
X366083Y453583D01*
X365708Y453292D01*
X365458Y452875D01*
X365375Y452500D01*
X367125D01*
G01X368642Y452792D02*
X368933Y452583D01*
X369267Y452500D01*
X369600Y452583D01*
X369892Y452833D01*
X370100Y453208D01*
X370183Y453583D01*
Y454042D01*
X370100Y454417D01*
X369892Y454750D01*
X369642Y454917D01*
X369350Y455000D01*
X369017Y454917D01*
X368767Y454750D01*
X368600Y454500D01*
X368517Y454167D01*
X368600Y453875D01*
X368808Y453583D01*
X369058Y453417D01*
X369350Y453375D01*
X369683Y453458D01*
X369933Y453667D01*
X370183Y454042D01*
G01X361481Y489866D02*
X357481D01*
Y482466D01*
G01X362767Y465900D02*
Y468400D01*
X363808D01*
X364142Y468275D01*
X364350Y468108D01*
X364433Y467775D01*
X364350Y467442D01*
X364100Y467233D01*
X363808Y467108D01*
X362767D01*
G01X363808D02*
X364433Y465900D01*
G01X365992Y466192D02*
X366283Y465983D01*
X366617Y465900D01*
X366950Y465983D01*
X367242Y466233D01*
X367450Y466608D01*
X367533Y466983D01*
Y467442D01*
X367450Y467817D01*
X367242Y468150D01*
X366992Y468317D01*
X366700Y468400D01*
X366367Y468317D01*
X366117Y468150D01*
X365950Y467900D01*
X365867Y467567D01*
X365950Y467275D01*
X366158Y466983D01*
X366408Y466817D01*
X366700Y466775D01*
X367033Y466858D01*
X367283Y467067D01*
X367533Y467442D01*
G01X368883Y466400D02*
X369133Y466108D01*
X369467Y465942D01*
X369842Y465900D01*
X370175Y465942D01*
X370508Y466150D01*
X370717Y466400D01*
X370758Y466650D01*
X370675Y466942D01*
X370383Y467150D01*
X370092Y467233D01*
X369717D01*
G01X370092D02*
X370342Y467358D01*
X370550Y467567D01*
X370633Y467817D01*
X370550Y468067D01*
X370342Y468275D01*
X369967Y468400D01*
X369592Y468358D01*
X369217Y468192D01*
G01X383457Y488637D02*
X385249D01*
X385624Y488804D01*
X385874Y489137D01*
X385957Y489554D01*
X385874Y489971D01*
X385624Y490304D01*
X385249Y490471D01*
X383457D01*
G01X385957Y493154D02*
X383457D01*
X385249Y491612D01*
Y493696D01*
G01X384915Y494962D02*
X384624Y495254D01*
X384457Y495504D01*
X384374Y495837D01*
X384457Y496129D01*
X384624Y496337D01*
X384874Y496504D01*
X385165Y496546D01*
X385415Y496504D01*
X385665Y496337D01*
X385874Y496087D01*
X385957Y495796D01*
X385874Y495462D01*
X385624Y495171D01*
X385249Y495004D01*
X384832Y494962D01*
X384290Y495046D01*
X383999Y495171D01*
X383707Y495379D01*
X383499Y495671D01*
X383457Y495962D01*
X383540Y496254D01*
X383749Y496462D01*
G01X377700Y497200D02*
Y483800D01*
G01X367700D02*
Y497200D01*
G01X377700Y483800D02*
X367700D01*
G01X390828Y462503D02*
X390703Y462253D01*
X390620Y461961D01*
Y461628D01*
X390745Y461253D01*
X390953Y460961D01*
X391203Y460753D01*
X391620Y460586D01*
X391995Y460544D01*
X392370Y460628D01*
X392620Y460753D01*
X392870Y461003D01*
X393037Y461294D01*
X393120Y461586D01*
Y461878D01*
X393037Y462169D01*
X392912Y462419D01*
X392745Y462628D01*
G01X393120Y464686D02*
X390620D01*
X391120Y464186D01*
G01X393120D02*
Y465186D01*
G01Y467786D02*
X393078Y468078D01*
X392953Y468411D01*
X392745Y468619D01*
X392453Y468703D01*
X392162Y468619D01*
X391912Y468369D01*
X391787Y467994D01*
Y467578D01*
X391703Y467328D01*
X391495Y467119D01*
X391203Y467036D01*
X390912Y467161D01*
X390703Y467453D01*
X390620Y467786D01*
X390703Y468119D01*
X390912Y468411D01*
X391203Y468536D01*
X391495Y468453D01*
X391703Y468244D01*
X391787Y467994D01*
Y467578D01*
X391912Y467203D01*
X392162Y466953D01*
X392453Y466869D01*
X392745Y466953D01*
X392953Y467161D01*
X393078Y467494D01*
X393120Y467786D01*
G01X376500Y437983D02*
X378292D01*
X378667Y438150D01*
X378917Y438483D01*
X379000Y438900D01*
X378917Y439317D01*
X378667Y439650D01*
X378292Y439817D01*
X376500D01*
G01X378500Y441083D02*
X378792Y441333D01*
X378958Y441667D01*
X379000Y442042D01*
X378958Y442375D01*
X378750Y442708D01*
X378500Y442917D01*
X378250Y442958D01*
X377958Y442875D01*
X377750Y442583D01*
X377667Y442292D01*
Y441917D01*
G01Y442292D02*
X377542Y442542D01*
X377333Y442750D01*
X377083Y442833D01*
X376833Y442750D01*
X376625Y442542D01*
X376500Y442167D01*
X376542Y441792D01*
X376708Y441417D01*
G01X379000Y445600D02*
X376500D01*
X378292Y444058D01*
Y446142D01*
G01X393817Y541459D02*
X393567Y541584D01*
X393275Y541667D01*
X392942D01*
X392567Y541542D01*
X392275Y541334D01*
X392067Y541084D01*
X391900Y540667D01*
X391858Y540292D01*
X391942Y539917D01*
X392067Y539667D01*
X392317Y539417D01*
X392608Y539250D01*
X392900Y539167D01*
X393192D01*
X393483Y539250D01*
X393733Y539375D01*
X393942Y539542D01*
G01X395083D02*
X395333Y539334D01*
X395625Y539209D01*
X396000Y539167D01*
X396375Y539250D01*
X396667Y539417D01*
X396875Y539709D01*
X396917Y540042D01*
X396833Y540375D01*
X396625Y540584D01*
X396333Y540750D01*
X396042Y540792D01*
X395750Y540750D01*
X395375Y540584D01*
X395500Y541667D01*
X396625D01*
G01X399100Y539167D02*
Y541667D01*
X398600Y541167D01*
G01Y539167D02*
X399600D01*
G01X392017Y533667D02*
Y536167D01*
X393058D01*
X393392Y536042D01*
X393600Y535875D01*
X393683Y535542D01*
X393600Y535209D01*
X393350Y535000D01*
X393058Y534875D01*
X392017D01*
G01X393058D02*
X393683Y533667D01*
G01X395950D02*
Y536167D01*
X395450Y535667D01*
G01Y533667D02*
X396450D01*
G01X398133Y534167D02*
X398383Y533875D01*
X398717Y533709D01*
X399092Y533667D01*
X399425Y533709D01*
X399758Y533917D01*
X399967Y534167D01*
X400008Y534417D01*
X399925Y534709D01*
X399633Y534917D01*
X399342Y535000D01*
X398967D01*
G01X399342D02*
X399592Y535125D01*
X399800Y535334D01*
X399883Y535584D01*
X399800Y535834D01*
X399592Y536042D01*
X399217Y536167D01*
X398842Y536125D01*
X398467Y535959D01*
G01X401442Y533959D02*
X401733Y533750D01*
X402067Y533667D01*
X402400Y533750D01*
X402692Y534000D01*
X402900Y534375D01*
X402983Y534750D01*
Y535209D01*
X402900Y535584D01*
X402692Y535917D01*
X402442Y536084D01*
X402150Y536167D01*
X401817Y536084D01*
X401567Y535917D01*
X401400Y535667D01*
X401317Y535334D01*
X401400Y535042D01*
X401608Y534750D01*
X401858Y534584D01*
X402150Y534542D01*
X402483Y534625D01*
X402733Y534834D01*
X402983Y535209D01*
G01X383800Y535400D02*
Y531400D01*
X391200D01*
G01X386300Y553800D02*
X382300D01*
Y546400D01*
G01X386489Y550535D02*
X390489D01*
Y557935D01*
G01X384400Y566400D02*
Y562400D01*
X391800D01*
G01X384500Y521983D02*
X386292D01*
X386667Y522150D01*
X386917Y522483D01*
X387000Y522900D01*
X386917Y523317D01*
X386667Y523650D01*
X386292Y523817D01*
X384500D01*
G01X384917Y525208D02*
X384667Y525458D01*
X384542Y525750D01*
X384500Y526083D01*
X384583Y526500D01*
X384792Y526792D01*
X385042Y526875D01*
X385292Y526833D01*
X385500Y526667D01*
X385917Y525833D01*
X386208Y525458D01*
X386625Y525208D01*
X387000Y525125D01*
Y526875D01*
G01X385958Y528308D02*
X385667Y528600D01*
X385500Y528850D01*
X385417Y529183D01*
X385500Y529475D01*
X385667Y529683D01*
X385917Y529850D01*
X386208Y529892D01*
X386458Y529850D01*
X386708Y529683D01*
X386917Y529433D01*
X387000Y529142D01*
X386917Y528808D01*
X386667Y528517D01*
X386292Y528350D01*
X385875Y528308D01*
X385333Y528392D01*
X385042Y528517D01*
X384750Y528725D01*
X384542Y529017D01*
X384500Y529308D01*
X384583Y529600D01*
X384792Y529808D01*
G01X371088Y541081D02*
X369288Y538981D01*
X367088Y541081D01*
G01X363488Y541181D02*
Y521981D01*
X374688D01*
Y541181D01*
X363488D01*
Y540781D01*
G01X367700Y497200D02*
X377700D01*
G01X384000Y504983D02*
X385792D01*
X386167Y505150D01*
X386417Y505483D01*
X386500Y505900D01*
X386417Y506317D01*
X386167Y506650D01*
X385792Y506817D01*
X384000D01*
G01X386000Y508083D02*
X386292Y508333D01*
X386458Y508667D01*
X386500Y509042D01*
X386458Y509375D01*
X386250Y509708D01*
X386000Y509917D01*
X385750Y509958D01*
X385458Y509875D01*
X385250Y509583D01*
X385167Y509292D01*
Y508917D01*
G01Y509292D02*
X385042Y509542D01*
X384833Y509750D01*
X384583Y509833D01*
X384333Y509750D01*
X384125Y509542D01*
X384000Y509167D01*
X384042Y508792D01*
X384208Y508417D01*
G01X386000Y511183D02*
X386292Y511433D01*
X386458Y511767D01*
X386500Y512142D01*
X386458Y512475D01*
X386250Y512808D01*
X386000Y513017D01*
X385750Y513058D01*
X385458Y512975D01*
X385250Y512683D01*
X385167Y512392D01*
Y512017D01*
G01Y512392D02*
X385042Y512642D01*
X384833Y512850D01*
X384583Y512933D01*
X384333Y512850D01*
X384125Y512642D01*
X384000Y512267D01*
X384042Y511892D01*
X384208Y511517D01*
G01X365589Y518969D02*
X373589D01*
Y506569D01*
X365589D01*
Y518969D01*
G01X369589Y517269D02*
X371089Y518769D01*
G01X369589Y517269D02*
X368089Y518769D01*
G01X359450Y592443D02*
X366340D01*
Y589728D01*
X377200D01*
G01X360664Y637920D02*
Y633920D01*
X368064D01*
G01X363120Y591086D02*
X359120D01*
Y583686D01*
G01X376600Y588800D02*
X372600D01*
Y581400D01*
G01X397003Y584041D02*
Y586541D01*
X398044D01*
X398378Y586416D01*
X398586Y586249D01*
X398669Y585916D01*
X398586Y585583D01*
X398336Y585374D01*
X398044Y585249D01*
X397003D01*
G01X398044D02*
X398669Y584041D01*
G01X400019Y584541D02*
X400269Y584249D01*
X400603Y584083D01*
X400978Y584041D01*
X401311Y584083D01*
X401644Y584291D01*
X401853Y584541D01*
X401894Y584791D01*
X401811Y585083D01*
X401519Y585291D01*
X401228Y585374D01*
X400853D01*
G01X401228D02*
X401478Y585499D01*
X401686Y585708D01*
X401769Y585958D01*
X401686Y586208D01*
X401478Y586416D01*
X401103Y586541D01*
X400728Y586499D01*
X400353Y586333D01*
G01X403119Y584416D02*
X403369Y584208D01*
X403661Y584083D01*
X404036Y584041D01*
X404411Y584124D01*
X404703Y584291D01*
X404911Y584583D01*
X404953Y584916D01*
X404869Y585249D01*
X404661Y585458D01*
X404369Y585624D01*
X404078Y585666D01*
X403786Y585624D01*
X403411Y585458D01*
X403536Y586541D01*
X404661D01*
G01X394936Y583080D02*
Y587080D01*
X387536D01*
G01X376800Y578400D02*
X380800D01*
Y585800D01*
G01X396567Y636861D02*
Y639361D01*
X397608D01*
X397942Y639236D01*
X398150Y639069D01*
X398233Y638736D01*
X398150Y638403D01*
X397900Y638194D01*
X397608Y638069D01*
X396567D01*
G01X397608D02*
X398233Y636861D01*
G01X399583Y637361D02*
X399833Y637069D01*
X400167Y636903D01*
X400542Y636861D01*
X400875Y636903D01*
X401208Y637111D01*
X401417Y637361D01*
X401458Y637611D01*
X401375Y637903D01*
X401083Y638111D01*
X400792Y638194D01*
X400417D01*
G01X400792D02*
X401042Y638319D01*
X401250Y638528D01*
X401333Y638778D01*
X401250Y639028D01*
X401042Y639236D01*
X400667Y639361D01*
X400292Y639319D01*
X399917Y639153D01*
G01X402808Y638944D02*
X403058Y639194D01*
X403350Y639319D01*
X403683Y639361D01*
X404100Y639278D01*
X404392Y639069D01*
X404475Y638819D01*
X404433Y638569D01*
X404267Y638361D01*
X403433Y637944D01*
X403058Y637653D01*
X402808Y637236D01*
X402725Y636861D01*
X404475D01*
G01X394600Y635900D02*
Y639900D01*
X387200D01*
G01X396267Y588361D02*
Y590861D01*
X397308D01*
X397642Y590736D01*
X397850Y590569D01*
X397933Y590236D01*
X397850Y589903D01*
X397600Y589694D01*
X397308Y589569D01*
X396267D01*
G01X397308D02*
X397933Y588361D01*
G01X399283Y588861D02*
X399533Y588569D01*
X399867Y588403D01*
X400242Y588361D01*
X400575Y588403D01*
X400908Y588611D01*
X401117Y588861D01*
X401158Y589111D01*
X401075Y589403D01*
X400783Y589611D01*
X400492Y589694D01*
X400117D01*
G01X400492D02*
X400742Y589819D01*
X400950Y590028D01*
X401033Y590278D01*
X400950Y590528D01*
X400742Y590736D01*
X400367Y590861D01*
X399992Y590819D01*
X399617Y590653D01*
G01X403300Y590861D02*
X402967Y590778D01*
X402717Y590569D01*
X402550Y590319D01*
X402425Y589986D01*
X402383Y589611D01*
X402425Y589236D01*
X402550Y588903D01*
X402717Y588653D01*
X402967Y588444D01*
X403300Y588361D01*
X403633Y588444D01*
X403883Y588653D01*
X404050Y588903D01*
X404175Y589236D01*
X404217Y589611D01*
X404175Y589986D01*
X404050Y590319D01*
X403883Y590569D01*
X403633Y590778D01*
X403300Y590861D01*
G01X394900Y587100D02*
Y591100D01*
X387500D01*
G01X381000Y578400D02*
X385000D01*
Y585800D01*
G01X395367Y612361D02*
Y614861D01*
X396408D01*
X396742Y614736D01*
X396950Y614569D01*
X397033Y614236D01*
X396950Y613903D01*
X396700Y613694D01*
X396408Y613569D01*
X395367D01*
G01X396408D02*
X397033Y612361D01*
G01X398508Y614444D02*
X398758Y614694D01*
X399050Y614819D01*
X399383Y614861D01*
X399800Y614778D01*
X400092Y614569D01*
X400175Y614319D01*
X400133Y614069D01*
X399967Y613861D01*
X399133Y613444D01*
X398758Y613153D01*
X398508Y612736D01*
X398425Y612361D01*
X400175D01*
G01X401483Y612861D02*
X401733Y612569D01*
X402067Y612403D01*
X402442Y612361D01*
X402775Y612403D01*
X403108Y612611D01*
X403317Y612861D01*
X403358Y613111D01*
X403275Y613403D01*
X402983Y613611D01*
X402692Y613694D01*
X402317D01*
G01X402692D02*
X402942Y613819D01*
X403150Y614028D01*
X403233Y614278D01*
X403150Y614528D01*
X402942Y614736D01*
X402567Y614861D01*
X402192Y614819D01*
X401817Y614653D01*
G01X385800Y615900D02*
Y611900D01*
X393200D01*
G01X396103Y627841D02*
Y630341D01*
X397144D01*
X397478Y630216D01*
X397686Y630049D01*
X397769Y629716D01*
X397686Y629383D01*
X397436Y629174D01*
X397144Y629049D01*
X396103D01*
G01X397144D02*
X397769Y627841D01*
G01X399244Y629924D02*
X399494Y630174D01*
X399786Y630299D01*
X400119Y630341D01*
X400536Y630258D01*
X400828Y630049D01*
X400911Y629799D01*
X400869Y629549D01*
X400703Y629341D01*
X399869Y628924D01*
X399494Y628633D01*
X399244Y628216D01*
X399161Y627841D01*
X400911D01*
G01X403136Y630341D02*
X402803Y630258D01*
X402553Y630049D01*
X402386Y629799D01*
X402261Y629466D01*
X402219Y629091D01*
X402261Y628716D01*
X402386Y628383D01*
X402553Y628133D01*
X402803Y627924D01*
X403136Y627841D01*
X403469Y627924D01*
X403719Y628133D01*
X403886Y628383D01*
X404011Y628716D01*
X404053Y629091D01*
X404011Y629466D01*
X403886Y629799D01*
X403719Y630049D01*
X403469Y630258D01*
X403136Y630341D01*
G01X394636Y626580D02*
Y630580D01*
X387236D01*
G01X396267Y604561D02*
Y607061D01*
X397308D01*
X397642Y606936D01*
X397850Y606769D01*
X397933Y606436D01*
X397850Y606103D01*
X397600Y605894D01*
X397308Y605769D01*
X396267D01*
G01X397308D02*
X397933Y604561D01*
G01X400200D02*
Y607061D01*
X399700Y606561D01*
G01Y604561D02*
X400700D01*
G01X402592Y604853D02*
X402883Y604644D01*
X403217Y604561D01*
X403550Y604644D01*
X403842Y604894D01*
X404050Y605269D01*
X404133Y605644D01*
Y606103D01*
X404050Y606478D01*
X403842Y606811D01*
X403592Y606978D01*
X403300Y607061D01*
X402967Y606978D01*
X402717Y606811D01*
X402550Y606561D01*
X402467Y606228D01*
X402550Y605936D01*
X402758Y605644D01*
X403008Y605478D01*
X403300Y605436D01*
X403633Y605519D01*
X403883Y605728D01*
X404133Y606103D01*
G01X395000Y603400D02*
Y607400D01*
X387600D01*
G01X395403Y616441D02*
Y618941D01*
X396444D01*
X396778Y618816D01*
X396986Y618649D01*
X397069Y618316D01*
X396986Y617983D01*
X396736Y617774D01*
X396444Y617649D01*
X395403D01*
G01X396444D02*
X397069Y616441D01*
G01X399336D02*
Y618941D01*
X398836Y618441D01*
G01Y616441D02*
X399836D01*
G01X402436D02*
X402728Y616483D01*
X403061Y616608D01*
X403269Y616816D01*
X403353Y617108D01*
X403269Y617399D01*
X403019Y617649D01*
X402644Y617774D01*
X402228D01*
X401978Y617858D01*
X401769Y618066D01*
X401686Y618358D01*
X401811Y618649D01*
X402103Y618858D01*
X402436Y618941D01*
X402769Y618858D01*
X403061Y618649D01*
X403186Y618358D01*
X403103Y618066D01*
X402894Y617858D01*
X402644Y617774D01*
X402228D01*
X401853Y617649D01*
X401603Y617399D01*
X401519Y617108D01*
X401603Y616816D01*
X401811Y616608D01*
X402144Y616483D01*
X402436Y616441D01*
G01X393236Y615980D02*
Y619980D01*
X385836D01*
G01X397167Y596161D02*
Y598661D01*
X398208D01*
X398542Y598536D01*
X398750Y598369D01*
X398833Y598036D01*
X398750Y597703D01*
X398500Y597494D01*
X398208Y597369D01*
X397167D01*
G01X398208D02*
X398833Y596161D01*
G01X401600D02*
Y598661D01*
X400058Y596869D01*
X402142D01*
G01X403283Y596661D02*
X403533Y596369D01*
X403867Y596203D01*
X404242Y596161D01*
X404575Y596203D01*
X404908Y596411D01*
X405117Y596661D01*
X405158Y596911D01*
X405075Y597203D01*
X404783Y597411D01*
X404492Y597494D01*
X404117D01*
G01X404492D02*
X404742Y597619D01*
X404950Y597828D01*
X405033Y598078D01*
X404950Y598328D01*
X404742Y598536D01*
X404367Y598661D01*
X403992Y598619D01*
X403617Y598453D01*
G01X387600Y599200D02*
Y595200D01*
X395000D01*
G01X396667Y592361D02*
Y594861D01*
X397708D01*
X398042Y594736D01*
X398250Y594569D01*
X398333Y594236D01*
X398250Y593903D01*
X398000Y593694D01*
X397708Y593569D01*
X396667D01*
G01X397708D02*
X398333Y592361D01*
G01X399683Y592861D02*
X399933Y592569D01*
X400267Y592403D01*
X400642Y592361D01*
X400975Y592403D01*
X401308Y592611D01*
X401517Y592861D01*
X401558Y593111D01*
X401475Y593403D01*
X401183Y593611D01*
X400892Y593694D01*
X400517D01*
G01X400892D02*
X401142Y593819D01*
X401350Y594028D01*
X401433Y594278D01*
X401350Y594528D01*
X401142Y594736D01*
X400767Y594861D01*
X400392Y594819D01*
X400017Y594653D01*
G01X402908Y593403D02*
X403200Y593694D01*
X403450Y593861D01*
X403783Y593944D01*
X404075Y593861D01*
X404283Y593694D01*
X404450Y593444D01*
X404492Y593153D01*
X404450Y592903D01*
X404283Y592653D01*
X404033Y592444D01*
X403742Y592361D01*
X403408Y592444D01*
X403117Y592694D01*
X402950Y593069D01*
X402908Y593486D01*
X402992Y594028D01*
X403117Y594319D01*
X403325Y594611D01*
X403617Y594819D01*
X403908Y594861D01*
X404200Y594778D01*
X404408Y594569D01*
G01X394900Y591200D02*
Y595200D01*
X387500D01*
G01X396767Y600161D02*
Y602661D01*
X397808D01*
X398142Y602536D01*
X398350Y602369D01*
X398433Y602036D01*
X398350Y601703D01*
X398100Y601494D01*
X397808Y601369D01*
X396767D01*
G01X397808D02*
X398433Y600161D01*
G01X399783Y600661D02*
X400033Y600369D01*
X400367Y600203D01*
X400742Y600161D01*
X401075Y600203D01*
X401408Y600411D01*
X401617Y600661D01*
X401658Y600911D01*
X401575Y601203D01*
X401283Y601411D01*
X400992Y601494D01*
X400617D01*
G01X400992D02*
X401242Y601619D01*
X401450Y601828D01*
X401533Y602078D01*
X401450Y602328D01*
X401242Y602536D01*
X400867Y602661D01*
X400492Y602619D01*
X400117Y602453D01*
G01X403800Y600161D02*
Y602661D01*
X403300Y602161D01*
G01Y600161D02*
X404300D01*
G01X395000Y599300D02*
Y603300D01*
X387600D01*
G01X393595Y566431D02*
Y570431D01*
X386195D01*
G01X393644Y570999D02*
Y574999D01*
X386244D01*
G01X396248Y621326D02*
Y623826D01*
X397289D01*
X397623Y623701D01*
X397831Y623534D01*
X397914Y623201D01*
X397831Y622868D01*
X397581Y622659D01*
X397289Y622534D01*
X396248D01*
G01X397289D02*
X397914Y621326D01*
G01X399389Y623409D02*
X399639Y623659D01*
X399931Y623784D01*
X400264Y623826D01*
X400681Y623743D01*
X400973Y623534D01*
X401056Y623284D01*
X401014Y623034D01*
X400848Y622826D01*
X400014Y622409D01*
X399639Y622118D01*
X399389Y621701D01*
X399306Y621326D01*
X401056D01*
G01X402489Y622368D02*
X402781Y622659D01*
X403031Y622826D01*
X403364Y622909D01*
X403656Y622826D01*
X403864Y622659D01*
X404031Y622409D01*
X404073Y622118D01*
X404031Y621868D01*
X403864Y621618D01*
X403614Y621409D01*
X403323Y621326D01*
X402989Y621409D01*
X402698Y621659D01*
X402531Y622034D01*
X402489Y622451D01*
X402573Y622993D01*
X402698Y623284D01*
X402906Y623576D01*
X403198Y623784D01*
X403489Y623826D01*
X403781Y623743D01*
X403989Y623534D01*
G01X387181Y624265D02*
Y620265D01*
X394581D01*
G01X371400Y595667D02*
Y593167D01*
G01X370442Y595667D02*
X372358D01*
G01X373667Y593167D02*
Y595667D01*
X374667D01*
X375000Y595542D01*
X375250Y595250D01*
X375333Y594917D01*
X375250Y594584D01*
X375042Y594334D01*
X374667Y594209D01*
X373667D01*
G01X376683Y593542D02*
X376933Y593334D01*
X377225Y593209D01*
X377600Y593167D01*
X377975Y593250D01*
X378267Y593417D01*
X378475Y593709D01*
X378517Y594042D01*
X378433Y594375D01*
X378225Y594584D01*
X377933Y594750D01*
X377642Y594792D01*
X377350Y594750D01*
X376975Y594584D01*
X377100Y595667D01*
X378225D01*
G01X369989Y578279D02*
X366839Y575129D01*
X363689Y578279D01*
G01X359164Y629720D02*
Y627820D01*
G01X368964Y630320D02*
Y627620D01*
G01X382164Y616520D02*
X380164D01*
G01X380264Y606720D02*
X382664D01*
G01X367064Y597420D02*
Y595620D01*
G01X357264Y597720D02*
Y595020D01*
G01X380964Y623420D02*
Y628420D01*
X375964D01*
G01X380964Y601820D02*
Y596820D01*
X375964D01*
G01X400398Y647681D02*
X395398Y651181D01*
G01Y647681D02*
X400398Y651181D01*
G01Y655031D02*
X395398D01*
X396398Y654031D01*
G01X400398D02*
Y656031D01*
G01X400565Y660631D02*
X400481Y660464D01*
X400315D01*
X400231Y660631D01*
X400315Y660798D01*
X400481D01*
X400565Y660631D01*
G01X398315D02*
X398231Y660464D01*
X398065D01*
X397981Y660631D01*
X398065Y660798D01*
X398231D01*
X398315Y660631D01*
G01X396231Y664648D02*
X395731Y665148D01*
X395481Y665731D01*
X395398Y666398D01*
X395565Y667231D01*
X395981Y667814D01*
X396481Y667981D01*
X396981Y667898D01*
X397398Y667564D01*
X398231Y665898D01*
X398815Y665148D01*
X399648Y664648D01*
X400398Y664481D01*
Y667981D01*
G01Y672831D02*
X395398D01*
X398981Y669748D01*
Y673914D01*
G01X400398Y675264D02*
X395398D01*
X399565Y677431D01*
X395398Y679598D01*
X400398D01*
G01Y681281D02*
X395398D01*
G01Y684781D02*
X400398D01*
G01X397898D02*
Y681281D01*
G01X395398Y687048D02*
Y690214D01*
X400398Y687048D01*
Y690214D01*
G01X387033Y656852D02*
X386783Y656977D01*
X386491Y657060D01*
X386158D01*
X385783Y656935D01*
X385491Y656727D01*
X385283Y656477D01*
X385116Y656060D01*
X385074Y655685D01*
X385158Y655310D01*
X385283Y655060D01*
X385533Y654810D01*
X385824Y654643D01*
X386116Y654560D01*
X386408D01*
X386699Y654643D01*
X386949Y654768D01*
X387158Y654935D01*
G01X388424Y656643D02*
X388674Y656893D01*
X388966Y657018D01*
X389299Y657060D01*
X389716Y656977D01*
X390008Y656768D01*
X390091Y656518D01*
X390049Y656268D01*
X389883Y656060D01*
X389049Y655643D01*
X388674Y655352D01*
X388424Y654935D01*
X388341Y654560D01*
X390091D01*
G01X392316Y657060D02*
X391983Y656977D01*
X391733Y656768D01*
X391566Y656518D01*
X391441Y656185D01*
X391399Y655810D01*
X391441Y655435D01*
X391566Y655102D01*
X391733Y654852D01*
X391983Y654643D01*
X392316Y654560D01*
X392649Y654643D01*
X392899Y654852D01*
X393066Y655102D01*
X393191Y655435D01*
X393233Y655810D01*
X393191Y656185D01*
X393066Y656518D01*
X392899Y656768D01*
X392649Y656977D01*
X392316Y657060D01*
G01X377172Y656915D02*
X376922Y657040D01*
X376630Y657123D01*
X376297D01*
X375922Y656998D01*
X375630Y656790D01*
X375422Y656540D01*
X375255Y656123D01*
X375213Y655748D01*
X375297Y655373D01*
X375422Y655123D01*
X375672Y654873D01*
X375963Y654706D01*
X376255Y654623D01*
X376547D01*
X376838Y654706D01*
X377088Y654831D01*
X377297Y654998D01*
G01X379355Y654623D02*
Y657123D01*
X378855Y656623D01*
G01Y654623D02*
X379855D01*
G01X382372D02*
X382455Y655165D01*
X382580Y655623D01*
X382747Y656040D01*
X382955Y656498D01*
X383288Y657123D01*
X381622D01*
G01X392767Y699792D02*
X392517Y699917D01*
X392225Y700000D01*
X391892D01*
X391517Y699875D01*
X391225Y699667D01*
X391017Y699417D01*
X390850Y699000D01*
X390808Y698625D01*
X390892Y698250D01*
X391017Y698000D01*
X391267Y697750D01*
X391558Y697583D01*
X391850Y697500D01*
X392142D01*
X392433Y697583D01*
X392683Y697708D01*
X392892Y697875D01*
G01X394950Y697500D02*
Y700000D01*
X394450Y699500D01*
G01Y697500D02*
X395450D01*
G01X398550D02*
Y700000D01*
X397008Y698208D01*
X399092D01*
G01X401150Y697500D02*
Y700000D01*
X400650Y699500D01*
G01Y697500D02*
X401650D01*
G01X379508Y650083D02*
Y652583D01*
X380549D01*
X380883Y652458D01*
X381091Y652291D01*
X381174Y651958D01*
X381091Y651625D01*
X380841Y651416D01*
X380549Y651291D01*
X379508D01*
G01X380549D02*
X381174Y650083D01*
G01X382649Y652166D02*
X382899Y652416D01*
X383191Y652541D01*
X383524Y652583D01*
X383941Y652500D01*
X384233Y652291D01*
X384316Y652041D01*
X384274Y651791D01*
X384108Y651583D01*
X383274Y651166D01*
X382899Y650875D01*
X382649Y650458D01*
X382566Y650083D01*
X384316D01*
G01X386458D02*
X386541Y650625D01*
X386666Y651083D01*
X386833Y651500D01*
X387041Y651958D01*
X387374Y652583D01*
X385708D01*
G01X393017Y693000D02*
Y695500D01*
X394058D01*
X394392Y695375D01*
X394600Y695208D01*
X394683Y694875D01*
X394600Y694542D01*
X394350Y694333D01*
X394058Y694208D01*
X393017D01*
G01X394058D02*
X394683Y693000D01*
G01X396867D02*
X396950Y693542D01*
X397075Y694000D01*
X397242Y694417D01*
X397450Y694875D01*
X397783Y695500D01*
X396117D01*
G01X399133Y693500D02*
X399383Y693208D01*
X399717Y693042D01*
X400092Y693000D01*
X400425Y693042D01*
X400758Y693250D01*
X400967Y693500D01*
X401008Y693750D01*
X400925Y694042D01*
X400633Y694250D01*
X400342Y694333D01*
X399967D01*
G01X400342D02*
X400592Y694458D01*
X400800Y694667D01*
X400883Y694917D01*
X400800Y695167D01*
X400592Y695375D01*
X400217Y695500D01*
X399842Y695458D01*
X399467Y695292D01*
G01X402358Y694042D02*
X402650Y694333D01*
X402900Y694500D01*
X403233Y694583D01*
X403525Y694500D01*
X403733Y694333D01*
X403900Y694083D01*
X403942Y693792D01*
X403900Y693542D01*
X403733Y693292D01*
X403483Y693083D01*
X403192Y693000D01*
X402858Y693083D01*
X402567Y693333D01*
X402400Y693708D01*
X402358Y694125D01*
X402442Y694667D01*
X402567Y694958D01*
X402775Y695250D01*
X403067Y695458D01*
X403358Y695500D01*
X403650Y695417D01*
X403858Y695208D01*
G01X391502Y692223D02*
Y696223D01*
X384102D01*
G01X382033Y668974D02*
Y671474D01*
X383074D01*
X383408Y671349D01*
X383616Y671182D01*
X383699Y670849D01*
X383616Y670516D01*
X383366Y670307D01*
X383074Y670182D01*
X382033D01*
G01X383074D02*
X383699Y668974D01*
G01X385966D02*
Y671474D01*
X385466Y670974D01*
G01Y668974D02*
X386466D01*
G01X388274Y671057D02*
X388524Y671307D01*
X388816Y671432D01*
X389149Y671474D01*
X389566Y671391D01*
X389858Y671182D01*
X389941Y670932D01*
X389899Y670682D01*
X389733Y670474D01*
X388899Y670057D01*
X388524Y669766D01*
X388274Y669349D01*
X388191Y668974D01*
X389941D01*
G01X392666D02*
Y671474D01*
X391124Y669682D01*
X393208D01*
G01X390800Y681900D02*
Y685900D01*
X383400D01*
G01X381933Y664874D02*
Y667374D01*
X382974D01*
X383308Y667249D01*
X383516Y667082D01*
X383599Y666749D01*
X383516Y666416D01*
X383266Y666207D01*
X382974Y666082D01*
X381933D01*
G01X382974D02*
X383599Y664874D01*
G01X385866D02*
Y667374D01*
X385366Y666874D01*
G01Y664874D02*
X386366D01*
G01X388174Y666957D02*
X388424Y667207D01*
X388716Y667332D01*
X389049Y667374D01*
X389466Y667291D01*
X389758Y667082D01*
X389841Y666832D01*
X389799Y666582D01*
X389633Y666374D01*
X388799Y665957D01*
X388424Y665666D01*
X388174Y665249D01*
X388091Y664874D01*
X389841D01*
G01X391149Y665374D02*
X391399Y665082D01*
X391733Y664916D01*
X392108Y664874D01*
X392441Y664916D01*
X392774Y665124D01*
X392983Y665374D01*
X393024Y665624D01*
X392941Y665916D01*
X392649Y666124D01*
X392358Y666207D01*
X391983D01*
G01X392358D02*
X392608Y666332D01*
X392816Y666541D01*
X392899Y666791D01*
X392816Y667041D01*
X392608Y667249D01*
X392233Y667374D01*
X391858Y667332D01*
X391483Y667166D01*
G01X390700Y677800D02*
Y681800D01*
X383300D01*
G01X381933Y660674D02*
Y663174D01*
X382974D01*
X383308Y663049D01*
X383516Y662882D01*
X383599Y662549D01*
X383516Y662216D01*
X383266Y662007D01*
X382974Y661882D01*
X381933D01*
G01X382974D02*
X383599Y660674D01*
G01X385783D02*
X385866Y661216D01*
X385991Y661674D01*
X386158Y662091D01*
X386366Y662549D01*
X386699Y663174D01*
X385033D01*
G01X388174Y662757D02*
X388424Y663007D01*
X388716Y663132D01*
X389049Y663174D01*
X389466Y663091D01*
X389758Y662882D01*
X389841Y662632D01*
X389799Y662382D01*
X389633Y662174D01*
X388799Y661757D01*
X388424Y661466D01*
X388174Y661049D01*
X388091Y660674D01*
X389841D01*
G01X392566D02*
Y663174D01*
X391024Y661382D01*
X393108D01*
G01X390700Y673600D02*
Y677600D01*
X383300D01*
G01X371300Y699700D02*
Y713700D01*
G01X361496Y659172D02*
X363246Y661672D01*
G01X361496D02*
X363246Y659172D01*
G01X365471D02*
Y661672D01*
X364971Y661172D01*
G01Y659172D02*
X365971D01*
G01X373011Y654949D02*
X356311D01*
Y642749D01*
X373011D01*
Y654949D01*
G01X377336Y704826D02*
Y703034D01*
X377503Y702659D01*
X377836Y702409D01*
X378253Y702326D01*
X378670Y702409D01*
X379003Y702659D01*
X379170Y703034D01*
Y704826D01*
G01X381353Y702326D02*
Y704826D01*
X380853Y704326D01*
G01Y702326D02*
X381853D01*
G01X384453Y704826D02*
X384120Y704743D01*
X383870Y704534D01*
X383703Y704284D01*
X383578Y703951D01*
X383536Y703576D01*
X383578Y703201D01*
X383703Y702868D01*
X383870Y702618D01*
X384120Y702409D01*
X384453Y702326D01*
X384786Y702409D01*
X385036Y702618D01*
X385203Y702868D01*
X385328Y703201D01*
X385370Y703576D01*
X385328Y703951D01*
X385203Y704284D01*
X385036Y704534D01*
X384786Y704743D01*
X384453Y704826D01*
G01X387470Y702326D02*
X387553Y702868D01*
X387678Y703326D01*
X387845Y703743D01*
X388053Y704201D01*
X388386Y704826D01*
X386720D01*
G01X384046Y712676D02*
X383796Y712801D01*
X383504Y712884D01*
X383171D01*
X382796Y712759D01*
X382504Y712551D01*
X382296Y712301D01*
X382129Y711884D01*
X382087Y711509D01*
X382171Y711134D01*
X382296Y710884D01*
X382546Y710634D01*
X382837Y710467D01*
X383129Y710384D01*
X383421D01*
X383712Y710467D01*
X383962Y710592D01*
X384171Y710759D01*
G01X386229Y710384D02*
Y712884D01*
X385729Y712384D01*
G01Y710384D02*
X386729D01*
G01X388412Y710884D02*
X388662Y710592D01*
X388996Y710426D01*
X389371Y710384D01*
X389704Y710426D01*
X390037Y710634D01*
X390246Y710884D01*
X390287Y711134D01*
X390204Y711426D01*
X389912Y711634D01*
X389621Y711717D01*
X389246D01*
G01X389621D02*
X389871Y711842D01*
X390079Y712051D01*
X390162Y712301D01*
X390079Y712551D01*
X389871Y712759D01*
X389496Y712884D01*
X389121Y712842D01*
X388746Y712676D01*
G01X391637Y711426D02*
X391929Y711717D01*
X392179Y711884D01*
X392512Y711967D01*
X392804Y711884D01*
X393012Y711717D01*
X393179Y711467D01*
X393221Y711176D01*
X393179Y710926D01*
X393012Y710676D01*
X392762Y710467D01*
X392471Y710384D01*
X392137Y710467D01*
X391846Y710717D01*
X391679Y711092D01*
X391637Y711509D01*
X391721Y712051D01*
X391846Y712342D01*
X392054Y712634D01*
X392346Y712842D01*
X392637Y712884D01*
X392929Y712801D01*
X393137Y712592D01*
G01X439585Y36057D02*
Y40057D01*
X432185D01*
G01X447985Y19957D02*
Y23957D01*
X440585D01*
G01X441258Y54153D02*
Y58153D01*
X433858D01*
G01X448085Y28457D02*
Y32457D01*
X440685D01*
G01X448085Y24157D02*
Y28157D01*
X440685D01*
G01X448016Y36147D02*
Y40147D01*
X440616D01*
G01X486098Y12277D02*
Y14777D01*
X487139D01*
X487473Y14652D01*
X487681Y14485D01*
X487764Y14152D01*
X487681Y13819D01*
X487431Y13610D01*
X487139Y13485D01*
X486098D01*
G01X487139D02*
X487764Y12277D01*
G01X490531D02*
Y14777D01*
X488989Y12985D01*
X491073D01*
G01X492214Y12777D02*
X492464Y12485D01*
X492798Y12319D01*
X493173Y12277D01*
X493506Y12319D01*
X493839Y12527D01*
X494048Y12777D01*
X494089Y13027D01*
X494006Y13319D01*
X493714Y13527D01*
X493423Y13610D01*
X493048D01*
G01X493423D02*
X493673Y13735D01*
X493881Y13944D01*
X493964Y14194D01*
X493881Y14444D01*
X493673Y14652D01*
X493298Y14777D01*
X492923Y14735D01*
X492548Y14569D01*
G01X496231Y12277D02*
X496523Y12319D01*
X496856Y12444D01*
X497064Y12652D01*
X497148Y12944D01*
X497064Y13235D01*
X496814Y13485D01*
X496439Y13610D01*
X496023D01*
X495773Y13694D01*
X495564Y13902D01*
X495481Y14194D01*
X495606Y14485D01*
X495898Y14694D01*
X496231Y14777D01*
X496564Y14694D01*
X496856Y14485D01*
X496981Y14194D01*
X496898Y13902D01*
X496689Y13694D01*
X496439Y13610D01*
X496023D01*
X495648Y13485D01*
X495398Y13235D01*
X495314Y12944D01*
X495398Y12652D01*
X495606Y12444D01*
X495939Y12319D01*
X496231Y12277D01*
G01X495200Y28000D02*
Y32000D01*
X487800D01*
G01Y44000D02*
Y40000D01*
X495200D01*
G01X486536Y16252D02*
Y18752D01*
X487577D01*
X487911Y18627D01*
X488119Y18460D01*
X488202Y18127D01*
X488119Y17794D01*
X487869Y17585D01*
X487577Y17460D01*
X486536D01*
G01X487577D02*
X488202Y16252D01*
G01X490969D02*
Y18752D01*
X489427Y16960D01*
X491511D01*
G01X492652Y16752D02*
X492902Y16460D01*
X493236Y16294D01*
X493611Y16252D01*
X493944Y16294D01*
X494277Y16502D01*
X494486Y16752D01*
X494527Y17002D01*
X494444Y17294D01*
X494152Y17502D01*
X493861Y17585D01*
X493486D01*
G01X493861D02*
X494111Y17710D01*
X494319Y17919D01*
X494402Y18169D01*
X494319Y18419D01*
X494111Y18627D01*
X493736Y18752D01*
X493361Y18710D01*
X492986Y18544D01*
G01X495752Y16627D02*
X496002Y16419D01*
X496294Y16294D01*
X496669Y16252D01*
X497044Y16335D01*
X497336Y16502D01*
X497544Y16794D01*
X497586Y17127D01*
X497502Y17460D01*
X497294Y17669D01*
X497002Y17835D01*
X496711Y17877D01*
X496419Y17835D01*
X496044Y17669D01*
X496169Y18752D01*
X497294D01*
G01X488200Y36000D02*
Y32000D01*
X495600D01*
G01X485998Y4077D02*
Y6577D01*
X487039D01*
X487373Y6452D01*
X487581Y6285D01*
X487664Y5952D01*
X487581Y5619D01*
X487331Y5410D01*
X487039Y5285D01*
X485998D01*
G01X487039D02*
X487664Y4077D01*
G01X489848D02*
X489931Y4619D01*
X490056Y5077D01*
X490223Y5494D01*
X490431Y5952D01*
X490764Y6577D01*
X489098D01*
G01X493031Y4077D02*
Y6577D01*
X492531Y6077D01*
G01Y4077D02*
X493531D01*
G01X495339Y6160D02*
X495589Y6410D01*
X495881Y6535D01*
X496214Y6577D01*
X496631Y6494D01*
X496923Y6285D01*
X497006Y6035D01*
X496964Y5785D01*
X496798Y5577D01*
X495964Y5160D01*
X495589Y4869D01*
X495339Y4452D01*
X495256Y4077D01*
X497006D01*
G01X495100Y19800D02*
Y23800D01*
X487700D01*
G01X486098Y8277D02*
Y10777D01*
X487139D01*
X487473Y10652D01*
X487681Y10485D01*
X487764Y10152D01*
X487681Y9819D01*
X487431Y9610D01*
X487139Y9485D01*
X486098D01*
G01X487139D02*
X487764Y8277D01*
G01X489948D02*
X490031Y8819D01*
X490156Y9277D01*
X490323Y9694D01*
X490531Y10152D01*
X490864Y10777D01*
X489198D01*
G01X493131Y8277D02*
Y10777D01*
X492631Y10277D01*
G01Y8277D02*
X493631D01*
G01X496231D02*
Y10777D01*
X495731Y10277D01*
G01Y8277D02*
X496731D01*
G01X495200Y24000D02*
Y28000D01*
X487800D01*
G01X466342Y59258D02*
X462342D01*
Y51858D01*
G01X477526Y61562D02*
Y57562D01*
X484926D01*
G01X483814Y53841D02*
Y49841D01*
X491214D01*
G01X470400Y66700D02*
X466400D01*
Y59300D01*
G01X474700Y66600D02*
X470700D01*
Y59200D01*
G01X448767Y60292D02*
X448517Y60417D01*
X448225Y60500D01*
X447892D01*
X447517Y60375D01*
X447225Y60167D01*
X447017Y59917D01*
X446850Y59500D01*
X446808Y59125D01*
X446892Y58750D01*
X447017Y58500D01*
X447267Y58250D01*
X447558Y58083D01*
X447850Y58000D01*
X448142D01*
X448433Y58083D01*
X448683Y58208D01*
X448892Y58375D01*
G01X450950Y58000D02*
Y60500D01*
X450450Y60000D01*
G01Y58000D02*
X451450D01*
G01X453258Y60083D02*
X453508Y60333D01*
X453800Y60458D01*
X454133Y60500D01*
X454550Y60417D01*
X454842Y60208D01*
X454925Y59958D01*
X454883Y59708D01*
X454717Y59500D01*
X453883Y59083D01*
X453508Y58792D01*
X453258Y58375D01*
X453175Y58000D01*
X454925D01*
G01X457150D02*
X457442Y58042D01*
X457775Y58167D01*
X457983Y58375D01*
X458067Y58667D01*
X457983Y58958D01*
X457733Y59208D01*
X457358Y59333D01*
X456942D01*
X456692Y59417D01*
X456483Y59625D01*
X456400Y59917D01*
X456525Y60208D01*
X456817Y60417D01*
X457150Y60500D01*
X457483Y60417D01*
X457775Y60208D01*
X457900Y59917D01*
X457817Y59625D01*
X457608Y59417D01*
X457358Y59333D01*
X456942D01*
X456567Y59208D01*
X456317Y58958D01*
X456233Y58667D01*
X456317Y58375D01*
X456525Y58167D01*
X456858Y58042D01*
X457150Y58000D01*
G01X438000Y59517D02*
X435500D01*
Y60558D01*
X435625Y60892D01*
X435792Y61100D01*
X436125Y61183D01*
X436458Y61100D01*
X436667Y60850D01*
X436792Y60558D01*
Y59517D01*
G01Y60558D02*
X438000Y61183D01*
G01Y63950D02*
X435500D01*
X437292Y62408D01*
Y64492D01*
G01X437625Y65633D02*
X437833Y65883D01*
X437958Y66175D01*
X438000Y66550D01*
X437917Y66925D01*
X437750Y67217D01*
X437458Y67425D01*
X437125Y67467D01*
X436792Y67383D01*
X436583Y67175D01*
X436417Y66883D01*
X436375Y66592D01*
X436417Y66300D01*
X436583Y65925D01*
X435500Y66050D01*
Y67175D01*
G01X437500Y68733D02*
X437792Y68983D01*
X437958Y69317D01*
X438000Y69692D01*
X437958Y70025D01*
X437750Y70358D01*
X437500Y70567D01*
X437250Y70608D01*
X436958Y70525D01*
X436750Y70233D01*
X436667Y69942D01*
Y69567D01*
G01Y69942D02*
X436542Y70192D01*
X436333Y70400D01*
X436083Y70483D01*
X435833Y70400D01*
X435625Y70192D01*
X435500Y69817D01*
X435542Y69442D01*
X435708Y69067D01*
G01X445489Y47801D02*
X441489D01*
Y40401D01*
G01X441457Y48015D02*
X445457D01*
Y55415D01*
G01X463483Y16167D02*
Y14375D01*
X463650Y14000D01*
X463983Y13750D01*
X464400Y13667D01*
X464817Y13750D01*
X465150Y14000D01*
X465317Y14375D01*
Y16167D01*
G01X466583Y14167D02*
X466833Y13875D01*
X467167Y13709D01*
X467542Y13667D01*
X467875Y13709D01*
X468208Y13917D01*
X468417Y14167D01*
X468458Y14417D01*
X468375Y14709D01*
X468083Y14917D01*
X467792Y15000D01*
X467417D01*
G01X467792D02*
X468042Y15125D01*
X468250Y15334D01*
X468333Y15584D01*
X468250Y15834D01*
X468042Y16042D01*
X467667Y16167D01*
X467292Y16125D01*
X466917Y15959D01*
G01X469683Y14042D02*
X469933Y13834D01*
X470225Y13709D01*
X470600Y13667D01*
X470975Y13750D01*
X471267Y13917D01*
X471475Y14209D01*
X471517Y14542D01*
X471433Y14875D01*
X471225Y15084D01*
X470933Y15250D01*
X470642Y15292D01*
X470350Y15250D01*
X469975Y15084D01*
X470100Y16167D01*
X471225D01*
G01X483950Y34413D02*
X480950D01*
G01X453050D02*
X455050D01*
G01X463080Y19450D02*
Y22450D01*
G01X465048Y51350D02*
Y48350D01*
G01X474888Y50350D02*
Y48350D01*
G01X472920Y20450D02*
Y22450D01*
G01X476850Y49250D02*
X481850D01*
Y44250D01*
G01X459150Y21550D02*
X454150D01*
Y26550D01*
G01X476850Y21550D02*
X481850D01*
Y26550D01*
G01X485928Y54651D02*
X499928D01*
G01X485928Y67651D02*
Y54651D01*
G01X479707Y71081D02*
X479457Y71206D01*
X479165Y71289D01*
X478832D01*
X478457Y71164D01*
X478165Y70956D01*
X477957Y70706D01*
X477790Y70289D01*
X477748Y69914D01*
X477832Y69539D01*
X477957Y69289D01*
X478207Y69039D01*
X478498Y68872D01*
X478790Y68789D01*
X479082D01*
X479373Y68872D01*
X479623Y68997D01*
X479832Y69164D01*
G01X481890Y68789D02*
Y71289D01*
X481390Y70789D01*
G01Y68789D02*
X482390D01*
G01X484198Y70872D02*
X484448Y71122D01*
X484740Y71247D01*
X485073Y71289D01*
X485490Y71206D01*
X485782Y70997D01*
X485865Y70747D01*
X485823Y70497D01*
X485657Y70289D01*
X484823Y69872D01*
X484448Y69581D01*
X484198Y69164D01*
X484115Y68789D01*
X485865D01*
G01X487382Y69081D02*
X487673Y68872D01*
X488007Y68789D01*
X488340Y68872D01*
X488632Y69122D01*
X488840Y69497D01*
X488923Y69872D01*
Y70331D01*
X488840Y70706D01*
X488632Y71039D01*
X488382Y71206D01*
X488090Y71289D01*
X487757Y71206D01*
X487507Y71039D01*
X487340Y70789D01*
X487257Y70456D01*
X487340Y70164D01*
X487548Y69872D01*
X487798Y69706D01*
X488090Y69664D01*
X488423Y69747D01*
X488673Y69956D01*
X488923Y70331D01*
G01X466209Y75269D02*
X465959Y75394D01*
X465667Y75477D01*
X465334D01*
X464959Y75352D01*
X464667Y75144D01*
X464459Y74894D01*
X464292Y74477D01*
X464250Y74102D01*
X464334Y73727D01*
X464459Y73477D01*
X464709Y73227D01*
X465000Y73060D01*
X465292Y72977D01*
X465584D01*
X465875Y73060D01*
X466125Y73185D01*
X466334Y73352D01*
G01X468392Y72977D02*
Y75477D01*
X467892Y74977D01*
G01Y72977D02*
X468892D01*
G01X470575Y73477D02*
X470825Y73185D01*
X471159Y73019D01*
X471534Y72977D01*
X471867Y73019D01*
X472200Y73227D01*
X472409Y73477D01*
X472450Y73727D01*
X472367Y74019D01*
X472075Y74227D01*
X471784Y74310D01*
X471409D01*
G01X471784D02*
X472034Y74435D01*
X472242Y74644D01*
X472325Y74894D01*
X472242Y75144D01*
X472034Y75352D01*
X471659Y75477D01*
X471284Y75435D01*
X470909Y75269D01*
G01X473675Y73477D02*
X473925Y73185D01*
X474259Y73019D01*
X474634Y72977D01*
X474967Y73019D01*
X475300Y73227D01*
X475509Y73477D01*
X475550Y73727D01*
X475467Y74019D01*
X475175Y74227D01*
X474884Y74310D01*
X474509D01*
G01X474884D02*
X475134Y74435D01*
X475342Y74644D01*
X475425Y74894D01*
X475342Y75144D01*
X475134Y75352D01*
X474759Y75477D01*
X474384Y75435D01*
X474009Y75269D01*
G01X462000Y70017D02*
X459500D01*
Y71058D01*
X459625Y71392D01*
X459792Y71600D01*
X460125Y71683D01*
X460458Y71600D01*
X460667Y71350D01*
X460792Y71058D01*
Y70017D01*
G01Y71058D02*
X462000Y71683D01*
G01Y74450D02*
X459500D01*
X461292Y72908D01*
Y74992D01*
G01X461500Y76133D02*
X461792Y76383D01*
X461958Y76717D01*
X462000Y77092D01*
X461958Y77425D01*
X461750Y77758D01*
X461500Y77967D01*
X461250Y78008D01*
X460958Y77925D01*
X460750Y77633D01*
X460667Y77342D01*
Y76967D01*
G01Y77342D02*
X460542Y77592D01*
X460333Y77800D01*
X460083Y77883D01*
X459833Y77800D01*
X459625Y77592D01*
X459500Y77217D01*
X459542Y76842D01*
X459708Y76467D01*
G01X462000Y80150D02*
X459500D01*
X460000Y79650D01*
G01X462000D02*
Y80650D01*
G01X477957Y72973D02*
Y75473D01*
X478998D01*
X479332Y75348D01*
X479540Y75181D01*
X479623Y74848D01*
X479540Y74515D01*
X479290Y74306D01*
X478998Y74181D01*
X477957D01*
G01X478998D02*
X479623Y72973D01*
G01X482390D02*
Y75473D01*
X480848Y73681D01*
X482932D01*
G01X484073Y73473D02*
X484323Y73181D01*
X484657Y73015D01*
X485032Y72973D01*
X485365Y73015D01*
X485698Y73223D01*
X485907Y73473D01*
X485948Y73723D01*
X485865Y74015D01*
X485573Y74223D01*
X485282Y74306D01*
X484907D01*
G01X485282D02*
X485532Y74431D01*
X485740Y74640D01*
X485823Y74890D01*
X485740Y75140D01*
X485532Y75348D01*
X485157Y75473D01*
X484782Y75431D01*
X484407Y75265D01*
G01X487298Y75056D02*
X487548Y75306D01*
X487840Y75431D01*
X488173Y75473D01*
X488590Y75390D01*
X488882Y75181D01*
X488965Y74931D01*
X488923Y74681D01*
X488757Y74473D01*
X487923Y74056D01*
X487548Y73765D01*
X487298Y73348D01*
X487215Y72973D01*
X488965D01*
G01X466500Y77517D02*
X464000D01*
Y78558D01*
X464125Y78892D01*
X464292Y79100D01*
X464625Y79183D01*
X464958Y79100D01*
X465167Y78850D01*
X465292Y78558D01*
Y77517D01*
G01Y78558D02*
X466500Y79183D01*
G01Y81950D02*
X464000D01*
X465792Y80408D01*
Y82492D01*
G01X466500Y85050D02*
X464000D01*
X465792Y83508D01*
Y85592D01*
G01X464000Y87650D02*
X464083Y87317D01*
X464292Y87067D01*
X464542Y86900D01*
X464875Y86775D01*
X465250Y86733D01*
X465625Y86775D01*
X465958Y86900D01*
X466208Y87067D01*
X466417Y87317D01*
X466500Y87650D01*
X466417Y87983D01*
X466208Y88233D01*
X465958Y88400D01*
X465625Y88525D01*
X465250Y88567D01*
X464875Y88525D01*
X464542Y88400D01*
X464292Y88233D01*
X464083Y87983D01*
X464000Y87650D01*
G01X470500Y78017D02*
X468000D01*
Y79058D01*
X468125Y79392D01*
X468292Y79600D01*
X468625Y79683D01*
X468958Y79600D01*
X469167Y79350D01*
X469292Y79058D01*
Y78017D01*
G01Y79058D02*
X470500Y79683D01*
G01Y82450D02*
X468000D01*
X469792Y80908D01*
Y82992D01*
G01X470500Y85550D02*
X468000D01*
X469792Y84008D01*
Y86092D01*
G01X470500Y88150D02*
X468000D01*
X468500Y87650D01*
G01X470500D02*
Y88650D01*
G01X438000Y72517D02*
X435500D01*
Y73558D01*
X435625Y73892D01*
X435792Y74100D01*
X436125Y74183D01*
X436458Y74100D01*
X436667Y73850D01*
X436792Y73558D01*
Y72517D01*
G01Y73558D02*
X438000Y74183D01*
G01Y76950D02*
X435500D01*
X437292Y75408D01*
Y77492D01*
G01X437625Y78633D02*
X437833Y78883D01*
X437958Y79175D01*
X438000Y79550D01*
X437917Y79925D01*
X437750Y80217D01*
X437458Y80425D01*
X437125Y80467D01*
X436792Y80383D01*
X436583Y80175D01*
X436417Y79883D01*
X436375Y79592D01*
X436417Y79300D01*
X436583Y78925D01*
X435500Y79050D01*
Y80175D01*
G01X438000Y82567D02*
X437458Y82650D01*
X437000Y82775D01*
X436583Y82942D01*
X436125Y83150D01*
X435500Y83483D01*
Y81817D01*
G01X509232Y117921D02*
Y113921D01*
X507632D01*
X507099Y114121D01*
X506699Y114588D01*
X506566Y115121D01*
X506699Y115654D01*
X507032Y116054D01*
X507632Y116254D01*
X509232D01*
G01X504232Y117921D02*
Y115254D01*
G01Y115788D02*
X503899Y115521D01*
X503566Y115321D01*
X503099Y115254D01*
X502766Y115321D01*
X502366Y115521D01*
G01X499699Y116121D02*
X497566D01*
X497766Y115654D01*
X498099Y115388D01*
X498566Y115254D01*
X499032Y115321D01*
X499432Y115521D01*
X499699Y115988D01*
X499832Y116388D01*
Y116788D01*
X499699Y117188D01*
X499366Y117588D01*
X498966Y117854D01*
X498499Y117921D01*
X498032Y117788D01*
X497566Y117388D01*
G01X495099Y117454D02*
X494766Y117721D01*
X494299Y117921D01*
X493899D01*
X493499Y117788D01*
X493232Y117588D01*
X493099Y117321D01*
X493166Y116921D01*
X493432Y116721D01*
X494632Y116321D01*
X494899Y115854D01*
X494766Y115521D01*
X494499Y115321D01*
X494099Y115254D01*
X493699Y115321D01*
X493299Y115521D01*
G01X490499Y117454D02*
X490166Y117721D01*
X489699Y117921D01*
X489299D01*
X488899Y117788D01*
X488632Y117588D01*
X488499Y117321D01*
X488566Y116921D01*
X488832Y116721D01*
X490032Y116321D01*
X490299Y115854D01*
X490166Y115521D01*
X489899Y115321D01*
X489499Y115254D01*
X489099Y115321D01*
X488699Y115521D01*
G01X481566Y117921D02*
Y113921D01*
X479032D01*
G01X479966Y115854D02*
X481566D01*
G01X475699Y115254D02*
Y117921D01*
G01Y114188D02*
X475832Y114121D01*
Y113988D01*
X475699Y113921D01*
X475566Y113988D01*
Y114121D01*
X475699Y114188D01*
G01X471099Y113921D02*
Y117921D01*
G01X472032Y115254D02*
X470166D01*
G01X483317Y105958D02*
X483067Y106083D01*
X482775Y106166D01*
X482442D01*
X482067Y106041D01*
X481775Y105833D01*
X481567Y105583D01*
X481400Y105166D01*
X481358Y104791D01*
X481442Y104416D01*
X481567Y104166D01*
X481817Y103916D01*
X482108Y103749D01*
X482400Y103666D01*
X482692D01*
X482983Y103749D01*
X483233Y103874D01*
X483442Y104041D01*
G01X484542Y103666D02*
Y106166D01*
X486458Y103666D01*
Y106166D01*
G01X488600Y103666D02*
Y106166D01*
X488100Y105666D01*
G01Y103666D02*
X489100D01*
G01X499928Y67651D02*
X485928D01*
G01X558300Y61903D02*
X558050Y62028D01*
X557758Y62111D01*
X557425D01*
X557050Y61986D01*
X556758Y61778D01*
X556550Y61528D01*
X556383Y61111D01*
X556341Y60736D01*
X556425Y60361D01*
X556550Y60111D01*
X556800Y59861D01*
X557091Y59694D01*
X557383Y59611D01*
X557675D01*
X557966Y59694D01*
X558216Y59819D01*
X558425Y59986D01*
G01X560483Y59611D02*
Y62111D01*
X559983Y61611D01*
G01Y59611D02*
X560983D01*
G01X562666Y60111D02*
X562916Y59819D01*
X563250Y59653D01*
X563625Y59611D01*
X563958Y59653D01*
X564291Y59861D01*
X564500Y60111D01*
X564541Y60361D01*
X564458Y60653D01*
X564166Y60861D01*
X563875Y60944D01*
X563500D01*
G01X563875D02*
X564125Y61069D01*
X564333Y61278D01*
X564416Y61528D01*
X564333Y61778D01*
X564125Y61986D01*
X563750Y62111D01*
X563375Y62069D01*
X563000Y61903D01*
G01X566683Y59611D02*
X566975Y59653D01*
X567308Y59778D01*
X567516Y59986D01*
X567600Y60278D01*
X567516Y60569D01*
X567266Y60819D01*
X566891Y60944D01*
X566475D01*
X566225Y61028D01*
X566016Y61236D01*
X565933Y61528D01*
X566058Y61819D01*
X566350Y62028D01*
X566683Y62111D01*
X567016Y62028D01*
X567308Y61819D01*
X567433Y61528D01*
X567350Y61236D01*
X567141Y61028D01*
X566891Y60944D01*
X566475D01*
X566100Y60819D01*
X565850Y60569D01*
X565766Y60278D01*
X565850Y59986D01*
X566058Y59778D01*
X566391Y59653D01*
X566683Y59611D01*
G01X503728Y53459D02*
X503478Y53584D01*
X503186Y53667D01*
X502853D01*
X502478Y53542D01*
X502186Y53334D01*
X501978Y53084D01*
X501811Y52667D01*
X501769Y52292D01*
X501853Y51917D01*
X501978Y51667D01*
X502228Y51417D01*
X502519Y51250D01*
X502811Y51167D01*
X503103D01*
X503394Y51250D01*
X503644Y51375D01*
X503853Y51542D01*
G01X505911Y51167D02*
Y53667D01*
X505411Y53167D01*
G01Y51167D02*
X506411D01*
G01X508094Y51667D02*
X508344Y51375D01*
X508678Y51209D01*
X509053Y51167D01*
X509386Y51209D01*
X509719Y51417D01*
X509928Y51667D01*
X509969Y51917D01*
X509886Y52209D01*
X509594Y52417D01*
X509303Y52500D01*
X508928D01*
G01X509303D02*
X509553Y52625D01*
X509761Y52834D01*
X509844Y53084D01*
X509761Y53334D01*
X509553Y53542D01*
X509178Y53667D01*
X508803Y53625D01*
X508428Y53459D01*
G01X512111Y53667D02*
X511778Y53584D01*
X511528Y53375D01*
X511361Y53125D01*
X511236Y52792D01*
X511194Y52417D01*
X511236Y52042D01*
X511361Y51709D01*
X511528Y51459D01*
X511778Y51250D01*
X512111Y51167D01*
X512444Y51250D01*
X512694Y51459D01*
X512861Y51709D01*
X512986Y52042D01*
X513028Y52417D01*
X512986Y52792D01*
X512861Y53125D01*
X512694Y53375D01*
X512444Y53584D01*
X512111Y53667D01*
G01X501734Y55052D02*
Y57552D01*
X502775D01*
X503109Y57427D01*
X503317Y57260D01*
X503400Y56927D01*
X503317Y56594D01*
X503067Y56385D01*
X502775Y56260D01*
X501734D01*
G01X502775D02*
X503400Y55052D01*
G01X506167D02*
Y57552D01*
X504625Y55760D01*
X506709D01*
G01X507850Y55552D02*
X508100Y55260D01*
X508434Y55094D01*
X508809Y55052D01*
X509142Y55094D01*
X509475Y55302D01*
X509684Y55552D01*
X509725Y55802D01*
X509642Y56094D01*
X509350Y56302D01*
X509059Y56385D01*
X508684D01*
G01X509059D02*
X509309Y56510D01*
X509517Y56719D01*
X509600Y56969D01*
X509517Y57219D01*
X509309Y57427D01*
X508934Y57552D01*
X508559Y57510D01*
X508184Y57344D01*
G01X511159Y55344D02*
X511450Y55135D01*
X511784Y55052D01*
X512117Y55135D01*
X512409Y55385D01*
X512617Y55760D01*
X512700Y56135D01*
Y56594D01*
X512617Y56969D01*
X512409Y57302D01*
X512159Y57469D01*
X511867Y57552D01*
X511534Y57469D01*
X511284Y57302D01*
X511117Y57052D01*
X511034Y56719D01*
X511117Y56427D01*
X511325Y56135D01*
X511575Y55969D01*
X511867Y55927D01*
X512200Y56010D01*
X512450Y56219D01*
X512700Y56594D01*
G01X562314Y34264D02*
Y36764D01*
X563355D01*
X563689Y36639D01*
X563897Y36472D01*
X563980Y36139D01*
X563897Y35806D01*
X563647Y35597D01*
X563355Y35472D01*
X562314D01*
G01X563355D02*
X563980Y34264D01*
G01X565330Y34639D02*
X565580Y34431D01*
X565872Y34306D01*
X566247Y34264D01*
X566622Y34347D01*
X566914Y34514D01*
X567122Y34806D01*
X567164Y35139D01*
X567080Y35472D01*
X566872Y35681D01*
X566580Y35847D01*
X566289Y35889D01*
X565997Y35847D01*
X565622Y35681D01*
X565747Y36764D01*
X566872D01*
G01X569347Y34264D02*
Y36764D01*
X568847Y36264D01*
G01Y34264D02*
X569847D01*
G01X572447D02*
X572739Y34306D01*
X573072Y34431D01*
X573280Y34639D01*
X573364Y34931D01*
X573280Y35222D01*
X573030Y35472D01*
X572655Y35597D01*
X572239D01*
X571989Y35681D01*
X571780Y35889D01*
X571697Y36181D01*
X571822Y36472D01*
X572114Y36681D01*
X572447Y36764D01*
X572780Y36681D01*
X573072Y36472D01*
X573197Y36181D01*
X573114Y35889D01*
X572905Y35681D01*
X572655Y35597D01*
X572239D01*
X571864Y35472D01*
X571614Y35222D01*
X571530Y34931D01*
X571614Y34639D01*
X571822Y34431D01*
X572155Y34306D01*
X572447Y34264D01*
G01X563214Y30264D02*
Y32764D01*
X564255D01*
X564589Y32639D01*
X564797Y32472D01*
X564880Y32139D01*
X564797Y31806D01*
X564547Y31597D01*
X564255Y31472D01*
X563214D01*
G01X564255D02*
X564880Y30264D01*
G01X566230Y30639D02*
X566480Y30431D01*
X566772Y30306D01*
X567147Y30264D01*
X567522Y30347D01*
X567814Y30514D01*
X568022Y30806D01*
X568064Y31139D01*
X567980Y31472D01*
X567772Y31681D01*
X567480Y31847D01*
X567189Y31889D01*
X566897Y31847D01*
X566522Y31681D01*
X566647Y32764D01*
X567772D01*
G01X569455Y32347D02*
X569705Y32597D01*
X569997Y32722D01*
X570330Y32764D01*
X570747Y32681D01*
X571039Y32472D01*
X571122Y32222D01*
X571080Y31972D01*
X570914Y31764D01*
X570080Y31347D01*
X569705Y31056D01*
X569455Y30639D01*
X569372Y30264D01*
X571122D01*
G01X573347D02*
Y32764D01*
X572847Y32264D01*
G01Y30264D02*
X573847D01*
G01X563214Y42264D02*
Y44764D01*
X564255D01*
X564589Y44639D01*
X564797Y44472D01*
X564880Y44139D01*
X564797Y43806D01*
X564547Y43597D01*
X564255Y43472D01*
X563214D01*
G01X564255D02*
X564880Y42264D01*
G01X566230Y42639D02*
X566480Y42431D01*
X566772Y42306D01*
X567147Y42264D01*
X567522Y42347D01*
X567814Y42514D01*
X568022Y42806D01*
X568064Y43139D01*
X567980Y43472D01*
X567772Y43681D01*
X567480Y43847D01*
X567189Y43889D01*
X566897Y43847D01*
X566522Y43681D01*
X566647Y44764D01*
X567772D01*
G01X570247Y42264D02*
Y44764D01*
X569747Y44264D01*
G01Y42264D02*
X570747D01*
G01X572430Y42764D02*
X572680Y42472D01*
X573014Y42306D01*
X573389Y42264D01*
X573722Y42306D01*
X574055Y42514D01*
X574264Y42764D01*
X574305Y43014D01*
X574222Y43306D01*
X573930Y43514D01*
X573639Y43597D01*
X573264D01*
G01X573639D02*
X573889Y43722D01*
X574097Y43931D01*
X574180Y44181D01*
X574097Y44431D01*
X573889Y44639D01*
X573514Y44764D01*
X573139Y44722D01*
X572764Y44556D01*
G01X501734Y62952D02*
Y65452D01*
X502775D01*
X503109Y65327D01*
X503317Y65160D01*
X503400Y64827D01*
X503317Y64494D01*
X503067Y64285D01*
X502775Y64160D01*
X501734D01*
G01X502775D02*
X503400Y62952D01*
G01X506167D02*
Y65452D01*
X504625Y63660D01*
X506709D01*
G01X507850Y63452D02*
X508100Y63160D01*
X508434Y62994D01*
X508809Y62952D01*
X509142Y62994D01*
X509475Y63202D01*
X509684Y63452D01*
X509725Y63702D01*
X509642Y63994D01*
X509350Y64202D01*
X509059Y64285D01*
X508684D01*
G01X509059D02*
X509309Y64410D01*
X509517Y64619D01*
X509600Y64869D01*
X509517Y65119D01*
X509309Y65327D01*
X508934Y65452D01*
X508559Y65410D01*
X508184Y65244D01*
G01X512367Y62952D02*
Y65452D01*
X510825Y63660D01*
X512909D01*
G01X533000Y52648D02*
Y56648D01*
X525600D01*
G01X514229Y63141D02*
Y65641D01*
X515270D01*
X515604Y65516D01*
X515812Y65349D01*
X515895Y65016D01*
X515812Y64683D01*
X515562Y64474D01*
X515270Y64349D01*
X514229D01*
G01X515270D02*
X515895Y63141D01*
G01X518662D02*
Y65641D01*
X517120Y63849D01*
X519204D01*
G01X521762Y63141D02*
Y65641D01*
X520220Y63849D01*
X522304D01*
G01X523445Y63641D02*
X523695Y63349D01*
X524029Y63183D01*
X524404Y63141D01*
X524737Y63183D01*
X525070Y63391D01*
X525279Y63641D01*
X525320Y63891D01*
X525237Y64183D01*
X524945Y64391D01*
X524654Y64474D01*
X524279D01*
G01X524654D02*
X524904Y64599D01*
X525112Y64808D01*
X525195Y65058D01*
X525112Y65308D01*
X524904Y65516D01*
X524529Y65641D01*
X524154Y65599D01*
X523779Y65433D01*
G01X532997Y48148D02*
Y52148D01*
X525597D01*
G01X510797Y4106D02*
X508297D01*
Y5147D01*
X508422Y5481D01*
X508589Y5689D01*
X508922Y5772D01*
X509255Y5689D01*
X509464Y5439D01*
X509589Y5147D01*
Y4106D01*
G01Y5147D02*
X510797Y5772D01*
G01Y8539D02*
X508297D01*
X510089Y6997D01*
Y9081D01*
G01X510422Y10222D02*
X510630Y10472D01*
X510755Y10764D01*
X510797Y11139D01*
X510714Y11514D01*
X510547Y11806D01*
X510255Y12014D01*
X509922Y12056D01*
X509589Y11972D01*
X509380Y11764D01*
X509214Y11472D01*
X509172Y11181D01*
X509214Y10889D01*
X509380Y10514D01*
X508297Y10639D01*
Y11764D01*
G01X510422Y13322D02*
X510630Y13572D01*
X510755Y13864D01*
X510797Y14239D01*
X510714Y14614D01*
X510547Y14906D01*
X510255Y15114D01*
X509922Y15156D01*
X509589Y15072D01*
X509380Y14864D01*
X509214Y14572D01*
X509172Y14281D01*
X509214Y13989D01*
X509380Y13614D01*
X508297Y13739D01*
Y14864D01*
G01X504031Y5953D02*
X503906Y5703D01*
X503823Y5411D01*
Y5078D01*
X503948Y4703D01*
X504156Y4411D01*
X504406Y4203D01*
X504823Y4036D01*
X505198Y3994D01*
X505573Y4078D01*
X505823Y4203D01*
X506073Y4453D01*
X506240Y4744D01*
X506323Y5036D01*
Y5328D01*
X506240Y5619D01*
X506115Y5869D01*
X505948Y6078D01*
G01X506323Y8136D02*
X503823D01*
X504323Y7636D01*
G01X506323D02*
Y8636D01*
G01Y11736D02*
X503823D01*
X505615Y10194D01*
Y12278D01*
G01X505281Y13544D02*
X504990Y13836D01*
X504823Y14086D01*
X504740Y14419D01*
X504823Y14711D01*
X504990Y14919D01*
X505240Y15086D01*
X505531Y15128D01*
X505781Y15086D01*
X506031Y14919D01*
X506240Y14669D01*
X506323Y14378D01*
X506240Y14044D01*
X505990Y13753D01*
X505615Y13586D01*
X505198Y13544D01*
X504656Y13628D01*
X504365Y13753D01*
X504073Y13961D01*
X503865Y14253D01*
X503823Y14544D01*
X503906Y14836D01*
X504115Y15044D01*
G01X563564Y40556D02*
X563314Y40681D01*
X563022Y40764D01*
X562689D01*
X562314Y40639D01*
X562022Y40431D01*
X561814Y40181D01*
X561647Y39764D01*
X561605Y39389D01*
X561689Y39014D01*
X561814Y38764D01*
X562064Y38514D01*
X562355Y38347D01*
X562647Y38264D01*
X562939D01*
X563230Y38347D01*
X563480Y38472D01*
X563689Y38639D01*
G01X564955Y40347D02*
X565205Y40597D01*
X565497Y40722D01*
X565830Y40764D01*
X566247Y40681D01*
X566539Y40472D01*
X566622Y40222D01*
X566580Y39972D01*
X566414Y39764D01*
X565580Y39347D01*
X565205Y39056D01*
X564955Y38639D01*
X564872Y38264D01*
X566622D01*
G01X568847Y40764D02*
X568514Y40681D01*
X568264Y40472D01*
X568097Y40222D01*
X567972Y39889D01*
X567930Y39514D01*
X567972Y39139D01*
X568097Y38806D01*
X568264Y38556D01*
X568514Y38347D01*
X568847Y38264D01*
X569180Y38347D01*
X569430Y38556D01*
X569597Y38806D01*
X569722Y39139D01*
X569764Y39514D01*
X569722Y39889D01*
X569597Y40222D01*
X569430Y40472D01*
X569180Y40681D01*
X568847Y40764D01*
G01X571239Y38556D02*
X571530Y38347D01*
X571864Y38264D01*
X572197Y38347D01*
X572489Y38597D01*
X572697Y38972D01*
X572780Y39347D01*
Y39806D01*
X572697Y40181D01*
X572489Y40514D01*
X572239Y40681D01*
X571947Y40764D01*
X571614Y40681D01*
X571364Y40514D01*
X571197Y40264D01*
X571114Y39931D01*
X571197Y39639D01*
X571405Y39347D01*
X571655Y39181D01*
X571947Y39139D01*
X572280Y39222D01*
X572530Y39431D01*
X572780Y39806D01*
G01X513182Y12897D02*
Y15397D01*
X514223D01*
X514557Y15272D01*
X514765Y15105D01*
X514848Y14772D01*
X514765Y14439D01*
X514515Y14230D01*
X514223Y14105D01*
X513182D01*
G01X514223D02*
X514848Y12897D01*
G01X517615D02*
Y15397D01*
X516073Y13605D01*
X518157D01*
G01X519298Y13272D02*
X519548Y13064D01*
X519840Y12939D01*
X520215Y12897D01*
X520590Y12980D01*
X520882Y13147D01*
X521090Y13439D01*
X521132Y13772D01*
X521048Y14105D01*
X520840Y14314D01*
X520548Y14480D01*
X520257Y14522D01*
X519965Y14480D01*
X519590Y14314D01*
X519715Y15397D01*
X520840D01*
G01X523315D02*
X522982Y15314D01*
X522732Y15105D01*
X522565Y14855D01*
X522440Y14522D01*
X522398Y14147D01*
X522440Y13772D01*
X522565Y13439D01*
X522732Y13189D01*
X522982Y12980D01*
X523315Y12897D01*
X523648Y12980D01*
X523898Y13189D01*
X524065Y13439D01*
X524190Y13772D01*
X524232Y14147D01*
X524190Y14522D01*
X524065Y14855D01*
X523898Y15105D01*
X523648Y15314D01*
X523315Y15397D01*
G01X525472Y23180D02*
X520272D01*
G01X525472Y30180D02*
X517672D01*
G01X525472Y23180D02*
Y30180D01*
G01X512072Y23180D02*
X520772D01*
G01X512072Y30180D02*
Y23180D01*
G01X518472Y30180D02*
X512072D01*
G01X502517Y46500D02*
Y49000D01*
X503558D01*
X503892Y48875D01*
X504100Y48708D01*
X504183Y48375D01*
X504100Y48042D01*
X503850Y47833D01*
X503558Y47708D01*
X502517D01*
G01X503558D02*
X504183Y46500D01*
G01X506367D02*
X506450Y47042D01*
X506575Y47500D01*
X506742Y47917D01*
X506950Y48375D01*
X507283Y49000D01*
X505617D01*
G01X509550Y46500D02*
Y49000D01*
X509050Y48500D01*
G01Y46500D02*
X510050D01*
G01X512650Y49000D02*
X512317Y48917D01*
X512067Y48708D01*
X511900Y48458D01*
X511775Y48125D01*
X511733Y47750D01*
X511775Y47375D01*
X511900Y47042D01*
X512067Y46792D01*
X512317Y46583D01*
X512650Y46500D01*
X512983Y46583D01*
X513233Y46792D01*
X513400Y47042D01*
X513525Y47375D01*
X513567Y47750D01*
X513525Y48125D01*
X513400Y48458D01*
X513233Y48708D01*
X512983Y48917D01*
X512650Y49000D01*
G01X514354Y38593D02*
X509154D01*
G01X514354Y45593D02*
X506554D01*
G01X514354Y38593D02*
Y45593D01*
G01X500954Y38593D02*
X509654D01*
G01X500954Y45593D02*
Y38593D01*
G01X507354Y45593D02*
X500954D01*
G01X502017Y16500D02*
Y19000D01*
X503058D01*
X503392Y18875D01*
X503600Y18708D01*
X503683Y18375D01*
X503600Y18042D01*
X503350Y17833D01*
X503058Y17708D01*
X502017D01*
G01X503058D02*
X503683Y16500D01*
G01X505867D02*
X505950Y17042D01*
X506075Y17500D01*
X506242Y17917D01*
X506450Y18375D01*
X506783Y19000D01*
X505117D01*
G01X509050D02*
X508717Y18917D01*
X508467Y18708D01*
X508300Y18458D01*
X508175Y18125D01*
X508133Y17750D01*
X508175Y17375D01*
X508300Y17042D01*
X508467Y16792D01*
X508717Y16583D01*
X509050Y16500D01*
X509383Y16583D01*
X509633Y16792D01*
X509800Y17042D01*
X509925Y17375D01*
X509967Y17750D01*
X509925Y18125D01*
X509800Y18458D01*
X509633Y18708D01*
X509383Y18917D01*
X509050Y19000D01*
G01X511442Y16792D02*
X511733Y16583D01*
X512067Y16500D01*
X512400Y16583D01*
X512692Y16833D01*
X512900Y17208D01*
X512983Y17583D01*
Y18042D01*
X512900Y18417D01*
X512692Y18750D01*
X512442Y18917D01*
X512150Y19000D01*
X511817Y18917D01*
X511567Y18750D01*
X511400Y18500D01*
X511317Y18167D01*
X511400Y17875D01*
X511608Y17583D01*
X511858Y17417D01*
X512150Y17375D01*
X512483Y17458D01*
X512733Y17667D01*
X512983Y18042D01*
G01X500965Y37931D02*
X506165Y37932D01*
G01X500965Y30933D02*
X508765Y30932D01*
G01X500965Y37931D02*
Y30933D01*
G01X514365Y37931D02*
X505665Y37932D01*
G01X514365Y30933D02*
Y37931D01*
G01X507965Y30932D02*
X514365Y30933D01*
G01X526448Y60531D02*
X535548D01*
Y82331D01*
X526448D01*
Y60531D01*
G01X501734Y58952D02*
Y61452D01*
X502734D01*
X503067Y61327D01*
X503317Y61035D01*
X503400Y60702D01*
X503317Y60369D01*
X503109Y60119D01*
X502734Y59994D01*
X501734D01*
G01X505667Y58952D02*
Y61452D01*
X505167Y60952D01*
G01Y58952D02*
X506167D01*
G01X553124Y55834D02*
Y58334D01*
X554165D01*
X554499Y58209D01*
X554707Y58042D01*
X554790Y57709D01*
X554707Y57376D01*
X554457Y57167D01*
X554165Y57042D01*
X553124D01*
G01X554165D02*
X554790Y55834D01*
G01X557557D02*
Y58334D01*
X556015Y56542D01*
X558099D01*
G01X560657Y55834D02*
Y58334D01*
X559115Y56542D01*
X561199D01*
G01X563757Y55834D02*
Y58334D01*
X562215Y56542D01*
X564299D01*
G01X549995Y57648D02*
Y44648D01*
X534495D01*
Y57648D01*
X549995D01*
G01X541664Y15981D02*
X541331Y16023D01*
X541039Y16189D01*
X540789Y16439D01*
X540622Y16731D01*
X540539Y17064D01*
Y17398D01*
X540622Y17731D01*
X540789Y18023D01*
X541039Y18273D01*
X541331Y18439D01*
X541664Y18481D01*
X541997Y18439D01*
X542289Y18273D01*
X542539Y18023D01*
X542706Y17731D01*
X542789Y17398D01*
Y17064D01*
X542706Y16731D01*
X542539Y16439D01*
X542289Y16189D01*
X541997Y16023D01*
X541664Y15981D01*
G01X541997Y16648D02*
X542497Y15981D01*
G01X543847Y16356D02*
X544097Y16148D01*
X544389Y16023D01*
X544764Y15981D01*
X545139Y16064D01*
X545431Y16231D01*
X545639Y16523D01*
X545681Y16856D01*
X545597Y17189D01*
X545389Y17398D01*
X545097Y17564D01*
X544806Y17606D01*
X544514Y17564D01*
X544139Y17398D01*
X544264Y18481D01*
X545389D01*
G01X556893Y20783D02*
Y42483D01*
G01X526893Y20783D02*
X556893D01*
G01X526893Y42483D02*
Y20783D01*
G01X556893Y42483D02*
X526893D01*
G01X499928Y54651D02*
Y67651D01*
G01X513898Y73757D02*
X513773Y73507D01*
X513690Y73215D01*
Y72882D01*
X513815Y72507D01*
X514023Y72215D01*
X514273Y72007D01*
X514690Y71840D01*
X515065Y71798D01*
X515440Y71882D01*
X515690Y72007D01*
X515940Y72257D01*
X516107Y72548D01*
X516190Y72840D01*
Y73132D01*
X516107Y73423D01*
X515982Y73673D01*
X515815Y73882D01*
G01X516190Y75940D02*
X513690D01*
X514190Y75440D01*
G01X516190D02*
Y76440D01*
G01X515690Y78123D02*
X515982Y78373D01*
X516148Y78707D01*
X516190Y79082D01*
X516148Y79415D01*
X515940Y79748D01*
X515690Y79957D01*
X515440Y79998D01*
X515148Y79915D01*
X514940Y79623D01*
X514857Y79332D01*
Y78957D01*
G01Y79332D02*
X514732Y79582D01*
X514523Y79790D01*
X514273Y79873D01*
X514023Y79790D01*
X513815Y79582D01*
X513690Y79207D01*
X513732Y78832D01*
X513898Y78457D01*
G01X516190Y82640D02*
X513690D01*
X515482Y81098D01*
Y83182D01*
G01X514229Y67135D02*
Y69635D01*
X515270D01*
X515604Y69510D01*
X515812Y69343D01*
X515895Y69010D01*
X515812Y68677D01*
X515562Y68468D01*
X515270Y68343D01*
X514229D01*
G01X515270D02*
X515895Y67135D01*
G01X518662D02*
Y69635D01*
X517120Y67843D01*
X519204D01*
G01X521762Y67135D02*
Y69635D01*
X520220Y67843D01*
X522304D01*
G01X523570Y69218D02*
X523820Y69468D01*
X524112Y69593D01*
X524445Y69635D01*
X524862Y69552D01*
X525154Y69343D01*
X525237Y69093D01*
X525195Y68843D01*
X525029Y68635D01*
X524195Y68218D01*
X523820Y67927D01*
X523570Y67510D01*
X523487Y67135D01*
X525237D01*
G01X571814Y67109D02*
X569314D01*
Y68150D01*
X569439Y68484D01*
X569606Y68692D01*
X569939Y68775D01*
X570272Y68692D01*
X570481Y68442D01*
X570606Y68150D01*
Y67109D01*
G01Y68150D02*
X571814Y68775D01*
G01X571439Y70125D02*
X571647Y70375D01*
X571772Y70667D01*
X571814Y71042D01*
X571731Y71417D01*
X571564Y71709D01*
X571272Y71917D01*
X570939Y71959D01*
X570606Y71875D01*
X570397Y71667D01*
X570231Y71375D01*
X570189Y71084D01*
X570231Y70792D01*
X570397Y70417D01*
X569314Y70542D01*
Y71667D01*
G01X571814Y74142D02*
X569314D01*
X569814Y73642D01*
G01X571814D02*
Y74642D01*
G01Y77742D02*
X569314D01*
X571106Y76200D01*
Y78284D01*
G01X538555Y81408D02*
X538430Y81158D01*
X538347Y80866D01*
Y80533D01*
X538472Y80158D01*
X538680Y79866D01*
X538930Y79658D01*
X539347Y79491D01*
X539722Y79449D01*
X540097Y79533D01*
X540347Y79658D01*
X540597Y79908D01*
X540764Y80199D01*
X540847Y80491D01*
Y80783D01*
X540764Y81074D01*
X540639Y81324D01*
X540472Y81533D01*
G01X540847Y83591D02*
X538347D01*
X538847Y83091D01*
G01X540847D02*
Y84091D01*
G01X540347Y85774D02*
X540639Y86024D01*
X540805Y86358D01*
X540847Y86733D01*
X540805Y87066D01*
X540597Y87399D01*
X540347Y87608D01*
X540097Y87649D01*
X539805Y87566D01*
X539597Y87274D01*
X539514Y86983D01*
Y86608D01*
G01Y86983D02*
X539389Y87233D01*
X539180Y87441D01*
X538930Y87524D01*
X538680Y87441D01*
X538472Y87233D01*
X538347Y86858D01*
X538389Y86483D01*
X538555Y86108D01*
G01X540555Y89083D02*
X540764Y89374D01*
X540847Y89708D01*
X540764Y90041D01*
X540514Y90333D01*
X540139Y90541D01*
X539764Y90624D01*
X539305D01*
X538930Y90541D01*
X538597Y90333D01*
X538430Y90083D01*
X538347Y89791D01*
X538430Y89458D01*
X538597Y89208D01*
X538847Y89041D01*
X539180Y88958D01*
X539472Y89041D01*
X539764Y89249D01*
X539930Y89499D01*
X539972Y89791D01*
X539889Y90124D01*
X539680Y90374D01*
X539305Y90624D01*
G01X531932Y85964D02*
X529432D01*
Y86798D01*
X529557Y87131D01*
X529724Y87381D01*
X529974Y87589D01*
X530265Y87756D01*
X530682Y87798D01*
X531099Y87756D01*
X531390Y87589D01*
X531640Y87381D01*
X531807Y87131D01*
X531932Y86798D01*
Y85964D01*
G01Y89981D02*
X529432D01*
X529932Y89481D01*
G01X531932D02*
Y90481D01*
G01X501734Y66952D02*
Y69452D01*
X502734D01*
X503067Y69327D01*
X503317Y69035D01*
X503400Y68702D01*
X503317Y68369D01*
X503109Y68119D01*
X502734Y67994D01*
X501734D01*
G01X505667Y66952D02*
X505334Y66994D01*
X505042Y67160D01*
X504792Y67410D01*
X504625Y67702D01*
X504542Y68035D01*
Y68369D01*
X504625Y68702D01*
X504792Y68994D01*
X505042Y69244D01*
X505334Y69410D01*
X505667Y69452D01*
X506000Y69410D01*
X506292Y69244D01*
X506542Y68994D01*
X506709Y68702D01*
X506792Y68369D01*
Y68035D01*
X506709Y67702D01*
X506542Y67410D01*
X506292Y67160D01*
X506000Y66994D01*
X505667Y66952D01*
G01X506000Y67619D02*
X506500Y66952D01*
G01X508767D02*
Y69452D01*
X508267Y68952D01*
G01Y66952D02*
X509267D01*
G01X542394Y203859D02*
X541861Y204192D01*
X541261Y204392D01*
X540727D01*
X540194Y204192D01*
X539794Y203859D01*
X539594Y203392D01*
X539727Y202925D01*
X540061Y202525D01*
X540661Y202259D01*
X541461Y202125D01*
X541927Y201859D01*
X542127Y201392D01*
X541994Y200925D01*
X541661Y200592D01*
X541194Y200392D01*
X540727D01*
X540261Y200525D01*
X539861Y200859D01*
G01X536394Y204392D02*
Y200392D01*
G01X531794Y201725D02*
Y204392D01*
G01Y200659D02*
X531927Y200592D01*
Y200459D01*
X531794Y200392D01*
X531661Y200459D01*
Y200592D01*
X531794Y200659D01*
G01X527194Y200392D02*
Y204392D01*
G01X528127Y201725D02*
X526261D01*
G01X551691Y758540D02*
Y762540D01*
X550891Y761740D01*
G01Y758540D02*
X552491D01*
G01X626578Y21230D02*
X626453Y20980D01*
X626370Y20688D01*
Y20355D01*
X626495Y19980D01*
X626703Y19688D01*
X626953Y19480D01*
X627370Y19313D01*
X627745Y19271D01*
X628120Y19355D01*
X628370Y19480D01*
X628620Y19730D01*
X628787Y20021D01*
X628870Y20313D01*
Y20605D01*
X628787Y20896D01*
X628662Y21146D01*
X628495Y21355D01*
G01X626787Y22621D02*
X626537Y22871D01*
X626412Y23163D01*
X626370Y23496D01*
X626453Y23913D01*
X626662Y24205D01*
X626912Y24288D01*
X627162Y24246D01*
X627370Y24080D01*
X627787Y23246D01*
X628078Y22871D01*
X628495Y22621D01*
X628870Y22538D01*
Y24288D01*
G01Y26513D02*
X626370D01*
X626870Y26013D01*
G01X628870D02*
Y27013D01*
G01X626370Y29613D02*
X626453Y29280D01*
X626662Y29030D01*
X626912Y28863D01*
X627245Y28738D01*
X627620Y28696D01*
X627995Y28738D01*
X628328Y28863D01*
X628578Y29030D01*
X628787Y29280D01*
X628870Y29613D01*
X628787Y29946D01*
X628578Y30196D01*
X628328Y30363D01*
X627995Y30488D01*
X627620Y30530D01*
X627245Y30488D01*
X626912Y30363D01*
X626662Y30196D01*
X626453Y29946D01*
X626370Y29613D01*
G01X582808Y19267D02*
X582683Y19017D01*
X582600Y18725D01*
Y18392D01*
X582725Y18017D01*
X582933Y17725D01*
X583183Y17517D01*
X583600Y17350D01*
X583975Y17308D01*
X584350Y17392D01*
X584600Y17517D01*
X584850Y17767D01*
X585017Y18058D01*
X585100Y18350D01*
Y18642D01*
X585017Y18933D01*
X584892Y19183D01*
X584725Y19392D01*
G01X583017Y20658D02*
X582767Y20908D01*
X582642Y21200D01*
X582600Y21533D01*
X582683Y21950D01*
X582892Y22242D01*
X583142Y22325D01*
X583392Y22283D01*
X583600Y22117D01*
X584017Y21283D01*
X584308Y20908D01*
X584725Y20658D01*
X585100Y20575D01*
Y22325D01*
G01X582600Y24550D02*
X582683Y24217D01*
X582892Y23967D01*
X583142Y23800D01*
X583475Y23675D01*
X583850Y23633D01*
X584225Y23675D01*
X584558Y23800D01*
X584808Y23967D01*
X585017Y24217D01*
X585100Y24550D01*
X585017Y24883D01*
X584808Y25133D01*
X584558Y25300D01*
X584225Y25425D01*
X583850Y25467D01*
X583475Y25425D01*
X583142Y25300D01*
X582892Y25133D01*
X582683Y24883D01*
X582600Y24550D01*
G01X585100Y27650D02*
X585058Y27942D01*
X584933Y28275D01*
X584725Y28483D01*
X584433Y28567D01*
X584142Y28483D01*
X583892Y28233D01*
X583767Y27858D01*
Y27442D01*
X583683Y27192D01*
X583475Y26983D01*
X583183Y26900D01*
X582892Y27025D01*
X582683Y27317D01*
X582600Y27650D01*
X582683Y27983D01*
X582892Y28275D01*
X583183Y28400D01*
X583475Y28317D01*
X583683Y28108D01*
X583767Y27858D01*
Y27442D01*
X583892Y27067D01*
X584142Y26817D01*
X584433Y26733D01*
X584725Y26817D01*
X584933Y27025D01*
X585058Y27358D01*
X585100Y27650D01*
G01X592504Y55267D02*
X596504D01*
Y62667D01*
G01X612819Y58131D02*
Y60631D01*
X613860D01*
X614194Y60506D01*
X614402Y60339D01*
X614485Y60006D01*
X614402Y59673D01*
X614152Y59464D01*
X613860Y59339D01*
X612819D01*
G01X613860D02*
X614485Y58131D01*
G01X615835Y58506D02*
X616085Y58298D01*
X616377Y58173D01*
X616752Y58131D01*
X617127Y58214D01*
X617419Y58381D01*
X617627Y58673D01*
X617669Y59006D01*
X617585Y59339D01*
X617377Y59548D01*
X617085Y59714D01*
X616794Y59756D01*
X616502Y59714D01*
X616127Y59548D01*
X616252Y60631D01*
X617377D01*
G01X619852Y58131D02*
Y60631D01*
X619352Y60131D01*
G01Y58131D02*
X620352D01*
G01X622869D02*
X622952Y58673D01*
X623077Y59131D01*
X623244Y59548D01*
X623452Y60006D01*
X623785Y60631D01*
X622119D01*
G01X623996Y53138D02*
Y57138D01*
X616596D01*
G01X587304Y39467D02*
Y43467D01*
X579904D01*
G01X634647Y54907D02*
X638647D01*
Y62307D01*
G01X584747Y35207D02*
Y39207D01*
X577347D01*
G01X595500Y12017D02*
X593000D01*
Y13058D01*
X593125Y13392D01*
X593292Y13600D01*
X593625Y13683D01*
X593958Y13600D01*
X594167Y13350D01*
X594292Y13058D01*
Y12017D01*
G01Y13058D02*
X595500Y13683D01*
G01X595125Y15033D02*
X595333Y15283D01*
X595458Y15575D01*
X595500Y15950D01*
X595417Y16325D01*
X595250Y16617D01*
X594958Y16825D01*
X594625Y16867D01*
X594292Y16783D01*
X594083Y16575D01*
X593917Y16283D01*
X593875Y15992D01*
X593917Y15700D01*
X594083Y15325D01*
X593000Y15450D01*
Y16575D01*
G01X593417Y18258D02*
X593167Y18508D01*
X593042Y18800D01*
X593000Y19133D01*
X593083Y19550D01*
X593292Y19842D01*
X593542Y19925D01*
X593792Y19883D01*
X594000Y19717D01*
X594417Y18883D01*
X594708Y18508D01*
X595125Y18258D01*
X595500Y18175D01*
Y19925D01*
G01X593417Y21358D02*
X593167Y21608D01*
X593042Y21900D01*
X593000Y22233D01*
X593083Y22650D01*
X593292Y22942D01*
X593542Y23025D01*
X593792Y22983D01*
X594000Y22817D01*
X594417Y21983D01*
X594708Y21608D01*
X595125Y21358D01*
X595500Y21275D01*
Y23025D01*
G01X596541Y34981D02*
X592541D01*
Y27581D01*
G01X592347Y62707D02*
X588347D01*
Y55307D01*
G01X584020Y52435D02*
Y48435D01*
X591420D01*
G01X601609Y17564D02*
X601484Y17314D01*
X601401Y17022D01*
Y16689D01*
X601526Y16314D01*
X601734Y16022D01*
X601984Y15814D01*
X602401Y15647D01*
X602776Y15605D01*
X603151Y15689D01*
X603401Y15814D01*
X603651Y16064D01*
X603818Y16355D01*
X603901Y16647D01*
Y16939D01*
X603818Y17230D01*
X603693Y17480D01*
X603526Y17689D01*
G01X601818Y18955D02*
X601568Y19205D01*
X601443Y19497D01*
X601401Y19830D01*
X601484Y20247D01*
X601693Y20539D01*
X601943Y20622D01*
X602193Y20580D01*
X602401Y20414D01*
X602818Y19580D01*
X603109Y19205D01*
X603526Y18955D01*
X603901Y18872D01*
Y20622D01*
G01Y22847D02*
X601401D01*
X601901Y22347D01*
G01X603901D02*
Y23347D01*
G01X603401Y25030D02*
X603693Y25280D01*
X603859Y25614D01*
X603901Y25989D01*
X603859Y26322D01*
X603651Y26655D01*
X603401Y26864D01*
X603151Y26905D01*
X602859Y26822D01*
X602651Y26530D01*
X602568Y26239D01*
Y25864D01*
G01Y26239D02*
X602443Y26489D01*
X602234Y26697D01*
X601984Y26780D01*
X601734Y26697D01*
X601526Y26489D01*
X601401Y26114D01*
X601443Y25739D01*
X601609Y25364D01*
G01X611301Y15217D02*
Y17717D01*
X612342D01*
X612676Y17592D01*
X612884Y17425D01*
X612967Y17092D01*
X612884Y16759D01*
X612634Y16550D01*
X612342Y16425D01*
X611301D01*
G01X612342D02*
X612967Y15217D01*
G01X614317Y15592D02*
X614567Y15384D01*
X614859Y15259D01*
X615234Y15217D01*
X615609Y15300D01*
X615901Y15467D01*
X616109Y15759D01*
X616151Y16092D01*
X616067Y16425D01*
X615859Y16634D01*
X615567Y16800D01*
X615276Y16842D01*
X614984Y16800D01*
X614609Y16634D01*
X614734Y17717D01*
X615859D01*
G01X617542Y17300D02*
X617792Y17550D01*
X618084Y17675D01*
X618417Y17717D01*
X618834Y17634D01*
X619126Y17425D01*
X619209Y17175D01*
X619167Y16925D01*
X619001Y16717D01*
X618167Y16300D01*
X617792Y16009D01*
X617542Y15592D01*
X617459Y15217D01*
X619209D01*
G01X621434Y17717D02*
X621101Y17634D01*
X620851Y17425D01*
X620684Y17175D01*
X620559Y16842D01*
X620517Y16467D01*
X620559Y16092D01*
X620684Y15759D01*
X620851Y15509D01*
X621101Y15300D01*
X621434Y15217D01*
X621767Y15300D01*
X622017Y15509D01*
X622184Y15759D01*
X622309Y16092D01*
X622351Y16467D01*
X622309Y16842D01*
X622184Y17175D01*
X622017Y17425D01*
X621767Y17634D01*
X621434Y17717D01*
G01X619757Y20472D02*
X614557Y20471D01*
G01X619757Y27470D02*
X611957Y27471D01*
G01X619757Y20472D02*
Y27470D01*
G01X606357Y20472D02*
X615057Y20471D01*
G01X606357Y27470D02*
Y20472D01*
G01X612757Y27471D02*
X606357Y27470D01*
G01X619581Y32574D02*
X617081D01*
Y33574D01*
X617206Y33907D01*
X617498Y34157D01*
X617831Y34240D01*
X618164Y34157D01*
X618414Y33949D01*
X618539Y33574D01*
Y32574D01*
G01X617081Y35590D02*
X618873D01*
X619248Y35757D01*
X619498Y36090D01*
X619581Y36507D01*
X619498Y36924D01*
X619248Y37257D01*
X618873Y37424D01*
X617081D01*
G01X619581Y40107D02*
X617081D01*
X618873Y38565D01*
Y40649D01*
G01X615904Y49867D02*
Y54867D01*
X610904D01*
G01Y35067D02*
X615904D01*
Y40067D01*
G01X596104D02*
Y35067D01*
X601104D01*
G01X605020Y53873D02*
Y55873D01*
G01X603051Y36061D02*
Y34061D01*
G01X614910Y43983D02*
X617910D01*
G01X585250Y10700D02*
Y11533D01*
X586000D01*
X586250Y11283D01*
X586417Y10992D01*
X586500Y10575D01*
X586417Y10158D01*
X586250Y9867D01*
X586000Y9617D01*
X585708Y9450D01*
X585375Y9367D01*
X585083D01*
X584833Y9450D01*
X584542Y9617D01*
X584292Y9867D01*
X584125Y10117D01*
X584000Y10450D01*
Y10742D01*
X584083Y11075D01*
X584250Y11325D01*
G01X586125Y12633D02*
X586333Y12883D01*
X586458Y13175D01*
X586500Y13550D01*
X586417Y13925D01*
X586250Y14217D01*
X585958Y14425D01*
X585625Y14467D01*
X585292Y14383D01*
X585083Y14175D01*
X584917Y13883D01*
X584875Y13592D01*
X584917Y13300D01*
X585083Y12925D01*
X584000Y13050D01*
Y14175D01*
G01X634624Y27953D02*
Y25453D01*
X636290D01*
G01X638557D02*
Y27953D01*
X638057Y27453D01*
G01Y25453D02*
X639057D01*
G01X641657Y27953D02*
X641324Y27870D01*
X641074Y27661D01*
X640907Y27411D01*
X640782Y27078D01*
X640740Y26703D01*
X640782Y26328D01*
X640907Y25995D01*
X641074Y25745D01*
X641324Y25536D01*
X641657Y25453D01*
X641990Y25536D01*
X642240Y25745D01*
X642407Y25995D01*
X642532Y26328D01*
X642574Y26703D01*
X642532Y27078D01*
X642407Y27411D01*
X642240Y27661D01*
X641990Y27870D01*
X641657Y27953D01*
G01X651647Y32457D02*
X624647D01*
Y52957D01*
X651647D01*
Y32457D01*
G01X574422Y68859D02*
X574297Y68609D01*
X574214Y68317D01*
Y67984D01*
X574339Y67609D01*
X574547Y67317D01*
X574797Y67109D01*
X575214Y66942D01*
X575589Y66900D01*
X575964Y66984D01*
X576214Y67109D01*
X576464Y67359D01*
X576631Y67650D01*
X576714Y67942D01*
Y68234D01*
X576631Y68525D01*
X576506Y68775D01*
X576339Y68984D01*
G01X574631Y70250D02*
X574381Y70500D01*
X574256Y70792D01*
X574214Y71125D01*
X574297Y71542D01*
X574506Y71834D01*
X574756Y71917D01*
X575006Y71875D01*
X575214Y71709D01*
X575631Y70875D01*
X575922Y70500D01*
X576339Y70250D01*
X576714Y70167D01*
Y71917D01*
G01X574214Y74142D02*
X574297Y73809D01*
X574506Y73559D01*
X574756Y73392D01*
X575089Y73267D01*
X575464Y73225D01*
X575839Y73267D01*
X576172Y73392D01*
X576422Y73559D01*
X576631Y73809D01*
X576714Y74142D01*
X576631Y74475D01*
X576422Y74725D01*
X576172Y74892D01*
X575839Y75017D01*
X575464Y75059D01*
X575089Y75017D01*
X574756Y74892D01*
X574506Y74725D01*
X574297Y74475D01*
X574214Y74142D01*
G01X575672Y76450D02*
X575381Y76742D01*
X575214Y76992D01*
X575131Y77325D01*
X575214Y77617D01*
X575381Y77825D01*
X575631Y77992D01*
X575922Y78034D01*
X576172Y77992D01*
X576422Y77825D01*
X576631Y77575D01*
X576714Y77284D01*
X576631Y76950D01*
X576381Y76659D01*
X576006Y76492D01*
X575589Y76450D01*
X575047Y76534D01*
X574756Y76659D01*
X574464Y76867D01*
X574256Y77159D01*
X574214Y77450D01*
X574297Y77742D01*
X574506Y77950D01*
G01X603307Y85009D02*
X603057Y85134D01*
X602765Y85217D01*
X602432D01*
X602057Y85092D01*
X601765Y84884D01*
X601557Y84634D01*
X601390Y84217D01*
X601348Y83842D01*
X601432Y83467D01*
X601557Y83217D01*
X601807Y82967D01*
X602098Y82800D01*
X602390Y82717D01*
X602682D01*
X602973Y82800D01*
X603223Y82925D01*
X603432Y83092D01*
G01X604698Y84800D02*
X604948Y85050D01*
X605240Y85175D01*
X605573Y85217D01*
X605990Y85134D01*
X606282Y84925D01*
X606365Y84675D01*
X606323Y84425D01*
X606157Y84217D01*
X605323Y83800D01*
X604948Y83509D01*
X604698Y83092D01*
X604615Y82717D01*
X606365D01*
G01X608590Y85217D02*
X608257Y85134D01*
X608007Y84925D01*
X607840Y84675D01*
X607715Y84342D01*
X607673Y83967D01*
X607715Y83592D01*
X607840Y83259D01*
X608007Y83009D01*
X608257Y82800D01*
X608590Y82717D01*
X608923Y82800D01*
X609173Y83009D01*
X609340Y83259D01*
X609465Y83592D01*
X609507Y83967D01*
X609465Y84342D01*
X609340Y84675D01*
X609173Y84925D01*
X608923Y85134D01*
X608590Y85217D01*
G01X610773Y83217D02*
X611023Y82925D01*
X611357Y82759D01*
X611732Y82717D01*
X612065Y82759D01*
X612398Y82967D01*
X612607Y83217D01*
X612648Y83467D01*
X612565Y83759D01*
X612273Y83967D01*
X611982Y84050D01*
X611607D01*
G01X611982D02*
X612232Y84175D01*
X612440Y84384D01*
X612523Y84634D01*
X612440Y84884D01*
X612232Y85092D01*
X611857Y85217D01*
X611482Y85175D01*
X611107Y85009D01*
G01X603307Y93009D02*
X603057Y93134D01*
X602765Y93217D01*
X602432D01*
X602057Y93092D01*
X601765Y92884D01*
X601557Y92634D01*
X601390Y92217D01*
X601348Y91842D01*
X601432Y91467D01*
X601557Y91217D01*
X601807Y90967D01*
X602098Y90800D01*
X602390Y90717D01*
X602682D01*
X602973Y90800D01*
X603223Y90925D01*
X603432Y91092D01*
G01X604698Y92800D02*
X604948Y93050D01*
X605240Y93175D01*
X605573Y93217D01*
X605990Y93134D01*
X606282Y92925D01*
X606365Y92675D01*
X606323Y92425D01*
X606157Y92217D01*
X605323Y91800D01*
X604948Y91509D01*
X604698Y91092D01*
X604615Y90717D01*
X606365D01*
G01X608590Y93217D02*
X608257Y93134D01*
X608007Y92925D01*
X607840Y92675D01*
X607715Y92342D01*
X607673Y91967D01*
X607715Y91592D01*
X607840Y91259D01*
X608007Y91009D01*
X608257Y90800D01*
X608590Y90717D01*
X608923Y90800D01*
X609173Y91009D01*
X609340Y91259D01*
X609465Y91592D01*
X609507Y91967D01*
X609465Y92342D01*
X609340Y92675D01*
X609173Y92925D01*
X608923Y93134D01*
X608590Y93217D01*
G01X612190Y90717D02*
Y93217D01*
X610648Y91425D01*
X612732D01*
G01X603307Y89009D02*
X603057Y89134D01*
X602765Y89217D01*
X602432D01*
X602057Y89092D01*
X601765Y88884D01*
X601557Y88634D01*
X601390Y88217D01*
X601348Y87842D01*
X601432Y87467D01*
X601557Y87217D01*
X601807Y86967D01*
X602098Y86800D01*
X602390Y86717D01*
X602682D01*
X602973Y86800D01*
X603223Y86925D01*
X603432Y87092D01*
G01X604698Y88800D02*
X604948Y89050D01*
X605240Y89175D01*
X605573Y89217D01*
X605990Y89134D01*
X606282Y88925D01*
X606365Y88675D01*
X606323Y88425D01*
X606157Y88217D01*
X605323Y87800D01*
X604948Y87509D01*
X604698Y87092D01*
X604615Y86717D01*
X606365D01*
G01X608590Y89217D02*
X608257Y89134D01*
X608007Y88925D01*
X607840Y88675D01*
X607715Y88342D01*
X607673Y87967D01*
X607715Y87592D01*
X607840Y87259D01*
X608007Y87009D01*
X608257Y86800D01*
X608590Y86717D01*
X608923Y86800D01*
X609173Y87009D01*
X609340Y87259D01*
X609465Y87592D01*
X609507Y87967D01*
X609465Y88342D01*
X609340Y88675D01*
X609173Y88925D01*
X608923Y89134D01*
X608590Y89217D01*
G01X610773Y87092D02*
X611023Y86884D01*
X611315Y86759D01*
X611690Y86717D01*
X612065Y86800D01*
X612357Y86967D01*
X612565Y87259D01*
X612607Y87592D01*
X612523Y87925D01*
X612315Y88134D01*
X612023Y88300D01*
X611732Y88342D01*
X611440Y88300D01*
X611065Y88134D01*
X611190Y89217D01*
X612315D01*
G01X584714Y67109D02*
X582214D01*
Y68150D01*
X582339Y68484D01*
X582506Y68692D01*
X582839Y68775D01*
X583172Y68692D01*
X583381Y68442D01*
X583506Y68150D01*
Y67109D01*
G01Y68150D02*
X584714Y68775D01*
G01X584339Y70125D02*
X584547Y70375D01*
X584672Y70667D01*
X584714Y71042D01*
X584631Y71417D01*
X584464Y71709D01*
X584172Y71917D01*
X583839Y71959D01*
X583506Y71875D01*
X583297Y71667D01*
X583131Y71375D01*
X583089Y71084D01*
X583131Y70792D01*
X583297Y70417D01*
X582214Y70542D01*
Y71667D01*
G01X584714Y74142D02*
X582214D01*
X582714Y73642D01*
G01X584714D02*
Y74642D01*
G01X583672Y76450D02*
X583381Y76742D01*
X583214Y76992D01*
X583131Y77325D01*
X583214Y77617D01*
X583381Y77825D01*
X583631Y77992D01*
X583922Y78034D01*
X584172Y77992D01*
X584422Y77825D01*
X584631Y77575D01*
X584714Y77284D01*
X584631Y76950D01*
X584381Y76659D01*
X584006Y76492D01*
X583589Y76450D01*
X583047Y76534D01*
X582756Y76659D01*
X582464Y76867D01*
X582256Y77159D01*
X582214Y77450D01*
X582297Y77742D01*
X582506Y77950D01*
G01X637520Y66416D02*
X635020D01*
Y67457D01*
X635145Y67791D01*
X635312Y67999D01*
X635645Y68082D01*
X635978Y67999D01*
X636187Y67749D01*
X636312Y67457D01*
Y66416D01*
G01Y67457D02*
X637520Y68082D01*
G01X637145Y69432D02*
X637353Y69682D01*
X637478Y69974D01*
X637520Y70349D01*
X637437Y70724D01*
X637270Y71016D01*
X636978Y71224D01*
X636645Y71266D01*
X636312Y71182D01*
X636103Y70974D01*
X635937Y70682D01*
X635895Y70391D01*
X635937Y70099D01*
X636103Y69724D01*
X635020Y69849D01*
Y70974D01*
G01X637520Y73449D02*
X635020D01*
X635520Y72949D01*
G01X637520D02*
Y73949D01*
G01X637228Y75841D02*
X637437Y76132D01*
X637520Y76466D01*
X637437Y76799D01*
X637187Y77091D01*
X636812Y77299D01*
X636437Y77382D01*
X635978D01*
X635603Y77299D01*
X635270Y77091D01*
X635103Y76841D01*
X635020Y76549D01*
X635103Y76216D01*
X635270Y75966D01*
X635520Y75799D01*
X635853Y75716D01*
X636145Y75799D01*
X636437Y76007D01*
X636603Y76257D01*
X636645Y76549D01*
X636562Y76882D01*
X636353Y77132D01*
X635978Y77382D01*
G01X580714Y67109D02*
X578214D01*
Y68150D01*
X578339Y68484D01*
X578506Y68692D01*
X578839Y68775D01*
X579172Y68692D01*
X579381Y68442D01*
X579506Y68150D01*
Y67109D01*
G01Y68150D02*
X580714Y68775D01*
G01X580339Y70125D02*
X580547Y70375D01*
X580672Y70667D01*
X580714Y71042D01*
X580631Y71417D01*
X580464Y71709D01*
X580172Y71917D01*
X579839Y71959D01*
X579506Y71875D01*
X579297Y71667D01*
X579131Y71375D01*
X579089Y71084D01*
X579131Y70792D01*
X579297Y70417D01*
X578214Y70542D01*
Y71667D01*
G01X580714Y74142D02*
X578214D01*
X578714Y73642D01*
G01X580714D02*
Y74642D01*
G01X580339Y76325D02*
X580547Y76575D01*
X580672Y76867D01*
X580714Y77242D01*
X580631Y77617D01*
X580464Y77909D01*
X580172Y78117D01*
X579839Y78159D01*
X579506Y78075D01*
X579297Y77867D01*
X579131Y77575D01*
X579089Y77284D01*
X579131Y76992D01*
X579297Y76617D01*
X578214Y76742D01*
Y77867D01*
G01X595580Y82524D02*
X593080D01*
Y83565D01*
X593205Y83899D01*
X593372Y84107D01*
X593705Y84190D01*
X594038Y84107D01*
X594247Y83857D01*
X594372Y83565D01*
Y82524D01*
G01Y83565D02*
X595580Y84190D01*
G01X595205Y85540D02*
X595413Y85790D01*
X595538Y86082D01*
X595580Y86457D01*
X595497Y86832D01*
X595330Y87124D01*
X595038Y87332D01*
X594705Y87374D01*
X594372Y87290D01*
X594163Y87082D01*
X593997Y86790D01*
X593955Y86499D01*
X593997Y86207D01*
X594163Y85832D01*
X593080Y85957D01*
Y87082D01*
G01X595580Y89557D02*
X593080D01*
X593580Y89057D01*
G01X595580D02*
Y90057D01*
G01Y92657D02*
X593080D01*
X593580Y92157D01*
G01X595580D02*
Y93157D01*
G01X639883Y67944D02*
X639758Y67694D01*
X639675Y67402D01*
Y67069D01*
X639800Y66694D01*
X640008Y66402D01*
X640258Y66194D01*
X640675Y66027D01*
X641050Y65985D01*
X641425Y66069D01*
X641675Y66194D01*
X641925Y66444D01*
X642092Y66735D01*
X642175Y67027D01*
Y67319D01*
X642092Y67610D01*
X641967Y67860D01*
X641800Y68069D01*
G01X640092Y69335D02*
X639842Y69585D01*
X639717Y69877D01*
X639675Y70210D01*
X639758Y70627D01*
X639967Y70919D01*
X640217Y71002D01*
X640467Y70960D01*
X640675Y70794D01*
X641092Y69960D01*
X641383Y69585D01*
X641800Y69335D01*
X642175Y69252D01*
Y71002D01*
G01Y73227D02*
X639675D01*
X640175Y72727D01*
G01X642175D02*
Y73727D01*
G01Y76327D02*
X639675D01*
X640175Y75827D01*
G01X642175D02*
Y76827D01*
G01X630595Y68994D02*
X630470Y68744D01*
X630387Y68452D01*
Y68119D01*
X630512Y67744D01*
X630720Y67452D01*
X630970Y67244D01*
X631387Y67077D01*
X631762Y67035D01*
X632137Y67119D01*
X632387Y67244D01*
X632637Y67494D01*
X632804Y67785D01*
X632887Y68077D01*
Y68369D01*
X632804Y68660D01*
X632679Y68910D01*
X632512Y69119D01*
G01X630804Y70385D02*
X630554Y70635D01*
X630429Y70927D01*
X630387Y71260D01*
X630470Y71677D01*
X630679Y71969D01*
X630929Y72052D01*
X631179Y72010D01*
X631387Y71844D01*
X631804Y71010D01*
X632095Y70635D01*
X632512Y70385D01*
X632887Y70302D01*
Y72052D01*
G01X630387Y74277D02*
X630470Y73944D01*
X630679Y73694D01*
X630929Y73527D01*
X631262Y73402D01*
X631637Y73360D01*
X632012Y73402D01*
X632345Y73527D01*
X632595Y73694D01*
X632804Y73944D01*
X632887Y74277D01*
X632804Y74610D01*
X632595Y74860D01*
X632345Y75027D01*
X632012Y75152D01*
X631637Y75194D01*
X631262Y75152D01*
X630929Y75027D01*
X630679Y74860D01*
X630470Y74610D01*
X630387Y74277D01*
G01X632887Y77294D02*
X632345Y77377D01*
X631887Y77502D01*
X631470Y77669D01*
X631012Y77877D01*
X630387Y78210D01*
Y76544D01*
G01X597294Y84174D02*
X597169Y83924D01*
X597086Y83632D01*
Y83299D01*
X597211Y82924D01*
X597419Y82632D01*
X597669Y82424D01*
X598086Y82257D01*
X598461Y82215D01*
X598836Y82299D01*
X599086Y82424D01*
X599336Y82674D01*
X599503Y82965D01*
X599586Y83257D01*
Y83549D01*
X599503Y83840D01*
X599378Y84090D01*
X599211Y84299D01*
G01X597503Y85565D02*
X597253Y85815D01*
X597128Y86107D01*
X597086Y86440D01*
X597169Y86857D01*
X597378Y87149D01*
X597628Y87232D01*
X597878Y87190D01*
X598086Y87024D01*
X598503Y86190D01*
X598794Y85815D01*
X599211Y85565D01*
X599586Y85482D01*
Y87232D01*
G01X597086Y89457D02*
X597169Y89124D01*
X597378Y88874D01*
X597628Y88707D01*
X597961Y88582D01*
X598336Y88540D01*
X598711Y88582D01*
X599044Y88707D01*
X599294Y88874D01*
X599503Y89124D01*
X599586Y89457D01*
X599503Y89790D01*
X599294Y90040D01*
X599044Y90207D01*
X598711Y90332D01*
X598336Y90374D01*
X597961Y90332D01*
X597628Y90207D01*
X597378Y90040D01*
X597169Y89790D01*
X597086Y89457D01*
G01X597503Y91765D02*
X597253Y92015D01*
X597128Y92307D01*
X597086Y92640D01*
X597169Y93057D01*
X597378Y93349D01*
X597628Y93432D01*
X597878Y93390D01*
X598086Y93224D01*
X598503Y92390D01*
X598794Y92015D01*
X599211Y91765D01*
X599586Y91682D01*
Y93432D01*
G01X593854Y95242D02*
Y97742D01*
X594895D01*
X595229Y97617D01*
X595437Y97450D01*
X595520Y97117D01*
X595437Y96784D01*
X595187Y96575D01*
X594895Y96450D01*
X593854D01*
G01X594895D02*
X595520Y95242D01*
G01X596870Y95617D02*
X597120Y95409D01*
X597412Y95284D01*
X597787Y95242D01*
X598162Y95325D01*
X598454Y95492D01*
X598662Y95784D01*
X598704Y96117D01*
X598620Y96450D01*
X598412Y96659D01*
X598120Y96825D01*
X597829Y96867D01*
X597537Y96825D01*
X597162Y96659D01*
X597287Y97742D01*
X598412D01*
G01X600887Y95242D02*
Y97742D01*
X600387Y97242D01*
G01Y95242D02*
X601387D01*
G01X603195Y97325D02*
X603445Y97575D01*
X603737Y97700D01*
X604070Y97742D01*
X604487Y97659D01*
X604779Y97450D01*
X604862Y97200D01*
X604820Y96950D01*
X604654Y96742D01*
X603820Y96325D01*
X603445Y96034D01*
X603195Y95617D01*
X603112Y95242D01*
X604862D01*
G01X609147Y81007D02*
Y73007D01*
X591547D01*
Y81007D01*
X609147D01*
G01X584132Y274485D02*
X584799Y274985D01*
X585299Y275818D01*
X585632Y276985D01*
X585299Y277985D01*
X584632Y278652D01*
X583466Y279152D01*
X578966D01*
Y269152D01*
X584466D01*
X585632Y269819D01*
X586299Y270819D01*
X586632Y271985D01*
X586299Y273152D01*
X585299Y274152D01*
X584132Y274485D01*
X578966D01*
G01X591066Y269152D02*
Y275818D01*
G01Y274485D02*
X591899Y275152D01*
X592732Y275652D01*
X593899Y275818D01*
X594732Y275652D01*
X595732Y275152D01*
G01X600499Y266152D02*
X601499Y265819D01*
X602832Y266152D01*
X603666Y266819D01*
X604332Y267652D01*
X605332Y270318D01*
X607499Y275818D01*
G01X602166D02*
X605332Y270318D01*
G01X617266Y274985D02*
X616099Y275652D01*
X615099Y275818D01*
X613766Y275485D01*
X612766Y274819D01*
X612099Y273652D01*
X611932Y272485D01*
X612099Y271319D01*
X612766Y270318D01*
X613766Y269485D01*
X615099Y269152D01*
X616266Y269485D01*
X617266Y270152D01*
G01X622699Y273652D02*
X628032D01*
X627532Y274819D01*
X626699Y275485D01*
X625532Y275818D01*
X624366Y275652D01*
X623366Y275152D01*
X622699Y273985D01*
X622366Y272985D01*
Y271985D01*
X622699Y270985D01*
X623532Y269985D01*
X624532Y269319D01*
X625699Y269152D01*
X626866Y269485D01*
X628032Y270485D01*
G01X650066Y278319D02*
X649066Y278819D01*
X647899Y279152D01*
X646566D01*
X645065Y278652D01*
X643899Y277819D01*
X643066Y276819D01*
X642399Y275152D01*
X642232Y273652D01*
X642566Y272152D01*
X643066Y271152D01*
X644066Y270152D01*
X645232Y269485D01*
X646399Y269152D01*
X647566D01*
X648732Y269485D01*
X649732Y269985D01*
X650566Y270652D01*
G01X659999Y269152D02*
Y275818D01*
G01Y274652D02*
X659332Y275319D01*
X658332Y275652D01*
X657166Y275818D01*
X655999Y275485D01*
X654999Y274819D01*
X654332Y273819D01*
X653999Y272485D01*
X654332Y271152D01*
X654999Y270152D01*
X655999Y269485D01*
X657166Y269152D01*
X658332Y269319D01*
X659332Y269819D01*
X659999Y270485D01*
G01X664766Y269152D02*
Y275818D01*
G01Y274152D02*
X665432Y274985D01*
X666432Y275652D01*
X667766Y275818D01*
X668932Y275652D01*
X669932Y274985D01*
X670432Y273819D01*
Y269152D01*
G01X674699Y266152D02*
X675699Y265819D01*
X677032Y266152D01*
X677866Y266819D01*
X678532Y267652D01*
X679532Y270318D01*
X681699Y275818D01*
G01X676366D02*
X679532Y270318D01*
G01X688799Y269152D02*
X687799Y269319D01*
X686799Y269985D01*
X686132Y271152D01*
X685799Y272485D01*
X686132Y273819D01*
X686799Y274985D01*
X687799Y275652D01*
X688799Y275818D01*
X689799Y275652D01*
X690799Y274985D01*
X691466Y273819D01*
X691632Y272485D01*
X691466Y271152D01*
X690799Y269985D01*
X689799Y269319D01*
X688799Y269152D01*
G01X696566D02*
Y275818D01*
G01Y274152D02*
X697232Y274985D01*
X698232Y275652D01*
X699566Y275818D01*
X700732Y275652D01*
X701732Y274985D01*
X702232Y273819D01*
Y269152D01*
G01X718599Y279152D02*
X722599D01*
G01X720599D02*
Y269152D01*
G01X718599D02*
X722599D01*
G01X731199D02*
X729865Y269319D01*
X728699Y269985D01*
X727699Y270985D01*
X727032Y272152D01*
X726699Y273485D01*
Y274819D01*
X727032Y276152D01*
X727699Y277319D01*
X728699Y278319D01*
X729865Y278985D01*
X731199Y279152D01*
X732532Y278985D01*
X733699Y278319D01*
X734699Y277319D01*
X735366Y276152D01*
X735699Y274819D01*
Y273485D01*
X735366Y272152D01*
X734699Y270985D01*
X733699Y269985D01*
X732532Y269319D01*
X731199Y269152D01*
G01X737466D02*
Y279152D01*
X741799Y270819D01*
X746132Y279152D01*
Y269152D01*
G01X762166Y265819D02*
X760499Y267485D01*
X759666Y269152D01*
Y275818D01*
X760499Y277485D01*
X762166Y279152D01*
G01X769266Y269152D02*
Y279152D01*
X773599Y270819D01*
X777932Y279152D01*
Y269152D01*
G01X784199Y268819D02*
X783866Y268985D01*
Y269319D01*
X784199Y269485D01*
X784532Y269319D01*
Y268985D01*
X784199Y268819D01*
G01X791632Y277485D02*
X792632Y278485D01*
X793799Y278985D01*
X795132Y279152D01*
X796799Y278819D01*
X797966Y277985D01*
X798299Y276985D01*
X798132Y275985D01*
X797466Y275152D01*
X794132Y273485D01*
X792632Y272319D01*
X791632Y270652D01*
X791299Y269152D01*
X798299D01*
G01X815999D02*
X814999Y269319D01*
X813999Y269985D01*
X813332Y271152D01*
X812999Y272485D01*
X813332Y273819D01*
X813999Y274985D01*
X814999Y275652D01*
X815999Y275818D01*
X816999Y275652D01*
X817999Y274985D01*
X818666Y273819D01*
X818832Y272485D01*
X818666Y271152D01*
X817999Y269985D01*
X816999Y269319D01*
X815999Y269152D01*
G01X823766D02*
Y275818D01*
G01Y274152D02*
X824432Y274985D01*
X825432Y275652D01*
X826766Y275818D01*
X827932Y275652D01*
X828932Y274985D01*
X829432Y273819D01*
Y269152D01*
G01X837199D02*
Y279152D01*
G01X844299Y266152D02*
X845299Y265819D01*
X846632Y266152D01*
X847466Y266819D01*
X848132Y267652D01*
X849132Y270318D01*
X851299Y275818D01*
G01X845966D02*
X849132Y270318D01*
G01X859232Y265819D02*
X860899Y267485D01*
X861732Y269152D01*
Y275818D01*
X860899Y277485D01*
X859232Y279152D01*
G01X625592Y252883D02*
Y262883D01*
X623592Y260883D01*
G01Y252883D02*
X627592D01*
G01X633025Y257049D02*
X634192Y258216D01*
X635192Y258883D01*
X636525Y259216D01*
X637692Y258883D01*
X638525Y258216D01*
X639192Y257216D01*
X639359Y256050D01*
X639192Y255050D01*
X638525Y254049D01*
X637525Y253216D01*
X636359Y252883D01*
X635025Y253216D01*
X633859Y254216D01*
X633192Y255716D01*
X633025Y257383D01*
X633359Y259549D01*
X633859Y260716D01*
X634692Y261883D01*
X635859Y262716D01*
X637025Y262883D01*
X638192Y262550D01*
X639025Y261716D01*
G01X643125Y254883D02*
X644125Y253716D01*
X645458Y253050D01*
X646959Y252883D01*
X648292Y253050D01*
X649625Y253883D01*
X650459Y254883D01*
X650625Y255883D01*
X650292Y257049D01*
X649125Y257883D01*
X647959Y258216D01*
X646459D01*
G01X647959D02*
X648959Y258716D01*
X649792Y259549D01*
X650125Y260550D01*
X649792Y261550D01*
X648959Y262383D01*
X647459Y262883D01*
X645959Y262716D01*
X644459Y262050D01*
G01X659392Y252883D02*
Y262883D01*
X653225Y255716D01*
X661559D01*
G01X664825Y261216D02*
X665825Y262216D01*
X666992Y262716D01*
X668325Y262883D01*
X669992Y262550D01*
X671159Y261716D01*
X671492Y260716D01*
X671325Y259716D01*
X670659Y258883D01*
X667325Y257216D01*
X665825Y256050D01*
X664825Y254383D01*
X664492Y252883D01*
X671492D01*
G01X676425Y256216D02*
X680759D01*
G01X686025Y261216D02*
X687025Y262216D01*
X688192Y262716D01*
X689525Y262883D01*
X691192Y262550D01*
X692359Y261716D01*
X692692Y260716D01*
X692525Y259716D01*
X691859Y258883D01*
X688525Y257216D01*
X687025Y256050D01*
X686025Y254383D01*
X685692Y252883D01*
X692692D01*
G01X594885Y244301D02*
X595552Y244801D01*
X596052Y245634D01*
X596385Y246801D01*
X596052Y247801D01*
X595385Y248468D01*
X594219Y248968D01*
X589719D01*
Y238968D01*
X595219D01*
X596385Y239635D01*
X597052Y240635D01*
X597385Y241801D01*
X597052Y242968D01*
X596052Y243968D01*
X594885Y244301D01*
X589719D01*
G01X606152Y238968D02*
Y248968D01*
X599985Y241801D01*
X608319D01*
G01X614752Y238968D02*
X615919Y239135D01*
X617252Y239635D01*
X618085Y240468D01*
X618419Y241635D01*
X618085Y242801D01*
X617085Y243801D01*
X615585Y244301D01*
X613919D01*
X612919Y244635D01*
X612085Y245468D01*
X611752Y246635D01*
X612252Y247801D01*
X613418Y248635D01*
X614752Y248968D01*
X616085Y248635D01*
X617252Y247801D01*
X617752Y246635D01*
X617419Y245468D01*
X616585Y244635D01*
X615585Y244301D01*
X613919D01*
X612419Y243801D01*
X611419Y242801D01*
X611085Y241635D01*
X611419Y240468D01*
X612252Y239635D01*
X613585Y239135D01*
X614752Y238968D01*
G01X625352Y238635D02*
X625019Y238801D01*
Y239135D01*
X625352Y239301D01*
X625685Y239135D01*
Y238801D01*
X625352Y238635D01*
G01X635952Y248968D02*
X634618Y248635D01*
X633619Y247801D01*
X632952Y246801D01*
X632452Y245468D01*
X632285Y243968D01*
X632452Y242468D01*
X632952Y241135D01*
X633619Y240134D01*
X634618Y239301D01*
X635952Y238968D01*
X637285Y239301D01*
X638285Y240134D01*
X638952Y241135D01*
X639452Y242468D01*
X639619Y243968D01*
X639452Y245468D01*
X638952Y246801D01*
X638285Y247801D01*
X637285Y248635D01*
X635952Y248968D01*
G01X646552Y238968D02*
Y248968D01*
X644552Y246968D01*
G01Y238968D02*
X648552D01*
G01X657152D02*
Y248968D01*
X655152Y246968D01*
G01Y238968D02*
X659152D01*
G01X667752D02*
Y248968D01*
X665752Y246968D01*
G01Y238968D02*
X669752D01*
G01X678352D02*
X679519Y239135D01*
X680852Y239635D01*
X681685Y240468D01*
X682019Y241635D01*
X681685Y242801D01*
X680685Y243801D01*
X679185Y244301D01*
X677519D01*
X676519Y244635D01*
X675685Y245468D01*
X675352Y246635D01*
X675852Y247801D01*
X677018Y248635D01*
X678352Y248968D01*
X679685Y248635D01*
X680852Y247801D01*
X681352Y246635D01*
X681019Y245468D01*
X680185Y244635D01*
X679185Y244301D01*
X677519D01*
X676019Y243801D01*
X675019Y242801D01*
X674685Y241635D01*
X675019Y240468D01*
X675852Y239635D01*
X677185Y239135D01*
X678352Y238968D01*
G01X688952Y238635D02*
X688619Y238801D01*
Y239135D01*
X688952Y239301D01*
X689285Y239135D01*
Y238801D01*
X688952Y238635D01*
G01X699552Y248968D02*
X698218Y248635D01*
X697219Y247801D01*
X696552Y246801D01*
X696052Y245468D01*
X695885Y243968D01*
X696052Y242468D01*
X696552Y241135D01*
X697219Y240134D01*
X698218Y239301D01*
X699552Y238968D01*
X700885Y239301D01*
X701885Y240134D01*
X702552Y241135D01*
X703052Y242468D01*
X703219Y243968D01*
X703052Y245468D01*
X702552Y246801D01*
X701885Y247801D01*
X700885Y248635D01*
X699552Y248968D01*
G01X710152D02*
X708818Y248635D01*
X707819Y247801D01*
X707152Y246801D01*
X706652Y245468D01*
X706485Y243968D01*
X706652Y242468D01*
X707152Y241135D01*
X707819Y240134D01*
X708818Y239301D01*
X710152Y238968D01*
X711485Y239301D01*
X712485Y240134D01*
X713152Y241135D01*
X713652Y242468D01*
X713819Y243968D01*
X713652Y245468D01*
X713152Y246801D01*
X712485Y247801D01*
X711485Y248635D01*
X710152Y248968D01*
G01X717585Y247301D02*
X718585Y248301D01*
X719752Y248801D01*
X721085Y248968D01*
X722752Y248635D01*
X723919Y247801D01*
X724252Y246801D01*
X724085Y245801D01*
X723419Y244968D01*
X720085Y243301D01*
X718585Y242135D01*
X717585Y240468D01*
X717252Y238968D01*
X724252D01*
G01X731352D02*
Y248968D01*
X729352Y246968D01*
G01Y238968D02*
X733352D01*
G01X588635Y222454D02*
Y232454D01*
X592968Y224121D01*
X597301Y232454D01*
Y222454D01*
G01X599401D02*
X603568Y232454D01*
X607735Y222454D01*
G01X606235Y225954D02*
X600901D01*
G01X610501Y222454D02*
Y232454D01*
X613835D01*
X615168Y231954D01*
X616168Y231287D01*
X617001Y230287D01*
X617668Y229120D01*
X617835Y227454D01*
X617668Y225787D01*
X617001Y224621D01*
X616168Y223620D01*
X615168Y222954D01*
X613835Y222454D01*
X610501D01*
G01X628101D02*
X621435D01*
Y232454D01*
X628101D01*
G01X625435Y227621D02*
X621435D01*
G01X643968Y232454D02*
X647968D01*
G01X645968D02*
Y222454D01*
G01X643968D02*
X647968D01*
G01X652735D02*
Y232454D01*
X660401Y222454D01*
Y232454D01*
G01X677768D02*
Y222454D01*
G01X673935Y232454D02*
X681601D01*
G01X684201Y222454D02*
X688368Y232454D01*
X692535Y222454D01*
G01X691035Y225954D02*
X685701D01*
G01X696968Y232454D02*
X700968D01*
G01X698968D02*
Y222454D01*
G01X696968D02*
X700968D01*
G01X704568Y232454D02*
X706901Y222454D01*
X709568Y232454D01*
X712235Y222454D01*
X714568Y232454D01*
G01X716001Y222454D02*
X720168Y232454D01*
X724335Y222454D01*
G01X722835Y225954D02*
X717501D01*
G01X726935Y222454D02*
Y232454D01*
X734601Y222454D01*
Y232454D01*
G01X631063Y520344D02*
Y522844D01*
X632104D01*
X632438Y522719D01*
X632646Y522552D01*
X632729Y522219D01*
X632646Y521886D01*
X632396Y521677D01*
X632104Y521552D01*
X631063D01*
G01X632104D02*
X632729Y520344D01*
G01X634996D02*
X635288Y520386D01*
X635621Y520511D01*
X635829Y520719D01*
X635913Y521011D01*
X635829Y521302D01*
X635579Y521552D01*
X635204Y521677D01*
X634788D01*
X634538Y521761D01*
X634329Y521969D01*
X634246Y522261D01*
X634371Y522552D01*
X634663Y522761D01*
X634996Y522844D01*
X635329Y522761D01*
X635621Y522552D01*
X635746Y522261D01*
X635663Y521969D01*
X635454Y521761D01*
X635204Y521677D01*
X634788D01*
X634413Y521552D01*
X634163Y521302D01*
X634079Y521011D01*
X634163Y520719D01*
X634371Y520511D01*
X634704Y520386D01*
X634996Y520344D01*
G01X638096Y522844D02*
X637763Y522761D01*
X637513Y522552D01*
X637346Y522302D01*
X637221Y521969D01*
X637179Y521594D01*
X637221Y521219D01*
X637346Y520886D01*
X637513Y520636D01*
X637763Y520427D01*
X638096Y520344D01*
X638429Y520427D01*
X638679Y520636D01*
X638846Y520886D01*
X638971Y521219D01*
X639013Y521594D01*
X638971Y521969D01*
X638846Y522302D01*
X638679Y522552D01*
X638429Y522761D01*
X638096Y522844D01*
G01X641696Y520344D02*
Y522844D01*
X640154Y521052D01*
X642238D01*
G01X631100Y528856D02*
Y531356D01*
X632141D01*
X632475Y531231D01*
X632683Y531064D01*
X632766Y530731D01*
X632683Y530398D01*
X632433Y530189D01*
X632141Y530064D01*
X631100D01*
G01X632141D02*
X632766Y528856D01*
G01X635033D02*
X635325Y528898D01*
X635658Y529023D01*
X635866Y529231D01*
X635950Y529523D01*
X635866Y529814D01*
X635616Y530064D01*
X635241Y530189D01*
X634825D01*
X634575Y530273D01*
X634366Y530481D01*
X634283Y530773D01*
X634408Y531064D01*
X634700Y531273D01*
X635033Y531356D01*
X635366Y531273D01*
X635658Y531064D01*
X635783Y530773D01*
X635700Y530481D01*
X635491Y530273D01*
X635241Y530189D01*
X634825D01*
X634450Y530064D01*
X634200Y529814D01*
X634116Y529523D01*
X634200Y529231D01*
X634408Y529023D01*
X634741Y528898D01*
X635033Y528856D01*
G01X637341Y530939D02*
X637591Y531189D01*
X637883Y531314D01*
X638216Y531356D01*
X638633Y531273D01*
X638925Y531064D01*
X639008Y530814D01*
X638966Y530564D01*
X638800Y530356D01*
X637966Y529939D01*
X637591Y529648D01*
X637341Y529231D01*
X637258Y528856D01*
X639008D01*
G01X640441Y530939D02*
X640691Y531189D01*
X640983Y531314D01*
X641316Y531356D01*
X641733Y531273D01*
X642025Y531064D01*
X642108Y530814D01*
X642066Y530564D01*
X641900Y530356D01*
X641066Y529939D01*
X640691Y529648D01*
X640441Y529231D01*
X640358Y528856D01*
X642108D01*
G01X631100Y524472D02*
Y526972D01*
X632141D01*
X632475Y526847D01*
X632683Y526680D01*
X632766Y526347D01*
X632683Y526014D01*
X632433Y525805D01*
X632141Y525680D01*
X631100D01*
G01X632141D02*
X632766Y524472D01*
G01X635033D02*
X635325Y524514D01*
X635658Y524639D01*
X635866Y524847D01*
X635950Y525139D01*
X635866Y525430D01*
X635616Y525680D01*
X635241Y525805D01*
X634825D01*
X634575Y525889D01*
X634366Y526097D01*
X634283Y526389D01*
X634408Y526680D01*
X634700Y526889D01*
X635033Y526972D01*
X635366Y526889D01*
X635658Y526680D01*
X635783Y526389D01*
X635700Y526097D01*
X635491Y525889D01*
X635241Y525805D01*
X634825D01*
X634450Y525680D01*
X634200Y525430D01*
X634116Y525139D01*
X634200Y524847D01*
X634408Y524639D01*
X634741Y524514D01*
X635033Y524472D01*
G01X638133D02*
Y526972D01*
X637633Y526472D01*
G01Y524472D02*
X638633D01*
G01X641233Y526972D02*
X640900Y526889D01*
X640650Y526680D01*
X640483Y526430D01*
X640358Y526097D01*
X640316Y525722D01*
X640358Y525347D01*
X640483Y525014D01*
X640650Y524764D01*
X640900Y524555D01*
X641233Y524472D01*
X641566Y524555D01*
X641816Y524764D01*
X641983Y525014D01*
X642108Y525347D01*
X642150Y525722D01*
X642108Y526097D01*
X641983Y526430D01*
X641816Y526680D01*
X641566Y526889D01*
X641233Y526972D01*
G01X637033Y515885D02*
Y518385D01*
X638074D01*
X638408Y518260D01*
X638616Y518093D01*
X638699Y517760D01*
X638616Y517427D01*
X638366Y517218D01*
X638074Y517093D01*
X637033D01*
G01X638074D02*
X638699Y515885D01*
G01X640966D02*
X641258Y515927D01*
X641591Y516052D01*
X641799Y516260D01*
X641883Y516552D01*
X641799Y516843D01*
X641549Y517093D01*
X641174Y517218D01*
X640758D01*
X640508Y517302D01*
X640299Y517510D01*
X640216Y517802D01*
X640341Y518093D01*
X640633Y518302D01*
X640966Y518385D01*
X641299Y518302D01*
X641591Y518093D01*
X641716Y517802D01*
X641633Y517510D01*
X641424Y517302D01*
X641174Y517218D01*
X640758D01*
X640383Y517093D01*
X640133Y516843D01*
X640049Y516552D01*
X640133Y516260D01*
X640341Y516052D01*
X640674Y515927D01*
X640966Y515885D01*
G01X644566D02*
Y518385D01*
X643024Y516593D01*
X645108D01*
G01X646374Y516927D02*
X646666Y517218D01*
X646916Y517385D01*
X647249Y517468D01*
X647541Y517385D01*
X647749Y517218D01*
X647916Y516968D01*
X647958Y516677D01*
X647916Y516427D01*
X647749Y516177D01*
X647499Y515968D01*
X647208Y515885D01*
X646874Y515968D01*
X646583Y516218D01*
X646416Y516593D01*
X646374Y517010D01*
X646458Y517552D01*
X646583Y517843D01*
X646791Y518135D01*
X647083Y518343D01*
X647374Y518385D01*
X647666Y518302D01*
X647874Y518093D01*
G01X613214Y759340D02*
X613614Y758873D01*
X614148Y758607D01*
X614748Y758540D01*
X615281Y758607D01*
X615814Y758940D01*
X616148Y759340D01*
X616214Y759740D01*
X616081Y760207D01*
X615614Y760540D01*
X615148Y760673D01*
X614548D01*
G01X615148D02*
X615548Y760873D01*
X615881Y761207D01*
X616014Y761607D01*
X615881Y762007D01*
X615548Y762340D01*
X614948Y762540D01*
X614348Y762473D01*
X613748Y762207D01*
G01X581919Y761873D02*
X582319Y762273D01*
X582786Y762473D01*
X583319Y762540D01*
X583986Y762407D01*
X584453Y762073D01*
X584586Y761673D01*
X584519Y761273D01*
X584253Y760940D01*
X582919Y760273D01*
X582319Y759807D01*
X581919Y759140D01*
X581786Y758540D01*
X584586D01*
G01X663288Y14574D02*
X663163Y14324D01*
X663080Y14032D01*
Y13699D01*
X663205Y13324D01*
X663413Y13032D01*
X663663Y12824D01*
X664080Y12657D01*
X664455Y12615D01*
X664830Y12699D01*
X665080Y12824D01*
X665330Y13074D01*
X665497Y13365D01*
X665580Y13657D01*
Y13949D01*
X665497Y14240D01*
X665372Y14490D01*
X665205Y14699D01*
G01X663497Y15965D02*
X663247Y16215D01*
X663122Y16507D01*
X663080Y16840D01*
X663163Y17257D01*
X663372Y17549D01*
X663622Y17632D01*
X663872Y17590D01*
X664080Y17424D01*
X664497Y16590D01*
X664788Y16215D01*
X665205Y15965D01*
X665580Y15882D01*
Y17632D01*
G01Y19857D02*
X663080D01*
X663580Y19357D01*
G01X665580D02*
Y20357D01*
G01Y23457D02*
X663080D01*
X664872Y21915D01*
Y23999D01*
G01X659394Y14874D02*
X659269Y14624D01*
X659186Y14332D01*
Y13999D01*
X659311Y13624D01*
X659519Y13332D01*
X659769Y13124D01*
X660186Y12957D01*
X660561Y12915D01*
X660936Y12999D01*
X661186Y13124D01*
X661436Y13374D01*
X661603Y13665D01*
X661686Y13957D01*
Y14249D01*
X661603Y14540D01*
X661478Y14790D01*
X661311Y14999D01*
G01X659603Y16265D02*
X659353Y16515D01*
X659228Y16807D01*
X659186Y17140D01*
X659269Y17557D01*
X659478Y17849D01*
X659728Y17932D01*
X659978Y17890D01*
X660186Y17724D01*
X660603Y16890D01*
X660894Y16515D01*
X661311Y16265D01*
X661686Y16182D01*
Y17932D01*
G01Y20157D02*
X659186D01*
X659686Y19657D01*
G01X661686D02*
Y20657D01*
G01X660644Y22465D02*
X660353Y22757D01*
X660186Y23007D01*
X660103Y23340D01*
X660186Y23632D01*
X660353Y23840D01*
X660603Y24007D01*
X660894Y24049D01*
X661144Y24007D01*
X661394Y23840D01*
X661603Y23590D01*
X661686Y23299D01*
X661603Y22965D01*
X661353Y22674D01*
X660978Y22507D01*
X660561Y22465D01*
X660019Y22549D01*
X659728Y22674D01*
X659436Y22882D01*
X659228Y23174D01*
X659186Y23465D01*
X659269Y23757D01*
X659478Y23965D01*
G01X654894Y14874D02*
X654769Y14624D01*
X654686Y14332D01*
Y13999D01*
X654811Y13624D01*
X655019Y13332D01*
X655269Y13124D01*
X655686Y12957D01*
X656061Y12915D01*
X656436Y12999D01*
X656686Y13124D01*
X656936Y13374D01*
X657103Y13665D01*
X657186Y13957D01*
Y14249D01*
X657103Y14540D01*
X656978Y14790D01*
X656811Y14999D01*
G01X655103Y16265D02*
X654853Y16515D01*
X654728Y16807D01*
X654686Y17140D01*
X654769Y17557D01*
X654978Y17849D01*
X655228Y17932D01*
X655478Y17890D01*
X655686Y17724D01*
X656103Y16890D01*
X656394Y16515D01*
X656811Y16265D01*
X657186Y16182D01*
Y17932D01*
G01Y20157D02*
X654686D01*
X655186Y19657D01*
G01X657186D02*
Y20657D01*
G01Y23174D02*
X656644Y23257D01*
X656186Y23382D01*
X655769Y23549D01*
X655311Y23757D01*
X654686Y24090D01*
Y22424D01*
G01X694017Y15700D02*
Y18200D01*
X695058D01*
X695392Y18075D01*
X695600Y17908D01*
X695683Y17575D01*
X695600Y17242D01*
X695350Y17033D01*
X695058Y16908D01*
X694017D01*
G01X695058D02*
X695683Y15700D01*
G01X697033Y16075D02*
X697283Y15867D01*
X697575Y15742D01*
X697950Y15700D01*
X698325Y15783D01*
X698617Y15950D01*
X698825Y16242D01*
X698867Y16575D01*
X698783Y16908D01*
X698575Y17117D01*
X698283Y17283D01*
X697992Y17325D01*
X697700Y17283D01*
X697325Y17117D01*
X697450Y18200D01*
X698575D01*
G01X700258Y17783D02*
X700508Y18033D01*
X700800Y18158D01*
X701133Y18200D01*
X701550Y18117D01*
X701842Y17908D01*
X701925Y17658D01*
X701883Y17408D01*
X701717Y17200D01*
X700883Y16783D01*
X700508Y16492D01*
X700258Y16075D01*
X700175Y15700D01*
X701925D01*
G01X704150D02*
X704442Y15742D01*
X704775Y15867D01*
X704983Y16075D01*
X705067Y16367D01*
X704983Y16658D01*
X704733Y16908D01*
X704358Y17033D01*
X703942D01*
X703692Y17117D01*
X703483Y17325D01*
X703400Y17617D01*
X703525Y17908D01*
X703817Y18117D01*
X704150Y18200D01*
X704483Y18117D01*
X704775Y17908D01*
X704900Y17617D01*
X704817Y17325D01*
X704608Y17117D01*
X704358Y17033D01*
X703942D01*
X703567Y16908D01*
X703317Y16658D01*
X703233Y16367D01*
X703317Y16075D01*
X703525Y15867D01*
X703858Y15742D01*
X704150Y15700D01*
G01X705300Y27200D02*
X701300D01*
Y19800D01*
G01X710900Y34500D02*
X710567Y34542D01*
X710275Y34708D01*
X710025Y34958D01*
X709858Y35250D01*
X709775Y35583D01*
Y35917D01*
X709858Y36250D01*
X710025Y36542D01*
X710275Y36792D01*
X710567Y36958D01*
X710900Y37000D01*
X711233Y36958D01*
X711525Y36792D01*
X711775Y36542D01*
X711942Y36250D01*
X712025Y35917D01*
Y35583D01*
X711942Y35250D01*
X711775Y34958D01*
X711525Y34708D01*
X711233Y34542D01*
X710900Y34500D01*
G01X711233Y35167D02*
X711733Y34500D01*
G01X713208Y36583D02*
X713458Y36833D01*
X713750Y36958D01*
X714083Y37000D01*
X714500Y36917D01*
X714792Y36708D01*
X714875Y36458D01*
X714833Y36208D01*
X714667Y36000D01*
X713833Y35583D01*
X713458Y35292D01*
X713208Y34875D01*
X713125Y34500D01*
X714875D01*
G01X717100D02*
X717392Y34542D01*
X717725Y34667D01*
X717933Y34875D01*
X718017Y35167D01*
X717933Y35458D01*
X717683Y35708D01*
X717308Y35833D01*
X716892D01*
X716642Y35917D01*
X716433Y36125D01*
X716350Y36417D01*
X716475Y36708D01*
X716767Y36917D01*
X717100Y37000D01*
X717433Y36917D01*
X717725Y36708D01*
X717850Y36417D01*
X717767Y36125D01*
X717558Y35917D01*
X717308Y35833D01*
X716892D01*
X716517Y35708D01*
X716267Y35458D01*
X716183Y35167D01*
X716267Y34875D01*
X716475Y34667D01*
X716808Y34542D01*
X717100Y34500D01*
G01X721300Y33400D02*
X707300D01*
G01Y20400D02*
X721300D01*
G01X707300Y33400D02*
Y20400D01*
G01X668330Y14507D02*
Y15340D01*
X669080D01*
X669330Y15090D01*
X669497Y14799D01*
X669580Y14382D01*
X669497Y13965D01*
X669330Y13674D01*
X669080Y13424D01*
X668788Y13257D01*
X668455Y13174D01*
X668163D01*
X667913Y13257D01*
X667622Y13424D01*
X667372Y13674D01*
X667205Y13924D01*
X667080Y14257D01*
Y14549D01*
X667163Y14882D01*
X667330Y15132D01*
G01X669580Y17857D02*
X667080D01*
X668872Y16315D01*
Y18399D01*
G01X704900Y385217D02*
X702400D01*
Y386258D01*
X702525Y386592D01*
X702692Y386800D01*
X703025Y386883D01*
X703358Y386800D01*
X703567Y386550D01*
X703692Y386258D01*
Y385217D01*
G01Y386258D02*
X704900Y386883D01*
G01X704525Y388233D02*
X704733Y388483D01*
X704858Y388775D01*
X704900Y389150D01*
X704817Y389525D01*
X704650Y389817D01*
X704358Y390025D01*
X704025Y390067D01*
X703692Y389983D01*
X703483Y389775D01*
X703317Y389483D01*
X703275Y389192D01*
X703317Y388900D01*
X703483Y388525D01*
X702400Y388650D01*
Y389775D01*
G01X704525Y391333D02*
X704733Y391583D01*
X704858Y391875D01*
X704900Y392250D01*
X704817Y392625D01*
X704650Y392917D01*
X704358Y393125D01*
X704025Y393167D01*
X703692Y393083D01*
X703483Y392875D01*
X703317Y392583D01*
X703275Y392292D01*
X703317Y392000D01*
X703483Y391625D01*
X702400Y391750D01*
Y392875D01*
G01X703858Y394558D02*
X703567Y394850D01*
X703400Y395100D01*
X703317Y395433D01*
X703400Y395725D01*
X703567Y395933D01*
X703817Y396100D01*
X704108Y396142D01*
X704358Y396100D01*
X704608Y395933D01*
X704817Y395683D01*
X704900Y395392D01*
X704817Y395058D01*
X704567Y394767D01*
X704192Y394600D01*
X703775Y394558D01*
X703233Y394642D01*
X702942Y394767D01*
X702650Y394975D01*
X702442Y395267D01*
X702400Y395558D01*
X702483Y395850D01*
X702692Y396058D01*
G01X715200Y396200D02*
X711200D01*
Y388800D01*
G01X708900Y385217D02*
X706400D01*
Y386258D01*
X706525Y386592D01*
X706692Y386800D01*
X707025Y386883D01*
X707358Y386800D01*
X707567Y386550D01*
X707692Y386258D01*
Y385217D01*
G01Y386258D02*
X708900Y386883D01*
G01X708525Y388233D02*
X708733Y388483D01*
X708858Y388775D01*
X708900Y389150D01*
X708817Y389525D01*
X708650Y389817D01*
X708358Y390025D01*
X708025Y390067D01*
X707692Y389983D01*
X707483Y389775D01*
X707317Y389483D01*
X707275Y389192D01*
X707317Y388900D01*
X707483Y388525D01*
X706400Y388650D01*
Y389775D01*
G01X708525Y391333D02*
X708733Y391583D01*
X708858Y391875D01*
X708900Y392250D01*
X708817Y392625D01*
X708650Y392917D01*
X708358Y393125D01*
X708025Y393167D01*
X707692Y393083D01*
X707483Y392875D01*
X707317Y392583D01*
X707275Y392292D01*
X707317Y392000D01*
X707483Y391625D01*
X706400Y391750D01*
Y392875D01*
G01X708900Y395267D02*
X708358Y395350D01*
X707900Y395475D01*
X707483Y395642D01*
X707025Y395850D01*
X706400Y396183D01*
Y394517D01*
G01X704600Y404783D02*
X706392D01*
X706767Y404950D01*
X707017Y405283D01*
X707100Y405700D01*
X707017Y406117D01*
X706767Y406450D01*
X706392Y406617D01*
X704600D01*
G01X707100Y408800D02*
X707058Y409092D01*
X706933Y409425D01*
X706725Y409633D01*
X706433Y409717D01*
X706142Y409633D01*
X705892Y409383D01*
X705767Y409008D01*
Y408592D01*
X705683Y408342D01*
X705475Y408133D01*
X705183Y408050D01*
X704892Y408175D01*
X704683Y408467D01*
X704600Y408800D01*
X704683Y409133D01*
X704892Y409425D01*
X705183Y409550D01*
X705475Y409467D01*
X705683Y409258D01*
X705767Y409008D01*
Y408592D01*
X705892Y408217D01*
X706142Y407967D01*
X706433Y407883D01*
X706725Y407967D01*
X706933Y408175D01*
X707058Y408508D01*
X707100Y408800D01*
G01Y412400D02*
X704600D01*
X706392Y410858D01*
Y412942D01*
G01X722544Y410875D02*
Y418875D01*
X710594D01*
Y410875D01*
X722544D01*
G01X710594Y417025D02*
X712594Y415025D01*
X710594Y413025D01*
G01X701767Y430792D02*
X701517Y430917D01*
X701225Y431000D01*
X700892D01*
X700517Y430875D01*
X700225Y430667D01*
X700017Y430417D01*
X699850Y430000D01*
X699808Y429625D01*
X699892Y429250D01*
X700017Y429000D01*
X700267Y428750D01*
X700558Y428583D01*
X700850Y428500D01*
X701142D01*
X701433Y428583D01*
X701683Y428708D01*
X701892Y428875D01*
G01X703158Y429542D02*
X703450Y429833D01*
X703700Y430000D01*
X704033Y430083D01*
X704325Y430000D01*
X704533Y429833D01*
X704700Y429583D01*
X704742Y429292D01*
X704700Y429042D01*
X704533Y428792D01*
X704283Y428583D01*
X703992Y428500D01*
X703658Y428583D01*
X703367Y428833D01*
X703200Y429208D01*
X703158Y429625D01*
X703242Y430167D01*
X703367Y430458D01*
X703575Y430750D01*
X703867Y430958D01*
X704158Y431000D01*
X704450Y430917D01*
X704658Y430708D01*
G01X707050Y431000D02*
X706717Y430917D01*
X706467Y430708D01*
X706300Y430458D01*
X706175Y430125D01*
X706133Y429750D01*
X706175Y429375D01*
X706300Y429042D01*
X706467Y428792D01*
X706717Y428583D01*
X707050Y428500D01*
X707383Y428583D01*
X707633Y428792D01*
X707800Y429042D01*
X707925Y429375D01*
X707967Y429750D01*
X707925Y430125D01*
X707800Y430458D01*
X707633Y430708D01*
X707383Y430917D01*
X707050Y431000D01*
G01X710150Y428500D02*
Y431000D01*
X709650Y430500D01*
G01Y428500D02*
X710650D01*
G01X709335Y467886D02*
X706835D01*
Y468927D01*
X706960Y469261D01*
X707127Y469469D01*
X707460Y469552D01*
X707793Y469469D01*
X708002Y469219D01*
X708127Y468927D01*
Y467886D01*
G01Y468927D02*
X709335Y469552D01*
G01Y471819D02*
X709293Y472111D01*
X709168Y472444D01*
X708960Y472652D01*
X708668Y472736D01*
X708377Y472652D01*
X708127Y472402D01*
X708002Y472027D01*
Y471611D01*
X707918Y471361D01*
X707710Y471152D01*
X707418Y471069D01*
X707127Y471194D01*
X706918Y471486D01*
X706835Y471819D01*
X706918Y472152D01*
X707127Y472444D01*
X707418Y472569D01*
X707710Y472486D01*
X707918Y472277D01*
X708002Y472027D01*
Y471611D01*
X708127Y471236D01*
X708377Y470986D01*
X708668Y470902D01*
X708960Y470986D01*
X709168Y471194D01*
X709293Y471527D01*
X709335Y471819D01*
G01X706835Y474919D02*
X706918Y474586D01*
X707127Y474336D01*
X707377Y474169D01*
X707710Y474044D01*
X708085Y474002D01*
X708460Y474044D01*
X708793Y474169D01*
X709043Y474336D01*
X709252Y474586D01*
X709335Y474919D01*
X709252Y475252D01*
X709043Y475502D01*
X708793Y475669D01*
X708460Y475794D01*
X708085Y475836D01*
X707710Y475794D01*
X707377Y475669D01*
X707127Y475502D01*
X706918Y475252D01*
X706835Y474919D01*
G01X708960Y477102D02*
X709168Y477352D01*
X709293Y477644D01*
X709335Y478019D01*
X709252Y478394D01*
X709085Y478686D01*
X708793Y478894D01*
X708460Y478936D01*
X708127Y478852D01*
X707918Y478644D01*
X707752Y478352D01*
X707710Y478061D01*
X707752Y477769D01*
X707918Y477394D01*
X706835Y477519D01*
Y478644D01*
G01X714851Y480282D02*
X710851D01*
Y472882D01*
G01X714100Y443917D02*
X711600D01*
Y444958D01*
X711725Y445292D01*
X711892Y445500D01*
X712225Y445583D01*
X712558Y445500D01*
X712767Y445250D01*
X712892Y444958D01*
Y443917D01*
G01Y444958D02*
X714100Y445583D01*
G01X713725Y446933D02*
X713933Y447183D01*
X714058Y447475D01*
X714100Y447850D01*
X714017Y448225D01*
X713850Y448517D01*
X713558Y448725D01*
X713225Y448767D01*
X712892Y448683D01*
X712683Y448475D01*
X712517Y448183D01*
X712475Y447892D01*
X712517Y447600D01*
X712683Y447225D01*
X711600Y447350D01*
Y448475D01*
G01X714100Y451450D02*
X711600D01*
X713392Y449908D01*
Y451992D01*
G01X713725Y453133D02*
X713933Y453383D01*
X714058Y453675D01*
X714100Y454050D01*
X714017Y454425D01*
X713850Y454717D01*
X713558Y454925D01*
X713225Y454967D01*
X712892Y454883D01*
X712683Y454675D01*
X712517Y454383D01*
X712475Y454092D01*
X712517Y453800D01*
X712683Y453425D01*
X711600Y453550D01*
Y454675D01*
G01X714000Y440800D02*
X710000D01*
Y433400D01*
G01X714100D02*
X718100D01*
Y440800D01*
G01X687750Y562083D02*
X688167Y561750D01*
X688750Y561500D01*
X689250D01*
X689750Y561667D01*
X690083Y561917D01*
X690250Y562250D01*
X690167Y562750D01*
X689833Y563000D01*
X688333Y563500D01*
X688000Y564083D01*
X688167Y564500D01*
X688500Y564750D01*
X689000Y564833D01*
X689500Y564750D01*
X690000Y564500D01*
G01X694600Y561500D02*
Y566500D01*
G01X700200Y561500D02*
X699700Y561583D01*
X699200Y561917D01*
X698867Y562500D01*
X698700Y563167D01*
X698867Y563833D01*
X699200Y564417D01*
X699700Y564750D01*
X700200Y564833D01*
X700700Y564750D01*
X701200Y564417D01*
X701533Y563833D01*
X701617Y563167D01*
X701533Y562500D01*
X701200Y561917D01*
X700700Y561583D01*
X700200Y561500D01*
G01X705800Y566500D02*
Y561500D01*
G01X704633Y564833D02*
X706967D01*
G01X717000Y566500D02*
X716333Y566333D01*
X715833Y565917D01*
X715500Y565417D01*
X715250Y564750D01*
X715167Y564000D01*
X715250Y563250D01*
X715500Y562583D01*
X715833Y562083D01*
X716333Y561667D01*
X717000Y561500D01*
X717667Y561667D01*
X718167Y562083D01*
X718500Y562583D01*
X718750Y563250D01*
X718833Y564000D01*
X718750Y564750D01*
X718500Y565417D01*
X718167Y565917D01*
X717667Y566333D01*
X717000Y566500D01*
G01X648346Y523683D02*
Y519683D01*
X655746D01*
G01X648383Y532195D02*
Y528195D01*
X655783D01*
G01Y523811D02*
Y527811D01*
X648383D01*
G01X651678Y519560D02*
Y515560D01*
X659078D01*
G01X661999Y497236D02*
Y535036D01*
X750599D01*
Y497236D01*
X661999D01*
G01X707900Y760207D02*
X708367Y760673D01*
X708767Y760940D01*
X709300Y761073D01*
X709767Y760940D01*
X710100Y760673D01*
X710367Y760273D01*
X710434Y759807D01*
X710367Y759407D01*
X710100Y759007D01*
X709700Y758673D01*
X709234Y758540D01*
X708700Y758673D01*
X708234Y759073D01*
X707967Y759673D01*
X707900Y760340D01*
X708034Y761207D01*
X708234Y761673D01*
X708567Y762140D01*
X709034Y762473D01*
X709500Y762540D01*
X709967Y762407D01*
X710300Y762073D01*
G01X676204Y759140D02*
X676604Y758807D01*
X677071Y758607D01*
X677671Y758540D01*
X678271Y758673D01*
X678738Y758940D01*
X679071Y759407D01*
X679138Y759940D01*
X679004Y760473D01*
X678671Y760807D01*
X678204Y761073D01*
X677738Y761140D01*
X677271Y761073D01*
X676671Y760807D01*
X676871Y762540D01*
X678671D01*
G01X646976Y758540D02*
Y762540D01*
X644509Y759673D01*
X647843D01*
G01X730100Y31917D02*
X727600D01*
Y32958D01*
X727725Y33292D01*
X727892Y33500D01*
X728225Y33583D01*
X728558Y33500D01*
X728767Y33250D01*
X728892Y32958D01*
Y31917D01*
G01Y32958D02*
X730100Y33583D01*
G01Y36350D02*
X727600D01*
X729392Y34808D01*
Y36892D01*
G01X730100Y38950D02*
X727600D01*
X728100Y38450D01*
G01X730100D02*
Y39450D01*
G01Y42050D02*
X727600D01*
X728100Y41550D01*
G01X730100D02*
Y42550D01*
G01X721800Y27700D02*
X725800D01*
Y35100D01*
G01X722917Y14000D02*
Y16500D01*
X723958D01*
X724292Y16375D01*
X724500Y16208D01*
X724583Y15875D01*
X724500Y15542D01*
X724250Y15333D01*
X723958Y15208D01*
X722917D01*
G01X723958D02*
X724583Y14000D01*
G01X726058Y15042D02*
X726350Y15333D01*
X726600Y15500D01*
X726933Y15583D01*
X727225Y15500D01*
X727433Y15333D01*
X727600Y15083D01*
X727642Y14792D01*
X727600Y14542D01*
X727433Y14292D01*
X727183Y14083D01*
X726892Y14000D01*
X726558Y14083D01*
X726267Y14333D01*
X726100Y14708D01*
X726058Y15125D01*
X726142Y15667D01*
X726267Y15958D01*
X726475Y16250D01*
X726767Y16458D01*
X727058Y16500D01*
X727350Y16417D01*
X727558Y16208D01*
G01X729242Y14292D02*
X729533Y14083D01*
X729867Y14000D01*
X730200Y14083D01*
X730492Y14333D01*
X730700Y14708D01*
X730783Y15083D01*
Y15542D01*
X730700Y15917D01*
X730492Y16250D01*
X730242Y16417D01*
X729950Y16500D01*
X729617Y16417D01*
X729367Y16250D01*
X729200Y16000D01*
X729117Y15667D01*
X729200Y15375D01*
X729408Y15083D01*
X729658Y14917D01*
X729950Y14875D01*
X730283Y14958D01*
X730533Y15167D01*
X730783Y15542D01*
G01X732133Y14375D02*
X732383Y14167D01*
X732675Y14042D01*
X733050Y14000D01*
X733425Y14083D01*
X733717Y14250D01*
X733925Y14542D01*
X733967Y14875D01*
X733883Y15208D01*
X733675Y15417D01*
X733383Y15583D01*
X733092Y15625D01*
X732800Y15583D01*
X732425Y15417D01*
X732550Y16500D01*
X733675D01*
G01X721800Y20000D02*
X725800D01*
Y27400D01*
G01X721300Y20400D02*
Y33400D01*
G01X778817Y13900D02*
Y16400D01*
X779858D01*
X780192Y16275D01*
X780400Y16108D01*
X780483Y15775D01*
X780400Y15442D01*
X780150Y15233D01*
X779858Y15108D01*
X778817D01*
G01X779858D02*
X780483Y13900D01*
G01X782667D02*
X782750Y14442D01*
X782875Y14900D01*
X783042Y15317D01*
X783250Y15775D01*
X783583Y16400D01*
X781917D01*
G01X784933Y14400D02*
X785183Y14108D01*
X785517Y13942D01*
X785892Y13900D01*
X786225Y13942D01*
X786558Y14150D01*
X786767Y14400D01*
X786808Y14650D01*
X786725Y14942D01*
X786433Y15150D01*
X786142Y15233D01*
X785767D01*
G01X786142D02*
X786392Y15358D01*
X786600Y15567D01*
X786683Y15817D01*
X786600Y16067D01*
X786392Y16275D01*
X786017Y16400D01*
X785642Y16358D01*
X785267Y16192D01*
G01X788867Y13900D02*
X788950Y14442D01*
X789075Y14900D01*
X789242Y15317D01*
X789450Y15775D01*
X789783Y16400D01*
X788117D01*
G01X781017Y33600D02*
Y36100D01*
X782058D01*
X782392Y35975D01*
X782600Y35808D01*
X782683Y35475D01*
X782600Y35142D01*
X782350Y34933D01*
X782058Y34808D01*
X781017D01*
G01X782058D02*
X782683Y33600D01*
G01X784950D02*
X785242Y33642D01*
X785575Y33767D01*
X785783Y33975D01*
X785867Y34267D01*
X785783Y34558D01*
X785533Y34808D01*
X785158Y34933D01*
X784742D01*
X784492Y35017D01*
X784283Y35225D01*
X784200Y35517D01*
X784325Y35808D01*
X784617Y36017D01*
X784950Y36100D01*
X785283Y36017D01*
X785575Y35808D01*
X785700Y35517D01*
X785617Y35225D01*
X785408Y35017D01*
X785158Y34933D01*
X784742D01*
X784367Y34808D01*
X784117Y34558D01*
X784033Y34267D01*
X784117Y33975D01*
X784325Y33767D01*
X784658Y33642D01*
X784950Y33600D01*
G01X788050D02*
Y36100D01*
X787550Y35600D01*
G01Y33600D02*
X788550D01*
G01X791067D02*
X791150Y34142D01*
X791275Y34600D01*
X791442Y35017D01*
X791650Y35475D01*
X791983Y36100D01*
X790317D01*
G01X771400Y39500D02*
X771067Y39542D01*
X770775Y39708D01*
X770525Y39958D01*
X770358Y40250D01*
X770275Y40583D01*
Y40917D01*
X770358Y41250D01*
X770525Y41542D01*
X770775Y41792D01*
X771067Y41958D01*
X771400Y42000D01*
X771733Y41958D01*
X772025Y41792D01*
X772275Y41542D01*
X772442Y41250D01*
X772525Y40917D01*
Y40583D01*
X772442Y40250D01*
X772275Y39958D01*
X772025Y39708D01*
X771733Y39542D01*
X771400Y39500D01*
G01X771733Y40167D02*
X772233Y39500D01*
G01X773708Y41583D02*
X773958Y41833D01*
X774250Y41958D01*
X774583Y42000D01*
X775000Y41917D01*
X775292Y41708D01*
X775375Y41458D01*
X775333Y41208D01*
X775167Y41000D01*
X774333Y40583D01*
X773958Y40292D01*
X773708Y39875D01*
X773625Y39500D01*
X775375D01*
G01X777517D02*
X777600Y40042D01*
X777725Y40500D01*
X777892Y40917D01*
X778100Y41375D01*
X778433Y42000D01*
X776767D01*
G01X778600Y28935D02*
X778340D01*
X776905Y27500D01*
X778340Y26065D01*
G01X778600Y28935D02*
Y26065D01*
X767600D01*
G01Y28935D02*
X778600D01*
G01X767600D02*
Y26065D01*
G01X731858Y420486D02*
Y422986D01*
X732899D01*
X733233Y422861D01*
X733441Y422694D01*
X733524Y422361D01*
X733441Y422028D01*
X733191Y421819D01*
X732899Y421694D01*
X731858D01*
G01X732899D02*
X733524Y420486D01*
G01X734874Y420861D02*
X735124Y420653D01*
X735416Y420528D01*
X735791Y420486D01*
X736166Y420569D01*
X736458Y420736D01*
X736666Y421028D01*
X736708Y421361D01*
X736624Y421694D01*
X736416Y421903D01*
X736124Y422069D01*
X735833Y422111D01*
X735541Y422069D01*
X735166Y421903D01*
X735291Y422986D01*
X736416D01*
G01X737974Y420861D02*
X738224Y420653D01*
X738516Y420528D01*
X738891Y420486D01*
X739266Y420569D01*
X739558Y420736D01*
X739766Y421028D01*
X739808Y421361D01*
X739724Y421694D01*
X739516Y421903D01*
X739224Y422069D01*
X738933Y422111D01*
X738641Y422069D01*
X738266Y421903D01*
X738391Y422986D01*
X739516D01*
G01X741074Y420986D02*
X741324Y420694D01*
X741658Y420528D01*
X742033Y420486D01*
X742366Y420528D01*
X742699Y420736D01*
X742908Y420986D01*
X742949Y421236D01*
X742866Y421528D01*
X742574Y421736D01*
X742283Y421819D01*
X741908D01*
G01X742283D02*
X742533Y421944D01*
X742741Y422153D01*
X742824Y422403D01*
X742741Y422653D01*
X742533Y422861D01*
X742158Y422986D01*
X741783Y422944D01*
X741408Y422778D01*
G01X720300Y396200D02*
X716300D01*
Y388800D01*
G01X787525Y380748D02*
X785025D01*
Y381789D01*
X785150Y382123D01*
X785317Y382331D01*
X785650Y382414D01*
X785983Y382331D01*
X786192Y382081D01*
X786317Y381789D01*
Y380748D01*
G01Y381789D02*
X787525Y382414D01*
G01X787150Y383764D02*
X787358Y384014D01*
X787483Y384306D01*
X787525Y384681D01*
X787442Y385056D01*
X787275Y385348D01*
X786983Y385556D01*
X786650Y385598D01*
X786317Y385514D01*
X786108Y385306D01*
X785942Y385014D01*
X785900Y384723D01*
X785942Y384431D01*
X786108Y384056D01*
X785025Y384181D01*
Y385306D01*
G01X787150Y386864D02*
X787358Y387114D01*
X787483Y387406D01*
X787525Y387781D01*
X787442Y388156D01*
X787275Y388448D01*
X786983Y388656D01*
X786650Y388698D01*
X786317Y388614D01*
X786108Y388406D01*
X785942Y388114D01*
X785900Y387823D01*
X785942Y387531D01*
X786108Y387156D01*
X785025Y387281D01*
Y388406D01*
G01X787525Y390881D02*
X787483Y391173D01*
X787358Y391506D01*
X787150Y391714D01*
X786858Y391798D01*
X786567Y391714D01*
X786317Y391464D01*
X786192Y391089D01*
Y390673D01*
X786108Y390423D01*
X785900Y390214D01*
X785608Y390131D01*
X785317Y390256D01*
X785108Y390548D01*
X785025Y390881D01*
X785108Y391214D01*
X785317Y391506D01*
X785608Y391631D01*
X785900Y391548D01*
X786108Y391339D01*
X786192Y391089D01*
Y390673D01*
X786317Y390298D01*
X786567Y390048D01*
X786858Y389964D01*
X787150Y390048D01*
X787358Y390256D01*
X787483Y390589D01*
X787525Y390881D01*
G01X785161Y402374D02*
X786953D01*
X787328Y402541D01*
X787578Y402874D01*
X787661Y403291D01*
X787578Y403708D01*
X787328Y404041D01*
X786953Y404208D01*
X785161D01*
G01X787661Y406391D02*
X787619Y406683D01*
X787494Y407016D01*
X787286Y407224D01*
X786994Y407308D01*
X786703Y407224D01*
X786453Y406974D01*
X786328Y406599D01*
Y406183D01*
X786244Y405933D01*
X786036Y405724D01*
X785744Y405641D01*
X785453Y405766D01*
X785244Y406058D01*
X785161Y406391D01*
X785244Y406724D01*
X785453Y407016D01*
X785744Y407141D01*
X786036Y407058D01*
X786244Y406849D01*
X786328Y406599D01*
Y406183D01*
X786453Y405808D01*
X786703Y405558D01*
X786994Y405474D01*
X787286Y405558D01*
X787494Y405766D01*
X787619Y406099D01*
X787661Y406391D01*
G01X787286Y408574D02*
X787494Y408824D01*
X787619Y409116D01*
X787661Y409491D01*
X787578Y409866D01*
X787411Y410158D01*
X787119Y410366D01*
X786786Y410408D01*
X786453Y410324D01*
X786244Y410116D01*
X786078Y409824D01*
X786036Y409533D01*
X786078Y409241D01*
X786244Y408866D01*
X785161Y408991D01*
Y410116D01*
G01X728786Y401519D02*
Y399019D01*
G01X727828Y401519D02*
X729744D01*
G01X731053Y399019D02*
Y401519D01*
X732053D01*
X732386Y401394D01*
X732636Y401102D01*
X732719Y400769D01*
X732636Y400436D01*
X732428Y400186D01*
X732053Y400061D01*
X731053D01*
G01X734194Y401102D02*
X734444Y401352D01*
X734736Y401477D01*
X735069Y401519D01*
X735486Y401436D01*
X735778Y401227D01*
X735861Y400977D01*
X735819Y400727D01*
X735653Y400519D01*
X734819Y400102D01*
X734444Y399811D01*
X734194Y399394D01*
X734111Y399019D01*
X735861D01*
G01X738086D02*
Y401519D01*
X737586Y401019D01*
G01Y399019D02*
X738586D01*
G01X740269Y399394D02*
X740519Y399186D01*
X740811Y399061D01*
X741186Y399019D01*
X741561Y399102D01*
X741853Y399269D01*
X742061Y399561D01*
X742103Y399894D01*
X742019Y400227D01*
X741811Y400436D01*
X741519Y400602D01*
X741228Y400644D01*
X740936Y400602D01*
X740561Y400436D01*
X740686Y401519D01*
X741811D01*
G01X781242Y431631D02*
X780992Y431756D01*
X780700Y431839D01*
X780367D01*
X779992Y431714D01*
X779700Y431506D01*
X779492Y431256D01*
X779325Y430839D01*
X779283Y430464D01*
X779367Y430089D01*
X779492Y429839D01*
X779742Y429589D01*
X780033Y429422D01*
X780325Y429339D01*
X780617D01*
X780908Y429422D01*
X781158Y429547D01*
X781367Y429714D01*
G01X782633Y430381D02*
X782925Y430672D01*
X783175Y430839D01*
X783508Y430922D01*
X783800Y430839D01*
X784008Y430672D01*
X784175Y430422D01*
X784217Y430131D01*
X784175Y429881D01*
X784008Y429631D01*
X783758Y429422D01*
X783467Y429339D01*
X783133Y429422D01*
X782842Y429672D01*
X782675Y430047D01*
X782633Y430464D01*
X782717Y431006D01*
X782842Y431297D01*
X783050Y431589D01*
X783342Y431797D01*
X783633Y431839D01*
X783925Y431756D01*
X784133Y431547D01*
G01X786525Y431839D02*
X786192Y431756D01*
X785942Y431547D01*
X785775Y431297D01*
X785650Y430964D01*
X785608Y430589D01*
X785650Y430214D01*
X785775Y429881D01*
X785942Y429631D01*
X786192Y429422D01*
X786525Y429339D01*
X786858Y429422D01*
X787108Y429631D01*
X787275Y429881D01*
X787400Y430214D01*
X787442Y430589D01*
X787400Y430964D01*
X787275Y431297D01*
X787108Y431547D01*
X786858Y431756D01*
X786525Y431839D01*
G01X788833Y431422D02*
X789083Y431672D01*
X789375Y431797D01*
X789708Y431839D01*
X790125Y431756D01*
X790417Y431547D01*
X790500Y431297D01*
X790458Y431047D01*
X790292Y430839D01*
X789458Y430422D01*
X789083Y430131D01*
X788833Y429714D01*
X788750Y429339D01*
X790500D01*
G01X726551Y470698D02*
X724051D01*
Y471739D01*
X724176Y472073D01*
X724343Y472281D01*
X724676Y472364D01*
X725009Y472281D01*
X725218Y472031D01*
X725343Y471739D01*
Y470698D01*
G01Y471739D02*
X726551Y472364D01*
G01Y474631D02*
X726509Y474923D01*
X726384Y475256D01*
X726176Y475464D01*
X725884Y475548D01*
X725593Y475464D01*
X725343Y475214D01*
X725218Y474839D01*
Y474423D01*
X725134Y474173D01*
X724926Y473964D01*
X724634Y473881D01*
X724343Y474006D01*
X724134Y474298D01*
X724051Y474631D01*
X724134Y474964D01*
X724343Y475256D01*
X724634Y475381D01*
X724926Y475298D01*
X725134Y475089D01*
X725218Y474839D01*
Y474423D01*
X725343Y474048D01*
X725593Y473798D01*
X725884Y473714D01*
X726176Y473798D01*
X726384Y474006D01*
X726509Y474339D01*
X726551Y474631D01*
G01X724051Y477731D02*
X724134Y477398D01*
X724343Y477148D01*
X724593Y476981D01*
X724926Y476856D01*
X725301Y476814D01*
X725676Y476856D01*
X726009Y476981D01*
X726259Y477148D01*
X726468Y477398D01*
X726551Y477731D01*
X726468Y478064D01*
X726259Y478314D01*
X726009Y478481D01*
X725676Y478606D01*
X725301Y478648D01*
X724926Y478606D01*
X724593Y478481D01*
X724343Y478314D01*
X724134Y478064D01*
X724051Y477731D01*
G01X725509Y480039D02*
X725218Y480331D01*
X725051Y480581D01*
X724968Y480914D01*
X725051Y481206D01*
X725218Y481414D01*
X725468Y481581D01*
X725759Y481623D01*
X726009Y481581D01*
X726259Y481414D01*
X726468Y481164D01*
X726551Y480873D01*
X726468Y480539D01*
X726218Y480248D01*
X725843Y480081D01*
X725426Y480039D01*
X724884Y480123D01*
X724593Y480248D01*
X724301Y480456D01*
X724093Y480748D01*
X724051Y481039D01*
X724134Y481331D01*
X724343Y481539D01*
G01X718017Y473214D02*
X722017D01*
Y480614D01*
G01X728200Y444017D02*
X725700D01*
Y445058D01*
X725825Y445392D01*
X725992Y445600D01*
X726325Y445683D01*
X726658Y445600D01*
X726867Y445350D01*
X726992Y445058D01*
Y444017D01*
G01Y445058D02*
X728200Y445683D01*
G01X727825Y447033D02*
X728033Y447283D01*
X728158Y447575D01*
X728200Y447950D01*
X728117Y448325D01*
X727950Y448617D01*
X727658Y448825D01*
X727325Y448867D01*
X726992Y448783D01*
X726783Y448575D01*
X726617Y448283D01*
X726575Y447992D01*
X726617Y447700D01*
X726783Y447325D01*
X725700Y447450D01*
Y448575D01*
G01X728200Y451550D02*
X725700D01*
X727492Y450008D01*
Y452092D01*
G01X727158Y453358D02*
X726867Y453650D01*
X726700Y453900D01*
X726617Y454233D01*
X726700Y454525D01*
X726867Y454733D01*
X727117Y454900D01*
X727408Y454942D01*
X727658Y454900D01*
X727908Y454733D01*
X728117Y454483D01*
X728200Y454192D01*
X728117Y453858D01*
X727867Y453567D01*
X727492Y453400D01*
X727075Y453358D01*
X726533Y453442D01*
X726242Y453567D01*
X725950Y453775D01*
X725742Y454067D01*
X725700Y454358D01*
X725783Y454650D01*
X725992Y454858D01*
G01X727200Y440800D02*
X723200D01*
Y433400D01*
G01X743097Y430143D02*
Y432643D01*
X744138D01*
X744472Y432518D01*
X744680Y432351D01*
X744763Y432018D01*
X744680Y431685D01*
X744430Y431476D01*
X744138Y431351D01*
X743097D01*
G01X744138D02*
X744763Y430143D01*
G01X746113Y430518D02*
X746363Y430310D01*
X746655Y430185D01*
X747030Y430143D01*
X747405Y430226D01*
X747697Y430393D01*
X747905Y430685D01*
X747947Y431018D01*
X747863Y431351D01*
X747655Y431560D01*
X747363Y431726D01*
X747072Y431768D01*
X746780Y431726D01*
X746405Y431560D01*
X746530Y432643D01*
X747655D01*
G01X750630Y430143D02*
Y432643D01*
X749088Y430851D01*
X751172D01*
G01X753147Y430143D02*
X753230Y430685D01*
X753355Y431143D01*
X753522Y431560D01*
X753730Y432018D01*
X754063Y432643D01*
X752397D01*
G01X739200Y429000D02*
Y433000D01*
X731800D01*
G01X718100Y443917D02*
X715600D01*
Y444958D01*
X715725Y445292D01*
X715892Y445500D01*
X716225Y445583D01*
X716558Y445500D01*
X716767Y445250D01*
X716892Y444958D01*
Y443917D01*
G01Y444958D02*
X718100Y445583D01*
G01X717725Y446933D02*
X717933Y447183D01*
X718058Y447475D01*
X718100Y447850D01*
X718017Y448225D01*
X717850Y448517D01*
X717558Y448725D01*
X717225Y448767D01*
X716892Y448683D01*
X716683Y448475D01*
X716517Y448183D01*
X716475Y447892D01*
X716517Y447600D01*
X716683Y447225D01*
X715600Y447350D01*
Y448475D01*
G01X717725Y450033D02*
X717933Y450283D01*
X718058Y450575D01*
X718100Y450950D01*
X718017Y451325D01*
X717850Y451617D01*
X717558Y451825D01*
X717225Y451867D01*
X716892Y451783D01*
X716683Y451575D01*
X716517Y451283D01*
X716475Y450992D01*
X716517Y450700D01*
X716683Y450325D01*
X715600Y450450D01*
Y451575D01*
G01X718100Y454050D02*
X715600D01*
X716100Y453550D01*
G01X718100D02*
Y454550D01*
G01X724200Y444017D02*
X721700D01*
Y445058D01*
X721825Y445392D01*
X721992Y445600D01*
X722325Y445683D01*
X722658Y445600D01*
X722867Y445350D01*
X722992Y445058D01*
Y444017D01*
G01Y445058D02*
X724200Y445683D01*
G01X723825Y447033D02*
X724033Y447283D01*
X724158Y447575D01*
X724200Y447950D01*
X724117Y448325D01*
X723950Y448617D01*
X723658Y448825D01*
X723325Y448867D01*
X722992Y448783D01*
X722783Y448575D01*
X722617Y448283D01*
X722575Y447992D01*
X722617Y447700D01*
X722783Y447325D01*
X721700Y447450D01*
Y448575D01*
G01X723825Y450133D02*
X724033Y450383D01*
X724158Y450675D01*
X724200Y451050D01*
X724117Y451425D01*
X723950Y451717D01*
X723658Y451925D01*
X723325Y451967D01*
X722992Y451883D01*
X722783Y451675D01*
X722617Y451383D01*
X722575Y451092D01*
X722617Y450800D01*
X722783Y450425D01*
X721700Y450550D01*
Y451675D01*
G01X722117Y453358D02*
X721867Y453608D01*
X721742Y453900D01*
X721700Y454233D01*
X721783Y454650D01*
X721992Y454942D01*
X722242Y455025D01*
X722492Y454983D01*
X722700Y454817D01*
X723117Y453983D01*
X723408Y453608D01*
X723825Y453358D01*
X724200Y453275D01*
Y455025D01*
G01X719100Y433400D02*
X723100D01*
Y440800D01*
G01X731800Y428800D02*
Y424800D01*
X739200D01*
G01X777750Y562083D02*
X778167Y561750D01*
X778750Y561500D01*
X779250D01*
X779750Y561667D01*
X780083Y561917D01*
X780250Y562250D01*
X780167Y562750D01*
X779833Y563000D01*
X778333Y563500D01*
X778000Y564083D01*
X778167Y564500D01*
X778500Y564750D01*
X779000Y564833D01*
X779500Y564750D01*
X780000Y564500D01*
G01X784600Y561500D02*
Y566500D01*
G01X790200Y561500D02*
X789700Y561583D01*
X789200Y561917D01*
X788867Y562500D01*
X788700Y563167D01*
X788867Y563833D01*
X789200Y564417D01*
X789700Y564750D01*
X790200Y564833D01*
X790700Y564750D01*
X791200Y564417D01*
X791533Y563833D01*
X791617Y563167D01*
X791533Y562500D01*
X791200Y561917D01*
X790700Y561583D01*
X790200Y561500D01*
G01X795800Y566500D02*
Y561500D01*
G01X794633Y564833D02*
X796967D01*
G01X807000Y561500D02*
Y566500D01*
X806000Y565500D01*
G01Y561500D02*
X808000D01*
G01X756382Y506549D02*
X753882D01*
Y507590D01*
X754007Y507924D01*
X754174Y508132D01*
X754507Y508215D01*
X754840Y508132D01*
X755049Y507882D01*
X755174Y507590D01*
Y506549D01*
G01Y507590D02*
X756382Y508215D01*
G01Y510482D02*
X756340Y510774D01*
X756215Y511107D01*
X756007Y511315D01*
X755715Y511399D01*
X755424Y511315D01*
X755174Y511065D01*
X755049Y510690D01*
Y510274D01*
X754965Y510024D01*
X754757Y509815D01*
X754465Y509732D01*
X754174Y509857D01*
X753965Y510149D01*
X753882Y510482D01*
X753965Y510815D01*
X754174Y511107D01*
X754465Y511232D01*
X754757Y511149D01*
X754965Y510940D01*
X755049Y510690D01*
Y510274D01*
X755174Y509899D01*
X755424Y509649D01*
X755715Y509565D01*
X756007Y509649D01*
X756215Y509857D01*
X756340Y510190D01*
X756382Y510482D01*
G01Y514082D02*
X753882D01*
X755674Y512540D01*
Y514624D01*
G01X756007Y515765D02*
X756215Y516015D01*
X756340Y516307D01*
X756382Y516682D01*
X756299Y517057D01*
X756132Y517349D01*
X755840Y517557D01*
X755507Y517599D01*
X755174Y517515D01*
X754965Y517307D01*
X754799Y517015D01*
X754757Y516724D01*
X754799Y516432D01*
X754965Y516057D01*
X753882Y516182D01*
Y517307D01*
G01X756800Y532400D02*
X752800D01*
Y525000D01*
G01X741700Y565600D02*
Y563100D01*
G01X740742Y565600D02*
X742658D01*
G01X743967Y563100D02*
Y565600D01*
X744967D01*
X745300Y565475D01*
X745550Y565183D01*
X745633Y564850D01*
X745550Y564517D01*
X745342Y564267D01*
X744967Y564142D01*
X743967D01*
G01X747108Y565183D02*
X747358Y565433D01*
X747650Y565558D01*
X747983Y565600D01*
X748400Y565517D01*
X748692Y565308D01*
X748775Y565058D01*
X748733Y564808D01*
X748567Y564600D01*
X747733Y564183D01*
X747358Y563892D01*
X747108Y563475D01*
X747025Y563100D01*
X748775D01*
G01X751000D02*
Y565600D01*
X750500Y565100D01*
G01Y563100D02*
X751500D01*
G01X754600D02*
Y565600D01*
X753058Y563808D01*
X755142D01*
G01X741800Y560367D02*
Y557867D01*
G01X740842Y560367D02*
X742758D01*
G01X744067Y557867D02*
Y560367D01*
X745067D01*
X745400Y560242D01*
X745650Y559950D01*
X745733Y559617D01*
X745650Y559284D01*
X745442Y559034D01*
X745067Y558909D01*
X744067D01*
G01X747208Y559950D02*
X747458Y560200D01*
X747750Y560325D01*
X748083Y560367D01*
X748500Y560284D01*
X748792Y560075D01*
X748875Y559825D01*
X748833Y559575D01*
X748667Y559367D01*
X747833Y558950D01*
X747458Y558659D01*
X747208Y558242D01*
X747125Y557867D01*
X748875D01*
G01X751100D02*
Y560367D01*
X750600Y559867D01*
G01Y557867D02*
X751600D01*
G01X753283Y558367D02*
X753533Y558075D01*
X753867Y557909D01*
X754242Y557867D01*
X754575Y557909D01*
X754908Y558117D01*
X755117Y558367D01*
X755158Y558617D01*
X755075Y558909D01*
X754783Y559117D01*
X754492Y559200D01*
X754117D01*
G01X754492D02*
X754742Y559325D01*
X754950Y559534D01*
X755033Y559784D01*
X754950Y560034D01*
X754742Y560242D01*
X754367Y560367D01*
X753992Y560325D01*
X753617Y560159D01*
G01X758467Y537666D02*
Y540166D01*
X759550Y538083D01*
X760633Y540166D01*
Y537666D01*
G01X762650D02*
Y540166D01*
X762150Y539666D01*
G01Y537666D02*
X763150D01*
G01X760424Y497236D02*
Y535036D01*
X849024D01*
Y497236D01*
X760424D01*
G01X744367Y538500D02*
Y541000D01*
X745450Y538917D01*
X746533Y541000D01*
Y538500D01*
G01X747758Y540583D02*
X748008Y540833D01*
X748300Y540958D01*
X748633Y541000D01*
X749050Y540917D01*
X749342Y540708D01*
X749425Y540458D01*
X749383Y540208D01*
X749217Y540000D01*
X748383Y539583D01*
X748008Y539292D01*
X747758Y538875D01*
X747675Y538500D01*
X749425D01*
G01X805017Y36000D02*
Y33500D01*
X806683D01*
G01X809783D02*
X808117D01*
Y36000D01*
X809783D01*
G01X809117Y34792D02*
X808117D01*
G01X811133Y33500D02*
Y36000D01*
X811967D01*
X812300Y35875D01*
X812550Y35708D01*
X812758Y35458D01*
X812925Y35167D01*
X812967Y34750D01*
X812925Y34333D01*
X812758Y34042D01*
X812550Y33792D01*
X812300Y33625D01*
X811967Y33500D01*
X811133D01*
G01X814233Y34000D02*
X814483Y33708D01*
X814817Y33542D01*
X815192Y33500D01*
X815525Y33542D01*
X815858Y33750D01*
X816067Y34000D01*
X816108Y34250D01*
X816025Y34542D01*
X815733Y34750D01*
X815442Y34833D01*
X815067D01*
G01X815442D02*
X815692Y34958D01*
X815900Y35167D01*
X815983Y35417D01*
X815900Y35667D01*
X815692Y35875D01*
X815317Y36000D01*
X814942Y35958D01*
X814567Y35792D01*
G01X796224Y30409D02*
X825824D01*
Y-7191D01*
X796224D01*
Y30409D01*
G01X804119Y15199D02*
X797419D01*
G01X809219D02*
X813319D01*
G01X804119Y10099D02*
X809219Y15199D01*
G01X804119Y20299D02*
Y10099D01*
G01X809219Y15199D02*
X804119Y20299D01*
G01X818419Y10099D02*
X813319Y15199D01*
G01X818419Y20299D02*
Y10099D01*
G01X813319Y15199D02*
X818419Y20299D01*
G01Y15199D02*
X822119D01*
G01X809219Y12399D02*
Y18799D01*
G01X813319Y12399D02*
Y18799D01*
G01X849194Y107274D02*
X849069Y107024D01*
X848986Y106732D01*
Y106399D01*
X849111Y106024D01*
X849319Y105732D01*
X849569Y105524D01*
X849986Y105357D01*
X850361Y105315D01*
X850736Y105399D01*
X850986Y105524D01*
X851236Y105774D01*
X851403Y106065D01*
X851486Y106357D01*
Y106649D01*
X851403Y106940D01*
X851278Y107190D01*
X851111Y107399D01*
G01X851486Y109457D02*
X848986D01*
X849486Y108957D01*
G01X851486D02*
Y109957D01*
G01X850444Y111765D02*
X850153Y112057D01*
X849986Y112307D01*
X849903Y112640D01*
X849986Y112932D01*
X850153Y113140D01*
X850403Y113307D01*
X850694Y113349D01*
X850944Y113307D01*
X851194Y113140D01*
X851403Y112890D01*
X851486Y112599D01*
X851403Y112265D01*
X851153Y111974D01*
X850778Y111807D01*
X850361Y111765D01*
X849819Y111849D01*
X849528Y111974D01*
X849236Y112182D01*
X849028Y112474D01*
X848986Y112765D01*
X849069Y113057D01*
X849278Y113265D01*
G01X851486Y115574D02*
X850944Y115657D01*
X850486Y115782D01*
X850069Y115949D01*
X849611Y116157D01*
X848986Y116490D01*
Y114824D01*
G01X855972Y120138D02*
X867172D01*
G01X855972Y102138D02*
Y120138D01*
G01X867172Y102138D02*
X855972D01*
G01X848924Y85678D02*
X848799Y85428D01*
X848716Y85136D01*
Y84803D01*
X848841Y84428D01*
X849049Y84136D01*
X849299Y83928D01*
X849716Y83761D01*
X850091Y83719D01*
X850466Y83803D01*
X850716Y83928D01*
X850966Y84178D01*
X851133Y84469D01*
X851216Y84761D01*
Y85053D01*
X851133Y85344D01*
X851008Y85594D01*
X850841Y85803D01*
G01X851216Y87861D02*
X848716D01*
X849216Y87361D01*
G01X851216D02*
Y88361D01*
G01X850174Y90169D02*
X849883Y90461D01*
X849716Y90711D01*
X849633Y91044D01*
X849716Y91336D01*
X849883Y91544D01*
X850133Y91711D01*
X850424Y91753D01*
X850674Y91711D01*
X850924Y91544D01*
X851133Y91294D01*
X851216Y91003D01*
X851133Y90669D01*
X850883Y90378D01*
X850508Y90211D01*
X850091Y90169D01*
X849549Y90253D01*
X849258Y90378D01*
X848966Y90586D01*
X848758Y90878D01*
X848716Y91169D01*
X848799Y91461D01*
X849008Y91669D01*
G01X851216Y94061D02*
X851174Y94353D01*
X851049Y94686D01*
X850841Y94894D01*
X850549Y94978D01*
X850258Y94894D01*
X850008Y94644D01*
X849883Y94269D01*
Y93853D01*
X849799Y93603D01*
X849591Y93394D01*
X849299Y93311D01*
X849008Y93436D01*
X848799Y93728D01*
X848716Y94061D01*
X848799Y94394D01*
X849008Y94686D01*
X849299Y94811D01*
X849591Y94728D01*
X849799Y94519D01*
X849883Y94269D01*
Y93853D01*
X850008Y93478D01*
X850258Y93228D01*
X850549Y93144D01*
X850841Y93228D01*
X851049Y93436D01*
X851174Y93769D01*
X851216Y94061D01*
G01X855972Y99638D02*
X867172D01*
G01X855972Y81638D02*
Y99638D01*
G01X867172Y81638D02*
X855972D01*
G01X835749Y184608D02*
X835624Y184358D01*
X835541Y184066D01*
Y183733D01*
X835666Y183358D01*
X835874Y183066D01*
X836124Y182858D01*
X836541Y182691D01*
X836916Y182649D01*
X837291Y182733D01*
X837541Y182858D01*
X837791Y183108D01*
X837958Y183399D01*
X838041Y183691D01*
Y183983D01*
X837958Y184274D01*
X837833Y184524D01*
X837666Y184733D01*
G01X838041Y186791D02*
X835541D01*
X836041Y186291D01*
G01X838041D02*
Y187291D01*
G01X836999Y189099D02*
X836708Y189391D01*
X836541Y189641D01*
X836458Y189974D01*
X836541Y190266D01*
X836708Y190474D01*
X836958Y190641D01*
X837249Y190683D01*
X837499Y190641D01*
X837749Y190474D01*
X837958Y190224D01*
X838041Y189933D01*
X837958Y189599D01*
X837708Y189308D01*
X837333Y189141D01*
X836916Y189099D01*
X836374Y189183D01*
X836083Y189308D01*
X835791Y189516D01*
X835583Y189808D01*
X835541Y190099D01*
X835624Y190391D01*
X835833Y190599D01*
G01X835958Y192199D02*
X835708Y192449D01*
X835583Y192741D01*
X835541Y193074D01*
X835624Y193491D01*
X835833Y193783D01*
X836083Y193866D01*
X836333Y193824D01*
X836541Y193658D01*
X836958Y192824D01*
X837249Y192449D01*
X837666Y192199D01*
X838041Y192116D01*
Y193866D01*
G01X831545Y184572D02*
X831420Y184322D01*
X831337Y184030D01*
Y183697D01*
X831462Y183322D01*
X831670Y183030D01*
X831920Y182822D01*
X832337Y182655D01*
X832712Y182613D01*
X833087Y182697D01*
X833337Y182822D01*
X833587Y183072D01*
X833754Y183363D01*
X833837Y183655D01*
Y183947D01*
X833754Y184238D01*
X833629Y184488D01*
X833462Y184697D01*
G01X833837Y186755D02*
X831337D01*
X831837Y186255D01*
G01X833837D02*
Y187255D01*
G01X832795Y189063D02*
X832504Y189355D01*
X832337Y189605D01*
X832254Y189938D01*
X832337Y190230D01*
X832504Y190438D01*
X832754Y190605D01*
X833045Y190647D01*
X833295Y190605D01*
X833545Y190438D01*
X833754Y190188D01*
X833837Y189897D01*
X833754Y189563D01*
X833504Y189272D01*
X833129Y189105D01*
X832712Y189063D01*
X832170Y189147D01*
X831879Y189272D01*
X831587Y189480D01*
X831379Y189772D01*
X831337Y190063D01*
X831420Y190355D01*
X831629Y190563D01*
G01X833337Y192038D02*
X833629Y192288D01*
X833795Y192622D01*
X833837Y192997D01*
X833795Y193330D01*
X833587Y193663D01*
X833337Y193872D01*
X833087Y193913D01*
X832795Y193830D01*
X832587Y193538D01*
X832504Y193247D01*
Y192872D01*
G01Y193247D02*
X832379Y193497D01*
X832170Y193705D01*
X831920Y193788D01*
X831670Y193705D01*
X831462Y193497D01*
X831337Y193122D01*
X831379Y192747D01*
X831545Y192372D01*
G01X814669Y157899D02*
Y160399D01*
X815710D01*
X816044Y160274D01*
X816252Y160107D01*
X816335Y159774D01*
X816252Y159441D01*
X816002Y159232D01*
X815710Y159107D01*
X814669D01*
G01X815710D02*
X816335Y157899D01*
G01X819102D02*
Y160399D01*
X817560Y158607D01*
X819644D01*
G01X820910Y158941D02*
X821202Y159232D01*
X821452Y159399D01*
X821785Y159482D01*
X822077Y159399D01*
X822285Y159232D01*
X822452Y158982D01*
X822494Y158691D01*
X822452Y158441D01*
X822285Y158191D01*
X822035Y157982D01*
X821744Y157899D01*
X821410Y157982D01*
X821119Y158232D01*
X820952Y158607D01*
X820910Y159024D01*
X820994Y159566D01*
X821119Y159857D01*
X821327Y160149D01*
X821619Y160357D01*
X821910Y160399D01*
X822202Y160316D01*
X822410Y160107D01*
G01X823885Y158399D02*
X824135Y158107D01*
X824469Y157941D01*
X824844Y157899D01*
X825177Y157941D01*
X825510Y158149D01*
X825719Y158399D01*
X825760Y158649D01*
X825677Y158941D01*
X825385Y159149D01*
X825094Y159232D01*
X824719D01*
G01X825094D02*
X825344Y159357D01*
X825552Y159566D01*
X825635Y159816D01*
X825552Y160066D01*
X825344Y160274D01*
X824969Y160399D01*
X824594Y160357D01*
X824219Y160191D01*
G01X844611Y167178D02*
Y163178D01*
X852011D01*
G01X846968Y209864D02*
Y205864D01*
X854368D01*
G01X828149Y146947D02*
Y149447D01*
X829190D01*
X829524Y149322D01*
X829732Y149155D01*
X829815Y148822D01*
X829732Y148489D01*
X829482Y148280D01*
X829190Y148155D01*
X828149D01*
G01X829190D02*
X829815Y146947D01*
G01X832582D02*
Y149447D01*
X831040Y147655D01*
X833124D01*
G01X834390Y147989D02*
X834682Y148280D01*
X834932Y148447D01*
X835265Y148530D01*
X835557Y148447D01*
X835765Y148280D01*
X835932Y148030D01*
X835974Y147739D01*
X835932Y147489D01*
X835765Y147239D01*
X835515Y147030D01*
X835224Y146947D01*
X834890Y147030D01*
X834599Y147280D01*
X834432Y147655D01*
X834390Y148072D01*
X834474Y148614D01*
X834599Y148905D01*
X834807Y149197D01*
X835099Y149405D01*
X835390Y149447D01*
X835682Y149364D01*
X835890Y149155D01*
G01X838282Y146947D02*
X838574Y146989D01*
X838907Y147114D01*
X839115Y147322D01*
X839199Y147614D01*
X839115Y147905D01*
X838865Y148155D01*
X838490Y148280D01*
X838074D01*
X837824Y148364D01*
X837615Y148572D01*
X837532Y148864D01*
X837657Y149155D01*
X837949Y149364D01*
X838282Y149447D01*
X838615Y149364D01*
X838907Y149155D01*
X839032Y148864D01*
X838949Y148572D01*
X838740Y148364D01*
X838490Y148280D01*
X838074D01*
X837699Y148155D01*
X837449Y147905D01*
X837365Y147614D01*
X837449Y147322D01*
X837657Y147114D01*
X837990Y146989D01*
X838282Y146947D01*
G01X856622Y147514D02*
Y151514D01*
X849222D01*
G01X832570Y151779D02*
X830070D01*
Y152820D01*
X830195Y153154D01*
X830362Y153362D01*
X830695Y153445D01*
X831028Y153362D01*
X831237Y153112D01*
X831362Y152820D01*
Y151779D01*
G01Y152820D02*
X832570Y153445D01*
G01Y156212D02*
X830070D01*
X831862Y154670D01*
Y156754D01*
G01X832570Y158729D02*
X832028Y158812D01*
X831570Y158937D01*
X831153Y159104D01*
X830695Y159312D01*
X830070Y159645D01*
Y157979D01*
G01X832570Y161912D02*
X830070D01*
X830570Y161412D01*
G01X832570D02*
Y162412D01*
G01X856596Y164535D02*
X852596D01*
Y157135D01*
G01X829853Y182568D02*
X827353D01*
Y183609D01*
X827478Y183943D01*
X827645Y184151D01*
X827978Y184234D01*
X828311Y184151D01*
X828520Y183901D01*
X828645Y183609D01*
Y182568D01*
G01Y183609D02*
X829853Y184234D01*
G01Y187001D02*
X827353D01*
X829145Y185459D01*
Y187543D01*
G01X829853Y189518D02*
X829311Y189601D01*
X828853Y189726D01*
X828436Y189893D01*
X827978Y190101D01*
X827353Y190434D01*
Y188768D01*
G01X829853Y193201D02*
X827353D01*
X829145Y191659D01*
Y193743D01*
G01X843625Y183177D02*
X839625D01*
Y175777D01*
G01X814661Y161521D02*
Y164021D01*
X815702D01*
X816036Y163896D01*
X816244Y163729D01*
X816327Y163396D01*
X816244Y163063D01*
X815994Y162854D01*
X815702Y162729D01*
X814661D01*
G01X815702D02*
X816327Y161521D01*
G01X819094D02*
Y164021D01*
X817552Y162229D01*
X819636D01*
G01X820902Y162563D02*
X821194Y162854D01*
X821444Y163021D01*
X821777Y163104D01*
X822069Y163021D01*
X822277Y162854D01*
X822444Y162604D01*
X822486Y162313D01*
X822444Y162063D01*
X822277Y161813D01*
X822027Y161604D01*
X821736Y161521D01*
X821402Y161604D01*
X821111Y161854D01*
X820944Y162229D01*
X820902Y162646D01*
X820986Y163188D01*
X821111Y163479D01*
X821319Y163771D01*
X821611Y163979D01*
X821902Y164021D01*
X822194Y163938D01*
X822402Y163729D01*
G01X823877Y161896D02*
X824127Y161688D01*
X824419Y161563D01*
X824794Y161521D01*
X825169Y161604D01*
X825461Y161771D01*
X825669Y162063D01*
X825711Y162396D01*
X825627Y162729D01*
X825419Y162938D01*
X825127Y163104D01*
X824836Y163146D01*
X824544Y163104D01*
X824169Y162938D01*
X824294Y164021D01*
X825419D01*
G01X852011Y167478D02*
Y171478D01*
X844611D01*
G01X833661Y203920D02*
Y206420D01*
X834702D01*
X835036Y206295D01*
X835244Y206128D01*
X835327Y205795D01*
X835244Y205462D01*
X834994Y205253D01*
X834702Y205128D01*
X833661D01*
G01X834702D02*
X835327Y203920D01*
G01X838094D02*
Y206420D01*
X836552Y204628D01*
X838636D01*
G01X840611Y203920D02*
X840694Y204462D01*
X840819Y204920D01*
X840986Y205337D01*
X841194Y205795D01*
X841527Y206420D01*
X839861D01*
G01X843711Y203920D02*
X843794Y204462D01*
X843919Y204920D01*
X844086Y205337D01*
X844294Y205795D01*
X844627Y206420D01*
X842961D01*
G01X854368Y201864D02*
Y205864D01*
X846968D01*
G01X830767Y195901D02*
X828267D01*
Y196942D01*
X828392Y197276D01*
X828559Y197484D01*
X828892Y197567D01*
X829225Y197484D01*
X829434Y197234D01*
X829559Y196942D01*
Y195901D01*
G01Y196942D02*
X830767Y197567D01*
G01Y200334D02*
X828267D01*
X830059Y198792D01*
Y200876D01*
G01X830767Y202851D02*
X830225Y202934D01*
X829767Y203059D01*
X829350Y203226D01*
X828892Y203434D01*
X828267Y203767D01*
Y202101D01*
G01X830767Y206034D02*
X830725Y206326D01*
X830600Y206659D01*
X830392Y206867D01*
X830100Y206951D01*
X829809Y206867D01*
X829559Y206617D01*
X829434Y206242D01*
Y205826D01*
X829350Y205576D01*
X829142Y205367D01*
X828850Y205284D01*
X828559Y205409D01*
X828350Y205701D01*
X828267Y206034D01*
X828350Y206367D01*
X828559Y206659D01*
X828850Y206784D01*
X829142Y206701D01*
X829350Y206492D01*
X829434Y206242D01*
Y205826D01*
X829559Y205451D01*
X829809Y205201D01*
X830100Y205117D01*
X830392Y205201D01*
X830600Y205409D01*
X830725Y205742D01*
X830767Y206034D01*
G01X840168Y183214D02*
X844168D01*
Y190614D01*
G01X837400Y151476D02*
X834900D01*
Y152517D01*
X835025Y152851D01*
X835192Y153059D01*
X835525Y153142D01*
X835858Y153059D01*
X836067Y152809D01*
X836192Y152517D01*
Y151476D01*
G01Y152517D02*
X837400Y153142D01*
G01Y155909D02*
X834900D01*
X836692Y154367D01*
Y156451D01*
G01X836358Y157717D02*
X836067Y158009D01*
X835900Y158259D01*
X835817Y158592D01*
X835900Y158884D01*
X836067Y159092D01*
X836317Y159259D01*
X836608Y159301D01*
X836858Y159259D01*
X837108Y159092D01*
X837317Y158842D01*
X837400Y158551D01*
X837317Y158217D01*
X837067Y157926D01*
X836692Y157759D01*
X836275Y157717D01*
X835733Y157801D01*
X835442Y157926D01*
X835150Y158134D01*
X834942Y158426D01*
X834900Y158717D01*
X834983Y159009D01*
X835192Y159217D01*
G01X837400Y161526D02*
X836858Y161609D01*
X836400Y161734D01*
X835983Y161901D01*
X835525Y162109D01*
X834900Y162442D01*
Y160776D01*
G01X856622Y157114D02*
X860622D01*
Y164514D01*
G01X814609Y147481D02*
Y149981D01*
X815650D01*
X815984Y149856D01*
X816192Y149689D01*
X816275Y149356D01*
X816192Y149023D01*
X815942Y148814D01*
X815650Y148689D01*
X814609D01*
G01X815650D02*
X816275Y147481D01*
G01X818459D02*
X818542Y148023D01*
X818667Y148481D01*
X818834Y148898D01*
X819042Y149356D01*
X819375Y149981D01*
X817709D01*
G01X821642Y147481D02*
Y149981D01*
X821142Y149481D01*
G01Y147481D02*
X822142D01*
G01X823825Y147981D02*
X824075Y147689D01*
X824409Y147523D01*
X824784Y147481D01*
X825117Y147523D01*
X825450Y147731D01*
X825659Y147981D01*
X825700Y148231D01*
X825617Y148523D01*
X825325Y148731D01*
X825034Y148814D01*
X824659D01*
G01X825034D02*
X825284Y148939D01*
X825492Y149148D01*
X825575Y149398D01*
X825492Y149648D01*
X825284Y149856D01*
X824909Y149981D01*
X824534Y149939D01*
X824159Y149773D01*
G01X848077Y157624D02*
X844077D01*
Y150224D01*
G01X827780Y168341D02*
X825280D01*
Y169382D01*
X825405Y169716D01*
X825572Y169924D01*
X825905Y170007D01*
X826238Y169924D01*
X826447Y169674D01*
X826572Y169382D01*
Y168341D01*
G01Y169382D02*
X827780Y170007D01*
G01Y172774D02*
X825280D01*
X827072Y171232D01*
Y173316D01*
G01X827780Y175291D02*
X827238Y175374D01*
X826780Y175499D01*
X826363Y175666D01*
X825905Y175874D01*
X825280Y176207D01*
Y174541D01*
G01X827280Y177557D02*
X827572Y177807D01*
X827738Y178141D01*
X827780Y178516D01*
X827738Y178849D01*
X827530Y179182D01*
X827280Y179391D01*
X827030Y179432D01*
X826738Y179349D01*
X826530Y179057D01*
X826447Y178766D01*
Y178391D01*
G01Y178766D02*
X826322Y179016D01*
X826113Y179224D01*
X825863Y179307D01*
X825613Y179224D01*
X825405Y179016D01*
X825280Y178641D01*
X825322Y178266D01*
X825488Y177891D01*
G01X816549Y154071D02*
X816299Y154196D01*
X816007Y154279D01*
X815674D01*
X815299Y154154D01*
X815007Y153946D01*
X814799Y153696D01*
X814632Y153279D01*
X814590Y152904D01*
X814674Y152529D01*
X814799Y152279D01*
X815049Y152029D01*
X815340Y151862D01*
X815632Y151779D01*
X815924D01*
X816215Y151862D01*
X816465Y151987D01*
X816674Y152154D01*
G01X818732Y151779D02*
Y154279D01*
X818232Y153779D01*
G01Y151779D02*
X819232D01*
G01X820915Y152154D02*
X821165Y151946D01*
X821457Y151821D01*
X821832Y151779D01*
X822207Y151862D01*
X822499Y152029D01*
X822707Y152321D01*
X822749Y152654D01*
X822665Y152987D01*
X822457Y153196D01*
X822165Y153362D01*
X821874Y153404D01*
X821582Y153362D01*
X821207Y153196D01*
X821332Y154279D01*
X822457D01*
G01X824140Y152821D02*
X824432Y153112D01*
X824682Y153279D01*
X825015Y153362D01*
X825307Y153279D01*
X825515Y153112D01*
X825682Y152862D01*
X825724Y152571D01*
X825682Y152321D01*
X825515Y152071D01*
X825265Y151862D01*
X824974Y151779D01*
X824640Y151862D01*
X824349Y152112D01*
X824182Y152487D01*
X824140Y152904D01*
X824224Y153446D01*
X824349Y153737D01*
X824557Y154029D01*
X824849Y154237D01*
X825140Y154279D01*
X825432Y154196D01*
X825640Y153987D01*
G01X829899Y144878D02*
X829649Y145003D01*
X829357Y145086D01*
X829024D01*
X828649Y144961D01*
X828357Y144753D01*
X828149Y144503D01*
X827982Y144086D01*
X827940Y143711D01*
X828024Y143336D01*
X828149Y143086D01*
X828399Y142836D01*
X828690Y142669D01*
X828982Y142586D01*
X829274D01*
X829565Y142669D01*
X829815Y142794D01*
X830024Y142961D01*
G01X832082Y142586D02*
Y145086D01*
X831582Y144586D01*
G01Y142586D02*
X832582D01*
G01X834390Y143628D02*
X834682Y143919D01*
X834932Y144086D01*
X835265Y144169D01*
X835557Y144086D01*
X835765Y143919D01*
X835932Y143669D01*
X835974Y143378D01*
X835932Y143128D01*
X835765Y142878D01*
X835515Y142669D01*
X835224Y142586D01*
X834890Y142669D01*
X834599Y142919D01*
X834432Y143294D01*
X834390Y143711D01*
X834474Y144253D01*
X834599Y144544D01*
X834807Y144836D01*
X835099Y145044D01*
X835390Y145086D01*
X835682Y145003D01*
X835890Y144794D01*
G01X838282Y145086D02*
X837949Y145003D01*
X837699Y144794D01*
X837532Y144544D01*
X837407Y144211D01*
X837365Y143836D01*
X837407Y143461D01*
X837532Y143128D01*
X837699Y142878D01*
X837949Y142669D01*
X838282Y142586D01*
X838615Y142669D01*
X838865Y142878D01*
X839032Y143128D01*
X839157Y143461D01*
X839199Y143836D01*
X839157Y144211D01*
X839032Y144544D01*
X838865Y144794D01*
X838615Y145003D01*
X838282Y145086D01*
G01X860822Y205115D02*
X855822D01*
Y200115D01*
G01X848568Y186980D02*
X849401D01*
Y186230D01*
X849151Y185980D01*
X848860Y185813D01*
X848443Y185730D01*
X848026Y185813D01*
X847735Y185980D01*
X847485Y186230D01*
X847318Y186522D01*
X847235Y186855D01*
Y187147D01*
X847318Y187397D01*
X847485Y187688D01*
X847735Y187938D01*
X847985Y188105D01*
X848318Y188230D01*
X848610D01*
X848943Y188147D01*
X849193Y187980D01*
G01X850626Y187813D02*
X850876Y188063D01*
X851168Y188188D01*
X851501Y188230D01*
X851918Y188147D01*
X852210Y187938D01*
X852293Y187688D01*
X852251Y187438D01*
X852085Y187230D01*
X851251Y186813D01*
X850876Y186522D01*
X850626Y186105D01*
X850543Y185730D01*
X852293D01*
G01X833661Y207920D02*
Y210420D01*
X834702D01*
X835036Y210295D01*
X835244Y210128D01*
X835327Y209795D01*
X835244Y209462D01*
X834994Y209253D01*
X834702Y209128D01*
X833661D01*
G01X834702D02*
X835327Y207920D01*
G01X838094D02*
Y210420D01*
X836552Y208628D01*
X838636D01*
G01X840611Y207920D02*
X840694Y208462D01*
X840819Y208920D01*
X840986Y209337D01*
X841194Y209795D01*
X841527Y210420D01*
X839861D01*
G01X842877Y208295D02*
X843127Y208087D01*
X843419Y207962D01*
X843794Y207920D01*
X844169Y208003D01*
X844461Y208170D01*
X844669Y208462D01*
X844711Y208795D01*
X844627Y209128D01*
X844419Y209337D01*
X844127Y209503D01*
X843836Y209545D01*
X843544Y209503D01*
X843169Y209337D01*
X843294Y210420D01*
X844419D01*
G01X833661Y215920D02*
Y218420D01*
X834702D01*
X835036Y218295D01*
X835244Y218128D01*
X835327Y217795D01*
X835244Y217462D01*
X834994Y217253D01*
X834702Y217128D01*
X833661D01*
G01X834702D02*
X835327Y215920D01*
G01X838094D02*
Y218420D01*
X836552Y216628D01*
X838636D01*
G01X840611Y215920D02*
X840694Y216462D01*
X840819Y216920D01*
X840986Y217337D01*
X841194Y217795D01*
X841527Y218420D01*
X839861D01*
G01X843794D02*
X843461Y218337D01*
X843211Y218128D01*
X843044Y217878D01*
X842919Y217545D01*
X842877Y217170D01*
X842919Y216795D01*
X843044Y216462D01*
X843211Y216212D01*
X843461Y216003D01*
X843794Y215920D01*
X844127Y216003D01*
X844377Y216212D01*
X844544Y216462D01*
X844669Y216795D01*
X844711Y217170D01*
X844669Y217545D01*
X844544Y217878D01*
X844377Y218128D01*
X844127Y218337D01*
X843794Y218420D01*
G01X854368Y213964D02*
Y217964D01*
X846968D01*
G01X833876Y226005D02*
Y228505D01*
X834917D01*
X835251Y228380D01*
X835459Y228213D01*
X835542Y227880D01*
X835459Y227547D01*
X835209Y227338D01*
X834917Y227213D01*
X833876D01*
G01X834917D02*
X835542Y226005D01*
G01X838309D02*
Y228505D01*
X836767Y226713D01*
X838851D01*
G01X840826Y226005D02*
X840909Y226547D01*
X841034Y227005D01*
X841201Y227422D01*
X841409Y227880D01*
X841742Y228505D01*
X840076D01*
G01X843217Y227047D02*
X843509Y227338D01*
X843759Y227505D01*
X844092Y227588D01*
X844384Y227505D01*
X844592Y227338D01*
X844759Y227088D01*
X844801Y226797D01*
X844759Y226547D01*
X844592Y226297D01*
X844342Y226088D01*
X844051Y226005D01*
X843717Y226088D01*
X843426Y226338D01*
X843259Y226713D01*
X843217Y227130D01*
X843301Y227672D01*
X843426Y227963D01*
X843634Y228255D01*
X843926Y228463D01*
X844217Y228505D01*
X844509Y228422D01*
X844717Y228213D01*
G01X833661Y211920D02*
Y214420D01*
X834702D01*
X835036Y214295D01*
X835244Y214128D01*
X835327Y213795D01*
X835244Y213462D01*
X834994Y213253D01*
X834702Y213128D01*
X833661D01*
G01X834702D02*
X835327Y211920D01*
G01X838094D02*
Y214420D01*
X836552Y212628D01*
X838636D01*
G01X840611Y211920D02*
X840694Y212462D01*
X840819Y212920D01*
X840986Y213337D01*
X841194Y213795D01*
X841527Y214420D01*
X839861D01*
G01X843002Y214003D02*
X843252Y214253D01*
X843544Y214378D01*
X843877Y214420D01*
X844294Y214337D01*
X844586Y214128D01*
X844669Y213878D01*
X844627Y213628D01*
X844461Y213420D01*
X843627Y213003D01*
X843252Y212712D01*
X843002Y212295D01*
X842919Y211920D01*
X844669D01*
G01X846968Y213864D02*
Y209864D01*
X854368D01*
G01X835726Y224292D02*
X835476Y224417D01*
X835184Y224500D01*
X834851D01*
X834476Y224375D01*
X834184Y224167D01*
X833976Y223917D01*
X833809Y223500D01*
X833767Y223125D01*
X833851Y222750D01*
X833976Y222500D01*
X834226Y222250D01*
X834517Y222083D01*
X834809Y222000D01*
X835101D01*
X835392Y222083D01*
X835642Y222208D01*
X835851Y222375D01*
G01X837909Y222000D02*
Y224500D01*
X837409Y224000D01*
G01Y222000D02*
X838409D01*
G01X840217Y223042D02*
X840509Y223333D01*
X840759Y223500D01*
X841092Y223583D01*
X841384Y223500D01*
X841592Y223333D01*
X841759Y223083D01*
X841801Y222792D01*
X841759Y222542D01*
X841592Y222292D01*
X841342Y222083D01*
X841051Y222000D01*
X840717Y222083D01*
X840426Y222333D01*
X840259Y222708D01*
X840217Y223125D01*
X840301Y223667D01*
X840426Y223958D01*
X840634Y224250D01*
X840926Y224458D01*
X841217Y224500D01*
X841509Y224417D01*
X841717Y224208D01*
G01X844109Y222000D02*
Y224500D01*
X843609Y224000D01*
G01Y222000D02*
X844609D01*
G01X822269Y343686D02*
Y346186D01*
X823310D01*
X823644Y346061D01*
X823852Y345894D01*
X823935Y345561D01*
X823852Y345228D01*
X823602Y345019D01*
X823310Y344894D01*
X822269D01*
G01X823310D02*
X823935Y343686D01*
G01X826202D02*
X826494Y343728D01*
X826827Y343853D01*
X827035Y344061D01*
X827119Y344353D01*
X827035Y344644D01*
X826785Y344894D01*
X826410Y345019D01*
X825994D01*
X825744Y345103D01*
X825535Y345311D01*
X825452Y345603D01*
X825577Y345894D01*
X825869Y346103D01*
X826202Y346186D01*
X826535Y346103D01*
X826827Y345894D01*
X826952Y345603D01*
X826869Y345311D01*
X826660Y345103D01*
X826410Y345019D01*
X825994D01*
X825619Y344894D01*
X825369Y344644D01*
X825285Y344353D01*
X825369Y344061D01*
X825577Y343853D01*
X825910Y343728D01*
X826202Y343686D01*
G01X828385Y344186D02*
X828635Y343894D01*
X828969Y343728D01*
X829344Y343686D01*
X829677Y343728D01*
X830010Y343936D01*
X830219Y344186D01*
X830260Y344436D01*
X830177Y344728D01*
X829885Y344936D01*
X829594Y345019D01*
X829219D01*
G01X829594D02*
X829844Y345144D01*
X830052Y345353D01*
X830135Y345603D01*
X830052Y345853D01*
X829844Y346061D01*
X829469Y346186D01*
X829094Y346144D01*
X828719Y345978D01*
G01X831610Y344728D02*
X831902Y345019D01*
X832152Y345186D01*
X832485Y345269D01*
X832777Y345186D01*
X832985Y345019D01*
X833152Y344769D01*
X833194Y344478D01*
X833152Y344228D01*
X832985Y343978D01*
X832735Y343769D01*
X832444Y343686D01*
X832110Y343769D01*
X831819Y344019D01*
X831652Y344394D01*
X831610Y344811D01*
X831694Y345353D01*
X831819Y345644D01*
X832027Y345936D01*
X832319Y346144D01*
X832610Y346186D01*
X832902Y346103D01*
X833110Y345894D01*
G01X844056Y346740D02*
Y342740D01*
X851456D01*
G01X841616Y349914D02*
Y353914D01*
X834216D01*
G01X824019Y341978D02*
X823769Y342103D01*
X823477Y342186D01*
X823144D01*
X822769Y342061D01*
X822477Y341853D01*
X822269Y341603D01*
X822102Y341186D01*
X822060Y340811D01*
X822144Y340436D01*
X822269Y340186D01*
X822519Y339936D01*
X822810Y339769D01*
X823102Y339686D01*
X823394D01*
X823685Y339769D01*
X823935Y339894D01*
X824144Y340061D01*
G01X825410Y340728D02*
X825702Y341019D01*
X825952Y341186D01*
X826285Y341269D01*
X826577Y341186D01*
X826785Y341019D01*
X826952Y340769D01*
X826994Y340478D01*
X826952Y340228D01*
X826785Y339978D01*
X826535Y339769D01*
X826244Y339686D01*
X825910Y339769D01*
X825619Y340019D01*
X825452Y340394D01*
X825410Y340811D01*
X825494Y341353D01*
X825619Y341644D01*
X825827Y341936D01*
X826119Y342144D01*
X826410Y342186D01*
X826702Y342103D01*
X826910Y341894D01*
G01X828385Y340061D02*
X828635Y339853D01*
X828927Y339728D01*
X829302Y339686D01*
X829677Y339769D01*
X829969Y339936D01*
X830177Y340228D01*
X830219Y340561D01*
X830135Y340894D01*
X829927Y341103D01*
X829635Y341269D01*
X829344Y341311D01*
X829052Y341269D01*
X828677Y341103D01*
X828802Y342186D01*
X829927D01*
G01X831610Y341769D02*
X831860Y342019D01*
X832152Y342144D01*
X832485Y342186D01*
X832902Y342103D01*
X833194Y341894D01*
X833277Y341644D01*
X833235Y341394D01*
X833069Y341186D01*
X832235Y340769D01*
X831860Y340478D01*
X831610Y340061D01*
X831527Y339686D01*
X833277D01*
G01X856756Y365001D02*
X898156D01*
Y314401D01*
X856756D01*
Y365001D01*
G01X826563Y378424D02*
X826438Y378174D01*
X826355Y377882D01*
Y377549D01*
X826480Y377174D01*
X826688Y376882D01*
X826938Y376674D01*
X827355Y376507D01*
X827730Y376465D01*
X828105Y376549D01*
X828355Y376674D01*
X828605Y376924D01*
X828772Y377215D01*
X828855Y377507D01*
Y377799D01*
X828772Y378090D01*
X828647Y378340D01*
X828480Y378549D01*
G01X827813Y379815D02*
X827522Y380107D01*
X827355Y380357D01*
X827272Y380690D01*
X827355Y380982D01*
X827522Y381190D01*
X827772Y381357D01*
X828063Y381399D01*
X828313Y381357D01*
X828563Y381190D01*
X828772Y380940D01*
X828855Y380649D01*
X828772Y380315D01*
X828522Y380024D01*
X828147Y379857D01*
X827730Y379815D01*
X827188Y379899D01*
X826897Y380024D01*
X826605Y380232D01*
X826397Y380524D01*
X826355Y380815D01*
X826438Y381107D01*
X826647Y381315D01*
G01X828855Y384207D02*
X826355D01*
X828147Y382665D01*
Y384749D01*
G01X828855Y387307D02*
X826355D01*
X828147Y385765D01*
Y387849D01*
G01X822563Y378424D02*
X822438Y378174D01*
X822355Y377882D01*
Y377549D01*
X822480Y377174D01*
X822688Y376882D01*
X822938Y376674D01*
X823355Y376507D01*
X823730Y376465D01*
X824105Y376549D01*
X824355Y376674D01*
X824605Y376924D01*
X824772Y377215D01*
X824855Y377507D01*
Y377799D01*
X824772Y378090D01*
X824647Y378340D01*
X824480Y378549D01*
G01X823813Y379815D02*
X823522Y380107D01*
X823355Y380357D01*
X823272Y380690D01*
X823355Y380982D01*
X823522Y381190D01*
X823772Y381357D01*
X824063Y381399D01*
X824313Y381357D01*
X824563Y381190D01*
X824772Y380940D01*
X824855Y380649D01*
X824772Y380315D01*
X824522Y380024D01*
X824147Y379857D01*
X823730Y379815D01*
X823188Y379899D01*
X822897Y380024D01*
X822605Y380232D01*
X822397Y380524D01*
X822355Y380815D01*
X822438Y381107D01*
X822647Y381315D01*
G01X824855Y384207D02*
X822355D01*
X824147Y382665D01*
Y384749D01*
G01X824855Y386807D02*
X824813Y387099D01*
X824688Y387432D01*
X824480Y387640D01*
X824188Y387724D01*
X823897Y387640D01*
X823647Y387390D01*
X823522Y387015D01*
Y386599D01*
X823438Y386349D01*
X823230Y386140D01*
X822938Y386057D01*
X822647Y386182D01*
X822438Y386474D01*
X822355Y386807D01*
X822438Y387140D01*
X822647Y387432D01*
X822938Y387557D01*
X823230Y387474D01*
X823438Y387265D01*
X823522Y387015D01*
Y386599D01*
X823647Y386224D01*
X823897Y385974D01*
X824188Y385890D01*
X824480Y385974D01*
X824688Y386182D01*
X824813Y386515D01*
X824855Y386807D01*
G01X809610Y355385D02*
Y357885D01*
X810651D01*
X810985Y357760D01*
X811193Y357593D01*
X811276Y357260D01*
X811193Y356927D01*
X810943Y356718D01*
X810651Y356593D01*
X809610D01*
G01X810651D02*
X811276Y355385D01*
G01X813543D02*
X813835Y355427D01*
X814168Y355552D01*
X814376Y355760D01*
X814460Y356052D01*
X814376Y356343D01*
X814126Y356593D01*
X813751Y356718D01*
X813335D01*
X813085Y356802D01*
X812876Y357010D01*
X812793Y357302D01*
X812918Y357593D01*
X813210Y357802D01*
X813543Y357885D01*
X813876Y357802D01*
X814168Y357593D01*
X814293Y357302D01*
X814210Y357010D01*
X814001Y356802D01*
X813751Y356718D01*
X813335D01*
X812960Y356593D01*
X812710Y356343D01*
X812626Y356052D01*
X812710Y355760D01*
X812918Y355552D01*
X813251Y355427D01*
X813543Y355385D01*
G01X815851Y357468D02*
X816101Y357718D01*
X816393Y357843D01*
X816726Y357885D01*
X817143Y357802D01*
X817435Y357593D01*
X817518Y357343D01*
X817476Y357093D01*
X817310Y356885D01*
X816476Y356468D01*
X816101Y356177D01*
X815851Y355760D01*
X815768Y355385D01*
X817518D01*
G01X819743Y357885D02*
X819410Y357802D01*
X819160Y357593D01*
X818993Y357343D01*
X818868Y357010D01*
X818826Y356635D01*
X818868Y356260D01*
X818993Y355927D01*
X819160Y355677D01*
X819410Y355468D01*
X819743Y355385D01*
X820076Y355468D01*
X820326Y355677D01*
X820493Y355927D01*
X820618Y356260D01*
X820660Y356635D01*
X820618Y357010D01*
X820493Y357343D01*
X820326Y357593D01*
X820076Y357802D01*
X819743Y357885D01*
G01X841639Y354008D02*
Y358008D01*
X834239D01*
G01X829915Y402051D02*
Y404551D01*
X830956D01*
X831290Y404426D01*
X831498Y404259D01*
X831581Y403926D01*
X831498Y403593D01*
X831248Y403384D01*
X830956Y403259D01*
X829915D01*
G01X830956D02*
X831581Y402051D01*
G01X833848D02*
X834140Y402093D01*
X834473Y402218D01*
X834681Y402426D01*
X834765Y402718D01*
X834681Y403009D01*
X834431Y403259D01*
X834056Y403384D01*
X833640D01*
X833390Y403468D01*
X833181Y403676D01*
X833098Y403968D01*
X833223Y404259D01*
X833515Y404468D01*
X833848Y404551D01*
X834181Y404468D01*
X834473Y404259D01*
X834598Y403968D01*
X834515Y403676D01*
X834306Y403468D01*
X834056Y403384D01*
X833640D01*
X833265Y403259D01*
X833015Y403009D01*
X832931Y402718D01*
X833015Y402426D01*
X833223Y402218D01*
X833556Y402093D01*
X833848Y402051D01*
G01X836156Y404134D02*
X836406Y404384D01*
X836698Y404509D01*
X837031Y404551D01*
X837448Y404468D01*
X837740Y404259D01*
X837823Y404009D01*
X837781Y403759D01*
X837615Y403551D01*
X836781Y403134D01*
X836406Y402843D01*
X836156Y402426D01*
X836073Y402051D01*
X837823D01*
G01X840548D02*
Y404551D01*
X839006Y402759D01*
X841090D01*
G01X843460Y405998D02*
Y401998D01*
X850860D01*
G01X834573Y378731D02*
X832073D01*
Y379772D01*
X832198Y380106D01*
X832365Y380314D01*
X832698Y380397D01*
X833031Y380314D01*
X833240Y380064D01*
X833365Y379772D01*
Y378731D01*
G01Y379772D02*
X834573Y380397D01*
G01Y382664D02*
X834531Y382956D01*
X834406Y383289D01*
X834198Y383497D01*
X833906Y383581D01*
X833615Y383497D01*
X833365Y383247D01*
X833240Y382872D01*
Y382456D01*
X833156Y382206D01*
X832948Y381997D01*
X832656Y381914D01*
X832365Y382039D01*
X832156Y382331D01*
X832073Y382664D01*
X832156Y382997D01*
X832365Y383289D01*
X832656Y383414D01*
X832948Y383331D01*
X833156Y383122D01*
X833240Y382872D01*
Y382456D01*
X833365Y382081D01*
X833615Y381831D01*
X833906Y381747D01*
X834198Y381831D01*
X834406Y382039D01*
X834531Y382372D01*
X834573Y382664D01*
G01X832490Y384972D02*
X832240Y385222D01*
X832115Y385514D01*
X832073Y385847D01*
X832156Y386264D01*
X832365Y386556D01*
X832615Y386639D01*
X832865Y386597D01*
X833073Y386431D01*
X833490Y385597D01*
X833781Y385222D01*
X834198Y384972D01*
X834573Y384889D01*
Y386639D01*
G01X834198Y387947D02*
X834406Y388197D01*
X834531Y388489D01*
X834573Y388864D01*
X834490Y389239D01*
X834323Y389531D01*
X834031Y389739D01*
X833698Y389781D01*
X833365Y389697D01*
X833156Y389489D01*
X832990Y389197D01*
X832948Y388906D01*
X832990Y388614D01*
X833156Y388239D01*
X832073Y388364D01*
Y389489D01*
G01X840627Y384215D02*
X836627D01*
Y376815D01*
G01X824696Y351569D02*
X822196D01*
Y352610D01*
X822321Y352944D01*
X822488Y353152D01*
X822821Y353235D01*
X823154Y353152D01*
X823363Y352902D01*
X823488Y352610D01*
Y351569D01*
G01Y352610D02*
X824696Y353235D01*
G01Y355502D02*
X824654Y355794D01*
X824529Y356127D01*
X824321Y356335D01*
X824029Y356419D01*
X823738Y356335D01*
X823488Y356085D01*
X823363Y355710D01*
Y355294D01*
X823279Y355044D01*
X823071Y354835D01*
X822779Y354752D01*
X822488Y354877D01*
X822279Y355169D01*
X822196Y355502D01*
X822279Y355835D01*
X822488Y356127D01*
X822779Y356252D01*
X823071Y356169D01*
X823279Y355960D01*
X823363Y355710D01*
Y355294D01*
X823488Y354919D01*
X823738Y354669D01*
X824029Y354585D01*
X824321Y354669D01*
X824529Y354877D01*
X824654Y355210D01*
X824696Y355502D01*
G01X822613Y357810D02*
X822363Y358060D01*
X822238Y358352D01*
X822196Y358685D01*
X822279Y359102D01*
X822488Y359394D01*
X822738Y359477D01*
X822988Y359435D01*
X823196Y359269D01*
X823613Y358435D01*
X823904Y358060D01*
X824321Y357810D01*
X824696Y357727D01*
Y359477D01*
G01X823654Y360910D02*
X823363Y361202D01*
X823196Y361452D01*
X823113Y361785D01*
X823196Y362077D01*
X823363Y362285D01*
X823613Y362452D01*
X823904Y362494D01*
X824154Y362452D01*
X824404Y362285D01*
X824613Y362035D01*
X824696Y361744D01*
X824613Y361410D01*
X824363Y361119D01*
X823988Y360952D01*
X823571Y360910D01*
X823029Y360994D01*
X822738Y361119D01*
X822446Y361327D01*
X822238Y361619D01*
X822196Y361910D01*
X822279Y362202D01*
X822488Y362410D01*
G01X848456Y359457D02*
X844456D01*
Y352057D01*
G01X809610Y359385D02*
Y361885D01*
X810651D01*
X810985Y361760D01*
X811193Y361593D01*
X811276Y361260D01*
X811193Y360927D01*
X810943Y360718D01*
X810651Y360593D01*
X809610D01*
G01X810651D02*
X811276Y359385D01*
G01X813543D02*
X813835Y359427D01*
X814168Y359552D01*
X814376Y359760D01*
X814460Y360052D01*
X814376Y360343D01*
X814126Y360593D01*
X813751Y360718D01*
X813335D01*
X813085Y360802D01*
X812876Y361010D01*
X812793Y361302D01*
X812918Y361593D01*
X813210Y361802D01*
X813543Y361885D01*
X813876Y361802D01*
X814168Y361593D01*
X814293Y361302D01*
X814210Y361010D01*
X814001Y360802D01*
X813751Y360718D01*
X813335D01*
X812960Y360593D01*
X812710Y360343D01*
X812626Y360052D01*
X812710Y359760D01*
X812918Y359552D01*
X813251Y359427D01*
X813543Y359385D01*
G01X815851Y361468D02*
X816101Y361718D01*
X816393Y361843D01*
X816726Y361885D01*
X817143Y361802D01*
X817435Y361593D01*
X817518Y361343D01*
X817476Y361093D01*
X817310Y360885D01*
X816476Y360468D01*
X816101Y360177D01*
X815851Y359760D01*
X815768Y359385D01*
X817518D01*
G01X819743D02*
X820035Y359427D01*
X820368Y359552D01*
X820576Y359760D01*
X820660Y360052D01*
X820576Y360343D01*
X820326Y360593D01*
X819951Y360718D01*
X819535D01*
X819285Y360802D01*
X819076Y361010D01*
X818993Y361302D01*
X819118Y361593D01*
X819410Y361802D01*
X819743Y361885D01*
X820076Y361802D01*
X820368Y361593D01*
X820493Y361302D01*
X820410Y361010D01*
X820201Y360802D01*
X819951Y360718D01*
X819535D01*
X819160Y360593D01*
X818910Y360343D01*
X818826Y360052D01*
X818910Y359760D01*
X819118Y359552D01*
X819451Y359427D01*
X819743Y359385D01*
G01X841613Y358311D02*
Y362311D01*
X834213D01*
G01X828696Y351569D02*
X826196D01*
Y352610D01*
X826321Y352944D01*
X826488Y353152D01*
X826821Y353235D01*
X827154Y353152D01*
X827363Y352902D01*
X827488Y352610D01*
Y351569D01*
G01Y352610D02*
X828696Y353235D01*
G01Y355502D02*
X828654Y355794D01*
X828529Y356127D01*
X828321Y356335D01*
X828029Y356419D01*
X827738Y356335D01*
X827488Y356085D01*
X827363Y355710D01*
Y355294D01*
X827279Y355044D01*
X827071Y354835D01*
X826779Y354752D01*
X826488Y354877D01*
X826279Y355169D01*
X826196Y355502D01*
X826279Y355835D01*
X826488Y356127D01*
X826779Y356252D01*
X827071Y356169D01*
X827279Y355960D01*
X827363Y355710D01*
Y355294D01*
X827488Y354919D01*
X827738Y354669D01*
X828029Y354585D01*
X828321Y354669D01*
X828529Y354877D01*
X828654Y355210D01*
X828696Y355502D01*
G01X828196Y357685D02*
X828488Y357935D01*
X828654Y358269D01*
X828696Y358644D01*
X828654Y358977D01*
X828446Y359310D01*
X828196Y359519D01*
X827946Y359560D01*
X827654Y359477D01*
X827446Y359185D01*
X827363Y358894D01*
Y358519D01*
G01Y358894D02*
X827238Y359144D01*
X827029Y359352D01*
X826779Y359435D01*
X826529Y359352D01*
X826321Y359144D01*
X826196Y358769D01*
X826238Y358394D01*
X826404Y358019D01*
G01X828696Y361702D02*
X826196D01*
X826696Y361202D01*
G01X828696D02*
Y362202D01*
G01X848730Y352078D02*
X852730D01*
Y359478D01*
G01X809610Y351385D02*
Y353885D01*
X810651D01*
X810985Y353760D01*
X811193Y353593D01*
X811276Y353260D01*
X811193Y352927D01*
X810943Y352718D01*
X810651Y352593D01*
X809610D01*
G01X810651D02*
X811276Y351385D01*
G01X813543D02*
X813835Y351427D01*
X814168Y351552D01*
X814376Y351760D01*
X814460Y352052D01*
X814376Y352343D01*
X814126Y352593D01*
X813751Y352718D01*
X813335D01*
X813085Y352802D01*
X812876Y353010D01*
X812793Y353302D01*
X812918Y353593D01*
X813210Y353802D01*
X813543Y353885D01*
X813876Y353802D01*
X814168Y353593D01*
X814293Y353302D01*
X814210Y353010D01*
X814001Y352802D01*
X813751Y352718D01*
X813335D01*
X812960Y352593D01*
X812710Y352343D01*
X812626Y352052D01*
X812710Y351760D01*
X812918Y351552D01*
X813251Y351427D01*
X813543Y351385D01*
G01X815726Y351885D02*
X815976Y351593D01*
X816310Y351427D01*
X816685Y351385D01*
X817018Y351427D01*
X817351Y351635D01*
X817560Y351885D01*
X817601Y352135D01*
X817518Y352427D01*
X817226Y352635D01*
X816935Y352718D01*
X816560D01*
G01X816935D02*
X817185Y352843D01*
X817393Y353052D01*
X817476Y353302D01*
X817393Y353552D01*
X817185Y353760D01*
X816810Y353885D01*
X816435Y353843D01*
X816060Y353677D01*
G01X819035Y351677D02*
X819326Y351468D01*
X819660Y351385D01*
X819993Y351468D01*
X820285Y351718D01*
X820493Y352093D01*
X820576Y352468D01*
Y352927D01*
X820493Y353302D01*
X820285Y353635D01*
X820035Y353802D01*
X819743Y353885D01*
X819410Y353802D01*
X819160Y353635D01*
X818993Y353385D01*
X818910Y353052D01*
X818993Y352760D01*
X819201Y352468D01*
X819451Y352302D01*
X819743Y352260D01*
X820076Y352343D01*
X820326Y352552D01*
X820576Y352927D01*
G01X820855Y376674D02*
X818355D01*
Y377715D01*
X818480Y378049D01*
X818647Y378257D01*
X818980Y378340D01*
X819313Y378257D01*
X819522Y378007D01*
X819647Y377715D01*
Y376674D01*
G01Y377715D02*
X820855Y378340D01*
G01Y380607D02*
X820813Y380899D01*
X820688Y381232D01*
X820480Y381440D01*
X820188Y381524D01*
X819897Y381440D01*
X819647Y381190D01*
X819522Y380815D01*
Y380399D01*
X819438Y380149D01*
X819230Y379940D01*
X818938Y379857D01*
X818647Y379982D01*
X818438Y380274D01*
X818355Y380607D01*
X818438Y380940D01*
X818647Y381232D01*
X818938Y381357D01*
X819230Y381274D01*
X819438Y381065D01*
X819522Y380815D01*
Y380399D01*
X819647Y380024D01*
X819897Y379774D01*
X820188Y379690D01*
X820480Y379774D01*
X820688Y379982D01*
X820813Y380315D01*
X820855Y380607D01*
G01Y384207D02*
X818355D01*
X820147Y382665D01*
Y384749D01*
G01X818355Y386807D02*
X818438Y386474D01*
X818647Y386224D01*
X818897Y386057D01*
X819230Y385932D01*
X819605Y385890D01*
X819980Y385932D01*
X820313Y386057D01*
X820563Y386224D01*
X820772Y386474D01*
X820855Y386807D01*
X820772Y387140D01*
X820563Y387390D01*
X820313Y387557D01*
X819980Y387682D01*
X819605Y387724D01*
X819230Y387682D01*
X818897Y387557D01*
X818647Y387390D01*
X818438Y387140D01*
X818355Y386807D01*
G01X836984Y376469D02*
X832984D01*
Y369069D01*
G01X852673Y410906D02*
X850173D01*
Y411947D01*
X850298Y412281D01*
X850465Y412489D01*
X850798Y412572D01*
X851131Y412489D01*
X851340Y412239D01*
X851465Y411947D01*
Y410906D01*
G01Y411947D02*
X852673Y412572D01*
G01Y414839D02*
X852631Y415131D01*
X852506Y415464D01*
X852298Y415672D01*
X852006Y415756D01*
X851715Y415672D01*
X851465Y415422D01*
X851340Y415047D01*
Y414631D01*
X851256Y414381D01*
X851048Y414172D01*
X850756Y414089D01*
X850465Y414214D01*
X850256Y414506D01*
X850173Y414839D01*
X850256Y415172D01*
X850465Y415464D01*
X850756Y415589D01*
X851048Y415506D01*
X851256Y415297D01*
X851340Y415047D01*
Y414631D01*
X851465Y414256D01*
X851715Y414006D01*
X852006Y413922D01*
X852298Y414006D01*
X852506Y414214D01*
X852631Y414547D01*
X852673Y414839D01*
G01Y418439D02*
X850173D01*
X851965Y416897D01*
Y418981D01*
G01X852673Y421039D02*
X850173D01*
X850673Y420539D01*
G01X852673D02*
Y421539D01*
G01X851060Y402298D02*
X855060D01*
Y409698D01*
G01X829915Y394051D02*
Y396551D01*
X830956D01*
X831290Y396426D01*
X831498Y396259D01*
X831581Y395926D01*
X831498Y395593D01*
X831248Y395384D01*
X830956Y395259D01*
X829915D01*
G01X830956D02*
X831581Y394051D01*
G01X833848D02*
X834140Y394093D01*
X834473Y394218D01*
X834681Y394426D01*
X834765Y394718D01*
X834681Y395009D01*
X834431Y395259D01*
X834056Y395384D01*
X833640D01*
X833390Y395468D01*
X833181Y395676D01*
X833098Y395968D01*
X833223Y396259D01*
X833515Y396468D01*
X833848Y396551D01*
X834181Y396468D01*
X834473Y396259D01*
X834598Y395968D01*
X834515Y395676D01*
X834306Y395468D01*
X834056Y395384D01*
X833640D01*
X833265Y395259D01*
X833015Y395009D01*
X832931Y394718D01*
X833015Y394426D01*
X833223Y394218D01*
X833556Y394093D01*
X833848Y394051D01*
G01X837448D02*
Y396551D01*
X835906Y394759D01*
X837990D01*
G01X839256Y396134D02*
X839506Y396384D01*
X839798Y396509D01*
X840131Y396551D01*
X840548Y396468D01*
X840840Y396259D01*
X840923Y396009D01*
X840881Y395759D01*
X840715Y395551D01*
X839881Y395134D01*
X839506Y394843D01*
X839256Y394426D01*
X839173Y394051D01*
X840923D01*
G01X843460Y397998D02*
Y393998D01*
X850860D01*
G01X829915Y398051D02*
Y400551D01*
X830956D01*
X831290Y400426D01*
X831498Y400259D01*
X831581Y399926D01*
X831498Y399593D01*
X831248Y399384D01*
X830956Y399259D01*
X829915D01*
G01X830956D02*
X831581Y398051D01*
G01X833848D02*
X834140Y398093D01*
X834473Y398218D01*
X834681Y398426D01*
X834765Y398718D01*
X834681Y399009D01*
X834431Y399259D01*
X834056Y399384D01*
X833640D01*
X833390Y399468D01*
X833181Y399676D01*
X833098Y399968D01*
X833223Y400259D01*
X833515Y400468D01*
X833848Y400551D01*
X834181Y400468D01*
X834473Y400259D01*
X834598Y399968D01*
X834515Y399676D01*
X834306Y399468D01*
X834056Y399384D01*
X833640D01*
X833265Y399259D01*
X833015Y399009D01*
X832931Y398718D01*
X833015Y398426D01*
X833223Y398218D01*
X833556Y398093D01*
X833848Y398051D01*
G01X837448D02*
Y400551D01*
X835906Y398759D01*
X837990D01*
G01X839131Y398551D02*
X839381Y398259D01*
X839715Y398093D01*
X840090Y398051D01*
X840423Y398093D01*
X840756Y398301D01*
X840965Y398551D01*
X841006Y398801D01*
X840923Y399093D01*
X840631Y399301D01*
X840340Y399384D01*
X839965D01*
G01X840340D02*
X840590Y399509D01*
X840798Y399718D01*
X840881Y399968D01*
X840798Y400218D01*
X840590Y400426D01*
X840215Y400551D01*
X839840Y400509D01*
X839465Y400343D01*
G01X843460Y401998D02*
Y397998D01*
X850860D01*
G01X815117Y415500D02*
Y418000D01*
X816158D01*
X816492Y417875D01*
X816700Y417708D01*
X816783Y417375D01*
X816700Y417042D01*
X816450Y416833D01*
X816158Y416708D01*
X815117D01*
G01X816158D02*
X816783Y415500D01*
G01X818133Y415875D02*
X818383Y415667D01*
X818675Y415542D01*
X819050Y415500D01*
X819425Y415583D01*
X819717Y415750D01*
X819925Y416042D01*
X819967Y416375D01*
X819883Y416708D01*
X819675Y416917D01*
X819383Y417083D01*
X819092Y417125D01*
X818800Y417083D01*
X818425Y416917D01*
X818550Y418000D01*
X819675D01*
G01X821233Y415875D02*
X821483Y415667D01*
X821775Y415542D01*
X822150Y415500D01*
X822525Y415583D01*
X822817Y415750D01*
X823025Y416042D01*
X823067Y416375D01*
X822983Y416708D01*
X822775Y416917D01*
X822483Y417083D01*
X822192Y417125D01*
X821900Y417083D01*
X821525Y416917D01*
X821650Y418000D01*
X822775D01*
G01X825250D02*
X824917Y417917D01*
X824667Y417708D01*
X824500Y417458D01*
X824375Y417125D01*
X824333Y416750D01*
X824375Y416375D01*
X824500Y416042D01*
X824667Y415792D01*
X824917Y415583D01*
X825250Y415500D01*
X825583Y415583D01*
X825833Y415792D01*
X826000Y416042D01*
X826125Y416375D01*
X826167Y416750D01*
X826125Y417125D01*
X826000Y417458D01*
X825833Y417708D01*
X825583Y417917D01*
X825250Y418000D01*
G01X815117Y419500D02*
Y422000D01*
X816158D01*
X816492Y421875D01*
X816700Y421708D01*
X816783Y421375D01*
X816700Y421042D01*
X816450Y420833D01*
X816158Y420708D01*
X815117D01*
G01X816158D02*
X816783Y419500D01*
G01X818133Y419875D02*
X818383Y419667D01*
X818675Y419542D01*
X819050Y419500D01*
X819425Y419583D01*
X819717Y419750D01*
X819925Y420042D01*
X819967Y420375D01*
X819883Y420708D01*
X819675Y420917D01*
X819383Y421083D01*
X819092Y421125D01*
X818800Y421083D01*
X818425Y420917D01*
X818550Y422000D01*
X819675D01*
G01X821233Y419875D02*
X821483Y419667D01*
X821775Y419542D01*
X822150Y419500D01*
X822525Y419583D01*
X822817Y419750D01*
X823025Y420042D01*
X823067Y420375D01*
X822983Y420708D01*
X822775Y420917D01*
X822483Y421083D01*
X822192Y421125D01*
X821900Y421083D01*
X821525Y420917D01*
X821650Y422000D01*
X822775D01*
G01X825750Y419500D02*
Y422000D01*
X824208Y420208D01*
X826292D01*
G01X798100Y395200D02*
X794100D01*
Y387800D01*
G01X791525Y380748D02*
X789025D01*
Y381789D01*
X789150Y382123D01*
X789317Y382331D01*
X789650Y382414D01*
X789983Y382331D01*
X790192Y382081D01*
X790317Y381789D01*
Y380748D01*
G01Y381789D02*
X791525Y382414D01*
G01X791150Y383764D02*
X791358Y384014D01*
X791483Y384306D01*
X791525Y384681D01*
X791442Y385056D01*
X791275Y385348D01*
X790983Y385556D01*
X790650Y385598D01*
X790317Y385514D01*
X790108Y385306D01*
X789942Y385014D01*
X789900Y384723D01*
X789942Y384431D01*
X790108Y384056D01*
X789025Y384181D01*
Y385306D01*
G01X791150Y386864D02*
X791358Y387114D01*
X791483Y387406D01*
X791525Y387781D01*
X791442Y388156D01*
X791275Y388448D01*
X790983Y388656D01*
X790650Y388698D01*
X790317Y388614D01*
X790108Y388406D01*
X789942Y388114D01*
X789900Y387823D01*
X789942Y387531D01*
X790108Y387156D01*
X789025Y387281D01*
Y388406D01*
G01X791233Y390173D02*
X791442Y390464D01*
X791525Y390798D01*
X791442Y391131D01*
X791192Y391423D01*
X790817Y391631D01*
X790442Y391714D01*
X789983D01*
X789608Y391631D01*
X789275Y391423D01*
X789108Y391173D01*
X789025Y390881D01*
X789108Y390548D01*
X789275Y390298D01*
X789525Y390131D01*
X789858Y390048D01*
X790150Y390131D01*
X790442Y390339D01*
X790608Y390589D01*
X790650Y390881D01*
X790567Y391214D01*
X790358Y391464D01*
X789983Y391714D01*
G01X803200Y395200D02*
X799200D01*
Y387800D01*
G01X802211Y370179D02*
Y372679D01*
X803252D01*
X803586Y372554D01*
X803794Y372387D01*
X803877Y372054D01*
X803794Y371721D01*
X803544Y371512D01*
X803252Y371387D01*
X802211D01*
G01X803252D02*
X803877Y370179D01*
G01X806144D02*
X806436Y370221D01*
X806769Y370346D01*
X806977Y370554D01*
X807061Y370846D01*
X806977Y371137D01*
X806727Y371387D01*
X806352Y371512D01*
X805936D01*
X805686Y371596D01*
X805477Y371804D01*
X805394Y372096D01*
X805519Y372387D01*
X805811Y372596D01*
X806144Y372679D01*
X806477Y372596D01*
X806769Y372387D01*
X806894Y372096D01*
X806811Y371804D01*
X806602Y371596D01*
X806352Y371512D01*
X805936D01*
X805561Y371387D01*
X805311Y371137D01*
X805227Y370846D01*
X805311Y370554D01*
X805519Y370346D01*
X805852Y370221D01*
X806144Y370179D01*
G01X808452Y372262D02*
X808702Y372512D01*
X808994Y372637D01*
X809327Y372679D01*
X809744Y372596D01*
X810036Y372387D01*
X810119Y372137D01*
X810077Y371887D01*
X809911Y371679D01*
X809077Y371262D01*
X808702Y370971D01*
X808452Y370554D01*
X808369Y370179D01*
X810119D01*
G01X811636Y370471D02*
X811927Y370262D01*
X812261Y370179D01*
X812594Y370262D01*
X812886Y370512D01*
X813094Y370887D01*
X813177Y371262D01*
Y371721D01*
X813094Y372096D01*
X812886Y372429D01*
X812636Y372596D01*
X812344Y372679D01*
X812011Y372596D01*
X811761Y372429D01*
X811594Y372179D01*
X811511Y371846D01*
X811594Y371554D01*
X811802Y371262D01*
X812052Y371096D01*
X812344Y371054D01*
X812677Y371137D01*
X812927Y371346D01*
X813177Y371721D01*
G01X832431Y367154D02*
X832181Y367279D01*
X831889Y367362D01*
X831556D01*
X831181Y367237D01*
X830889Y367029D01*
X830681Y366779D01*
X830514Y366362D01*
X830472Y365987D01*
X830556Y365612D01*
X830681Y365362D01*
X830931Y365112D01*
X831222Y364945D01*
X831514Y364862D01*
X831806D01*
X832097Y364945D01*
X832347Y365070D01*
X832556Y365237D01*
G01X833822Y365904D02*
X834114Y366195D01*
X834364Y366362D01*
X834697Y366445D01*
X834989Y366362D01*
X835197Y366195D01*
X835364Y365945D01*
X835406Y365654D01*
X835364Y365404D01*
X835197Y365154D01*
X834947Y364945D01*
X834656Y364862D01*
X834322Y364945D01*
X834031Y365195D01*
X833864Y365570D01*
X833822Y365987D01*
X833906Y366529D01*
X834031Y366820D01*
X834239Y367112D01*
X834531Y367320D01*
X834822Y367362D01*
X835114Y367279D01*
X835322Y367070D01*
G01X837631Y364862D02*
X837714Y365404D01*
X837839Y365862D01*
X838006Y366279D01*
X838214Y366737D01*
X838547Y367362D01*
X836881D01*
G01X840814D02*
X840481Y367279D01*
X840231Y367070D01*
X840064Y366820D01*
X839939Y366487D01*
X839897Y366112D01*
X839939Y365737D01*
X840064Y365404D01*
X840231Y365154D01*
X840481Y364945D01*
X840814Y364862D01*
X841147Y364945D01*
X841397Y365154D01*
X841564Y365404D01*
X841689Y365737D01*
X841731Y366112D01*
X841689Y366487D01*
X841564Y366820D01*
X841397Y367070D01*
X841147Y367279D01*
X840814Y367362D01*
G01X805444Y409875D02*
Y417875D01*
X793494D01*
Y409875D01*
X805444D01*
G01X793494Y416025D02*
X795494Y414025D01*
X793494Y412025D01*
G01X812768Y398865D02*
Y396365D01*
G01X811810Y398865D02*
X813726D01*
G01X815035Y396365D02*
Y398865D01*
X816035D01*
X816368Y398740D01*
X816618Y398448D01*
X816701Y398115D01*
X816618Y397782D01*
X816410Y397532D01*
X816035Y397407D01*
X815035D01*
G01X818176Y398448D02*
X818426Y398698D01*
X818718Y398823D01*
X819051Y398865D01*
X819468Y398782D01*
X819760Y398573D01*
X819843Y398323D01*
X819801Y398073D01*
X819635Y397865D01*
X818801Y397448D01*
X818426Y397157D01*
X818176Y396740D01*
X818093Y396365D01*
X819843D01*
G01X822068D02*
Y398865D01*
X821568Y398365D01*
G01Y396365D02*
X822568D01*
G01X824376Y397407D02*
X824668Y397698D01*
X824918Y397865D01*
X825251Y397948D01*
X825543Y397865D01*
X825751Y397698D01*
X825918Y397448D01*
X825960Y397157D01*
X825918Y396907D01*
X825751Y396657D01*
X825501Y396448D01*
X825210Y396365D01*
X824876Y396448D01*
X824585Y396698D01*
X824418Y397073D01*
X824376Y397490D01*
X824460Y398032D01*
X824585Y398323D01*
X824793Y398615D01*
X825085Y398823D01*
X825376Y398865D01*
X825668Y398782D01*
X825876Y398573D01*
G01X857114Y397249D02*
X852114D01*
Y392249D01*
G01X805855Y469331D02*
X803355D01*
Y470372D01*
X803480Y470706D01*
X803647Y470914D01*
X803980Y470997D01*
X804313Y470914D01*
X804522Y470664D01*
X804647Y470372D01*
Y469331D01*
G01Y470372D02*
X805855Y470997D01*
G01Y473264D02*
X805813Y473556D01*
X805688Y473889D01*
X805480Y474097D01*
X805188Y474181D01*
X804897Y474097D01*
X804647Y473847D01*
X804522Y473472D01*
Y473056D01*
X804438Y472806D01*
X804230Y472597D01*
X803938Y472514D01*
X803647Y472639D01*
X803438Y472931D01*
X803355Y473264D01*
X803438Y473597D01*
X803647Y473889D01*
X803938Y474014D01*
X804230Y473931D01*
X804438Y473722D01*
X804522Y473472D01*
Y473056D01*
X804647Y472681D01*
X804897Y472431D01*
X805188Y472347D01*
X805480Y472431D01*
X805688Y472639D01*
X805813Y472972D01*
X805855Y473264D01*
G01Y476364D02*
X803355D01*
X803855Y475864D01*
G01X805855D02*
Y476864D01*
G01Y479464D02*
X803355D01*
X803855Y478964D01*
G01X805855D02*
Y479964D01*
G01X813099Y479179D02*
X809099D01*
Y471779D01*
G01X820185Y469218D02*
X817685D01*
Y470259D01*
X817810Y470593D01*
X817977Y470801D01*
X818310Y470884D01*
X818643Y470801D01*
X818852Y470551D01*
X818977Y470259D01*
Y469218D01*
G01Y470259D02*
X820185Y470884D01*
G01Y473151D02*
X820143Y473443D01*
X820018Y473776D01*
X819810Y473984D01*
X819518Y474068D01*
X819227Y473984D01*
X818977Y473734D01*
X818852Y473359D01*
Y472943D01*
X818768Y472693D01*
X818560Y472484D01*
X818268Y472401D01*
X817977Y472526D01*
X817768Y472818D01*
X817685Y473151D01*
X817768Y473484D01*
X817977Y473776D01*
X818268Y473901D01*
X818560Y473818D01*
X818768Y473609D01*
X818852Y473359D01*
Y472943D01*
X818977Y472568D01*
X819227Y472318D01*
X819518Y472234D01*
X819810Y472318D01*
X820018Y472526D01*
X820143Y472859D01*
X820185Y473151D01*
G01Y476251D02*
X817685D01*
X818185Y475751D01*
G01X820185D02*
Y476751D01*
G01X818102Y478559D02*
X817852Y478809D01*
X817727Y479101D01*
X817685Y479434D01*
X817768Y479851D01*
X817977Y480143D01*
X818227Y480226D01*
X818477Y480184D01*
X818685Y480018D01*
X819102Y479184D01*
X819393Y478809D01*
X819810Y478559D01*
X820185Y478476D01*
Y480226D01*
G01X821728Y471600D02*
X825728D01*
Y479000D01*
G01X804490Y443626D02*
X801990D01*
Y444667D01*
X802115Y445001D01*
X802282Y445209D01*
X802615Y445292D01*
X802948Y445209D01*
X803157Y444959D01*
X803282Y444667D01*
Y443626D01*
G01Y444667D02*
X804490Y445292D01*
G01X804115Y446642D02*
X804323Y446892D01*
X804448Y447184D01*
X804490Y447559D01*
X804407Y447934D01*
X804240Y448226D01*
X803948Y448434D01*
X803615Y448476D01*
X803282Y448392D01*
X803073Y448184D01*
X802907Y447892D01*
X802865Y447601D01*
X802907Y447309D01*
X803073Y446934D01*
X801990Y447059D01*
Y448184D01*
G01X804490Y451159D02*
X801990D01*
X803782Y449617D01*
Y451701D01*
G01X804490Y454259D02*
X801990D01*
X803782Y452717D01*
Y454801D01*
G01X802000Y432400D02*
X806000D01*
Y439800D01*
G01X796490Y443626D02*
X793990D01*
Y444667D01*
X794115Y445001D01*
X794282Y445209D01*
X794615Y445292D01*
X794948Y445209D01*
X795157Y444959D01*
X795282Y444667D01*
Y443626D01*
G01Y444667D02*
X796490Y445292D01*
G01X796115Y446642D02*
X796323Y446892D01*
X796448Y447184D01*
X796490Y447559D01*
X796407Y447934D01*
X796240Y448226D01*
X795948Y448434D01*
X795615Y448476D01*
X795282Y448392D01*
X795073Y448184D01*
X794907Y447892D01*
X794865Y447601D01*
X794907Y447309D01*
X795073Y446934D01*
X793990Y447059D01*
Y448184D01*
G01X796490Y451159D02*
X793990D01*
X795782Y449617D01*
Y451701D01*
G01X796490Y453759D02*
X796448Y454051D01*
X796323Y454384D01*
X796115Y454592D01*
X795823Y454676D01*
X795532Y454592D01*
X795282Y454342D01*
X795157Y453967D01*
Y453551D01*
X795073Y453301D01*
X794865Y453092D01*
X794573Y453009D01*
X794282Y453134D01*
X794073Y453426D01*
X793990Y453759D01*
X794073Y454092D01*
X794282Y454384D01*
X794573Y454509D01*
X794865Y454426D01*
X795073Y454217D01*
X795157Y453967D01*
Y453551D01*
X795282Y453176D01*
X795532Y452926D01*
X795823Y452842D01*
X796115Y452926D01*
X796323Y453134D01*
X796448Y453467D01*
X796490Y453759D01*
G01X796900Y439800D02*
X792900D01*
Y432400D01*
G01X808490Y443626D02*
X805990D01*
Y444667D01*
X806115Y445001D01*
X806282Y445209D01*
X806615Y445292D01*
X806948Y445209D01*
X807157Y444959D01*
X807282Y444667D01*
Y443626D01*
G01Y444667D02*
X808490Y445292D01*
G01X808115Y446642D02*
X808323Y446892D01*
X808448Y447184D01*
X808490Y447559D01*
X808407Y447934D01*
X808240Y448226D01*
X807948Y448434D01*
X807615Y448476D01*
X807282Y448392D01*
X807073Y448184D01*
X806907Y447892D01*
X806865Y447601D01*
X806907Y447309D01*
X807073Y446934D01*
X805990Y447059D01*
Y448184D01*
G01X808490Y451159D02*
X805990D01*
X807782Y449617D01*
Y451701D01*
G01X808198Y453051D02*
X808407Y453342D01*
X808490Y453676D01*
X808407Y454009D01*
X808157Y454301D01*
X807782Y454509D01*
X807407Y454592D01*
X806948D01*
X806573Y454509D01*
X806240Y454301D01*
X806073Y454051D01*
X805990Y453759D01*
X806073Y453426D01*
X806240Y453176D01*
X806490Y453009D01*
X806823Y452926D01*
X807115Y453009D01*
X807407Y453217D01*
X807573Y453467D01*
X807615Y453759D01*
X807532Y454092D01*
X807323Y454342D01*
X806948Y454592D01*
G01X810100Y439800D02*
X806100D01*
Y432400D01*
G01X814700Y427800D02*
Y423800D01*
X822100D01*
G01Y428000D02*
Y432000D01*
X814700D01*
G01X800490Y443626D02*
X797990D01*
Y444667D01*
X798115Y445001D01*
X798282Y445209D01*
X798615Y445292D01*
X798948Y445209D01*
X799157Y444959D01*
X799282Y444667D01*
Y443626D01*
G01Y444667D02*
X800490Y445292D01*
G01X800115Y446642D02*
X800323Y446892D01*
X800448Y447184D01*
X800490Y447559D01*
X800407Y447934D01*
X800240Y448226D01*
X799948Y448434D01*
X799615Y448476D01*
X799282Y448392D01*
X799073Y448184D01*
X798907Y447892D01*
X798865Y447601D01*
X798907Y447309D01*
X799073Y446934D01*
X797990Y447059D01*
Y448184D01*
G01X800115Y449742D02*
X800323Y449992D01*
X800448Y450284D01*
X800490Y450659D01*
X800407Y451034D01*
X800240Y451326D01*
X799948Y451534D01*
X799615Y451576D01*
X799282Y451492D01*
X799073Y451284D01*
X798907Y450992D01*
X798865Y450701D01*
X798907Y450409D01*
X799073Y450034D01*
X797990Y450159D01*
Y451284D01*
G01X800115Y452842D02*
X800323Y453092D01*
X800448Y453384D01*
X800490Y453759D01*
X800407Y454134D01*
X800240Y454426D01*
X799948Y454634D01*
X799615Y454676D01*
X799282Y454592D01*
X799073Y454384D01*
X798907Y454092D01*
X798865Y453801D01*
X798907Y453509D01*
X799073Y453134D01*
X797990Y453259D01*
Y454384D01*
G01X797000Y432400D02*
X801000D01*
Y439800D01*
G01X829654Y474097D02*
Y471597D01*
G01X828696Y474097D02*
X830612D01*
G01X831921Y471597D02*
Y474097D01*
X832921D01*
X833254Y473972D01*
X833504Y473680D01*
X833587Y473347D01*
X833504Y473014D01*
X833296Y472764D01*
X832921Y472639D01*
X831921D01*
G01X835062Y473680D02*
X835312Y473930D01*
X835604Y474055D01*
X835937Y474097D01*
X836354Y474014D01*
X836646Y473805D01*
X836729Y473555D01*
X836687Y473305D01*
X836521Y473097D01*
X835687Y472680D01*
X835312Y472389D01*
X835062Y471972D01*
X834979Y471597D01*
X836729D01*
G01X838954D02*
Y474097D01*
X838454Y473597D01*
G01Y471597D02*
X839454D01*
G01X841262Y473680D02*
X841512Y473930D01*
X841804Y474055D01*
X842137Y474097D01*
X842554Y474014D01*
X842846Y473805D01*
X842929Y473555D01*
X842887Y473305D01*
X842721Y473097D01*
X841887Y472680D01*
X841512Y472389D01*
X841262Y471972D01*
X841179Y471597D01*
X842929D01*
G01X836581Y478418D02*
Y475918D01*
G01X835623Y478418D02*
X837539D01*
G01X838848Y475918D02*
Y478418D01*
X839848D01*
X840181Y478293D01*
X840431Y478001D01*
X840514Y477668D01*
X840431Y477335D01*
X840223Y477085D01*
X839848Y476960D01*
X838848D01*
G01X841989Y478001D02*
X842239Y478251D01*
X842531Y478376D01*
X842864Y478418D01*
X843281Y478335D01*
X843573Y478126D01*
X843656Y477876D01*
X843614Y477626D01*
X843448Y477418D01*
X842614Y477001D01*
X842239Y476710D01*
X841989Y476293D01*
X841906Y475918D01*
X843656D01*
G01X845881D02*
Y478418D01*
X845381Y477918D01*
G01Y475918D02*
X846381D01*
G01X848981D02*
Y478418D01*
X848481Y477918D01*
G01Y475918D02*
X849481D01*
G01X868778Y65481D02*
X868653Y65231D01*
X868570Y64939D01*
Y64606D01*
X868695Y64231D01*
X868903Y63939D01*
X869153Y63731D01*
X869570Y63564D01*
X869945Y63522D01*
X870320Y63606D01*
X870570Y63731D01*
X870820Y63981D01*
X870987Y64272D01*
X871070Y64564D01*
Y64856D01*
X870987Y65147D01*
X870862Y65397D01*
X870695Y65606D01*
G01X871070Y67664D02*
X868570D01*
X869070Y67164D01*
G01X871070D02*
Y68164D01*
G01X870028Y69972D02*
X869737Y70264D01*
X869570Y70514D01*
X869487Y70847D01*
X869570Y71139D01*
X869737Y71347D01*
X869987Y71514D01*
X870278Y71556D01*
X870528Y71514D01*
X870778Y71347D01*
X870987Y71097D01*
X871070Y70806D01*
X870987Y70472D01*
X870737Y70181D01*
X870362Y70014D01*
X869945Y69972D01*
X869403Y70056D01*
X869112Y70181D01*
X868820Y70389D01*
X868612Y70681D01*
X868570Y70972D01*
X868653Y71264D01*
X868862Y71472D01*
G01X870028Y73072D02*
X869737Y73364D01*
X869570Y73614D01*
X869487Y73947D01*
X869570Y74239D01*
X869737Y74447D01*
X869987Y74614D01*
X870278Y74656D01*
X870528Y74614D01*
X870778Y74447D01*
X870987Y74197D01*
X871070Y73906D01*
X870987Y73572D01*
X870737Y73281D01*
X870362Y73114D01*
X869945Y73072D01*
X869403Y73156D01*
X869112Y73281D01*
X868820Y73489D01*
X868612Y73781D01*
X868570Y74072D01*
X868653Y74364D01*
X868862Y74572D01*
G01X864778Y65481D02*
X864653Y65231D01*
X864570Y64939D01*
Y64606D01*
X864695Y64231D01*
X864903Y63939D01*
X865153Y63731D01*
X865570Y63564D01*
X865945Y63522D01*
X866320Y63606D01*
X866570Y63731D01*
X866820Y63981D01*
X866987Y64272D01*
X867070Y64564D01*
Y64856D01*
X866987Y65147D01*
X866862Y65397D01*
X866695Y65606D01*
G01X867070Y67664D02*
X864570D01*
X865070Y67164D01*
G01X867070D02*
Y68164D01*
G01X866028Y69972D02*
X865737Y70264D01*
X865570Y70514D01*
X865487Y70847D01*
X865570Y71139D01*
X865737Y71347D01*
X865987Y71514D01*
X866278Y71556D01*
X866528Y71514D01*
X866778Y71347D01*
X866987Y71097D01*
X867070Y70806D01*
X866987Y70472D01*
X866737Y70181D01*
X866362Y70014D01*
X865945Y69972D01*
X865403Y70056D01*
X865112Y70181D01*
X864820Y70389D01*
X864612Y70681D01*
X864570Y70972D01*
X864653Y71264D01*
X864862Y71472D01*
G01X866695Y72947D02*
X866903Y73197D01*
X867028Y73489D01*
X867070Y73864D01*
X866987Y74239D01*
X866820Y74531D01*
X866528Y74739D01*
X866195Y74781D01*
X865862Y74697D01*
X865653Y74489D01*
X865487Y74197D01*
X865445Y73906D01*
X865487Y73614D01*
X865653Y73239D01*
X864570Y73364D01*
Y74489D01*
G01X860778Y65481D02*
X860653Y65231D01*
X860570Y64939D01*
Y64606D01*
X860695Y64231D01*
X860903Y63939D01*
X861153Y63731D01*
X861570Y63564D01*
X861945Y63522D01*
X862320Y63606D01*
X862570Y63731D01*
X862820Y63981D01*
X862987Y64272D01*
X863070Y64564D01*
Y64856D01*
X862987Y65147D01*
X862862Y65397D01*
X862695Y65606D01*
G01X863070Y67664D02*
X860570D01*
X861070Y67164D01*
G01X863070D02*
Y68164D01*
G01X862028Y69972D02*
X861737Y70264D01*
X861570Y70514D01*
X861487Y70847D01*
X861570Y71139D01*
X861737Y71347D01*
X861987Y71514D01*
X862278Y71556D01*
X862528Y71514D01*
X862778Y71347D01*
X862987Y71097D01*
X863070Y70806D01*
X862987Y70472D01*
X862737Y70181D01*
X862362Y70014D01*
X861945Y69972D01*
X861403Y70056D01*
X861112Y70181D01*
X860820Y70389D01*
X860612Y70681D01*
X860570Y70972D01*
X860653Y71264D01*
X860862Y71472D01*
G01X863070Y74364D02*
X860570D01*
X862362Y72822D01*
Y74906D01*
G01X894372Y120138D02*
X883172D01*
G01X894372Y102138D02*
Y120138D01*
G01X883172Y102138D02*
X894372D01*
G01X861922Y121714D02*
X903322D01*
Y171914D01*
X861922D01*
Y121714D01*
G01X873819Y67914D02*
Y68747D01*
X874569D01*
X874819Y68497D01*
X874986Y68206D01*
X875069Y67789D01*
X874986Y67372D01*
X874819Y67081D01*
X874569Y66831D01*
X874277Y66664D01*
X873944Y66581D01*
X873652D01*
X873402Y66664D01*
X873111Y66831D01*
X872861Y67081D01*
X872694Y67331D01*
X872569Y67664D01*
Y67956D01*
X872652Y68289D01*
X872819Y68539D01*
G01X875069Y70764D02*
X872569D01*
X873069Y70264D01*
G01X875069D02*
Y71264D01*
G01X894372Y99638D02*
X883172D01*
G01X894372Y81638D02*
Y99638D01*
G01X883172Y81638D02*
X894372D01*
G01X899973Y180609D02*
X899848Y180359D01*
X899765Y180067D01*
Y179734D01*
X899890Y179359D01*
X900098Y179067D01*
X900348Y178859D01*
X900765Y178692D01*
X901140Y178650D01*
X901515Y178734D01*
X901765Y178859D01*
X902015Y179109D01*
X902182Y179400D01*
X902265Y179692D01*
Y179984D01*
X902182Y180275D01*
X902057Y180525D01*
X901890Y180734D01*
G01X902265Y182792D02*
X899765D01*
X900265Y182292D01*
G01X902265D02*
Y183292D01*
G01X901890Y184975D02*
X902098Y185225D01*
X902223Y185517D01*
X902265Y185892D01*
X902182Y186267D01*
X902015Y186559D01*
X901723Y186767D01*
X901390Y186809D01*
X901057Y186725D01*
X900848Y186517D01*
X900682Y186225D01*
X900640Y185934D01*
X900682Y185642D01*
X900848Y185267D01*
X899765Y185392D01*
Y186517D01*
G01X901973Y188284D02*
X902182Y188575D01*
X902265Y188909D01*
X902182Y189242D01*
X901932Y189534D01*
X901557Y189742D01*
X901182Y189825D01*
X900723D01*
X900348Y189742D01*
X900015Y189534D01*
X899848Y189284D01*
X899765Y188992D01*
X899848Y188659D01*
X900015Y188409D01*
X900265Y188242D01*
X900598Y188159D01*
X900890Y188242D01*
X901182Y188450D01*
X901348Y188700D01*
X901390Y188992D01*
X901307Y189325D01*
X901098Y189575D01*
X900723Y189825D01*
G01X904942Y198441D02*
X904692Y198566D01*
X904400Y198649D01*
X904067D01*
X903692Y198524D01*
X903400Y198316D01*
X903192Y198066D01*
X903025Y197649D01*
X902983Y197274D01*
X903067Y196899D01*
X903192Y196649D01*
X903442Y196399D01*
X903733Y196232D01*
X904025Y196149D01*
X904317D01*
X904608Y196232D01*
X904858Y196357D01*
X905067Y196524D01*
G01X907125Y196149D02*
Y198649D01*
X906625Y198149D01*
G01Y196149D02*
X907625D01*
G01X909308Y196524D02*
X909558Y196316D01*
X909850Y196191D01*
X910225Y196149D01*
X910600Y196232D01*
X910892Y196399D01*
X911100Y196691D01*
X911142Y197024D01*
X911058Y197357D01*
X910850Y197566D01*
X910558Y197732D01*
X910267Y197774D01*
X909975Y197732D01*
X909600Y197566D01*
X909725Y198649D01*
X910850D01*
G01X912533Y198232D02*
X912783Y198482D01*
X913075Y198607D01*
X913408Y198649D01*
X913825Y198566D01*
X914117Y198357D01*
X914200Y198107D01*
X914158Y197857D01*
X913992Y197649D01*
X913158Y197232D01*
X912783Y196941D01*
X912533Y196524D01*
X912450Y196149D01*
X914200D01*
G01X903192Y192149D02*
Y194649D01*
X904233D01*
X904567Y194524D01*
X904775Y194357D01*
X904858Y194024D01*
X904775Y193691D01*
X904525Y193482D01*
X904233Y193357D01*
X903192D01*
G01X904233D02*
X904858Y192149D01*
G01X907625D02*
Y194649D01*
X906083Y192857D01*
X908167D01*
G01X909433Y193191D02*
X909725Y193482D01*
X909975Y193649D01*
X910308Y193732D01*
X910600Y193649D01*
X910808Y193482D01*
X910975Y193232D01*
X911017Y192941D01*
X910975Y192691D01*
X910808Y192441D01*
X910558Y192232D01*
X910267Y192149D01*
X909933Y192232D01*
X909642Y192482D01*
X909475Y192857D01*
X909433Y193274D01*
X909517Y193816D01*
X909642Y194107D01*
X909850Y194399D01*
X910142Y194607D01*
X910433Y194649D01*
X910725Y194566D01*
X910933Y194357D01*
G01X912617Y192441D02*
X912908Y192232D01*
X913242Y192149D01*
X913575Y192232D01*
X913867Y192482D01*
X914075Y192857D01*
X914158Y193232D01*
Y193691D01*
X914075Y194066D01*
X913867Y194399D01*
X913617Y194566D01*
X913325Y194649D01*
X912992Y194566D01*
X912742Y194399D01*
X912575Y194149D01*
X912492Y193816D01*
X912575Y193524D01*
X912783Y193232D01*
X913033Y193066D01*
X913325Y193024D01*
X913658Y193107D01*
X913908Y193316D01*
X914158Y193691D01*
G01X897684Y189300D02*
X892484D01*
G01X897684Y196300D02*
X889884D01*
G01X897684Y189300D02*
Y196300D01*
G01X884284Y189300D02*
X892984D01*
G01X884284Y196300D02*
Y189300D01*
G01X890684Y196300D02*
X884284D01*
G01X887100Y180167D02*
X884600D01*
Y181167D01*
X884725Y181500D01*
X885017Y181750D01*
X885350Y181833D01*
X885683Y181750D01*
X885933Y181542D01*
X886058Y181167D01*
Y180167D01*
G01X884600Y183183D02*
X886392D01*
X886767Y183350D01*
X887017Y183683D01*
X887100Y184100D01*
X887017Y184517D01*
X886767Y184850D01*
X886392Y185017D01*
X884600D01*
G01X887100Y187200D02*
X884600D01*
X885100Y186700D01*
G01X887100D02*
Y187700D01*
G01X883422Y200115D02*
Y205115D01*
X878422D01*
G01Y177415D02*
X883422D01*
Y182415D01*
G01X863716Y204108D02*
Y207108D01*
G01X873559Y204108D02*
Y206108D01*
G01X877496Y178422D02*
Y175422D01*
G01X867653Y178422D02*
Y176422D01*
G01X907545Y145856D02*
X910045D01*
Y147522D01*
G01Y149706D02*
X909503Y149789D01*
X909045Y149914D01*
X908628Y150081D01*
X908170Y150289D01*
X907545Y150622D01*
Y148956D01*
G01X900665Y223716D02*
X900415Y223841D01*
X900123Y223924D01*
X899790D01*
X899415Y223799D01*
X899123Y223591D01*
X898915Y223341D01*
X898748Y222924D01*
X898706Y222549D01*
X898790Y222174D01*
X898915Y221924D01*
X899165Y221674D01*
X899456Y221507D01*
X899748Y221424D01*
X900040D01*
X900331Y221507D01*
X900581Y221632D01*
X900790Y221799D01*
G01X902848Y221424D02*
Y223924D01*
X902348Y223424D01*
G01Y221424D02*
X903348D01*
G01X905031Y221799D02*
X905281Y221591D01*
X905573Y221466D01*
X905948Y221424D01*
X906323Y221507D01*
X906615Y221674D01*
X906823Y221966D01*
X906865Y222299D01*
X906781Y222632D01*
X906573Y222841D01*
X906281Y223007D01*
X905990Y223049D01*
X905698Y223007D01*
X905323Y222841D01*
X905448Y223924D01*
X906573D01*
G01X909048Y221424D02*
Y223924D01*
X908548Y223424D01*
G01Y221424D02*
X909548D01*
G01X900665Y227716D02*
X900415Y227841D01*
X900123Y227924D01*
X899790D01*
X899415Y227799D01*
X899123Y227591D01*
X898915Y227341D01*
X898748Y226924D01*
X898706Y226549D01*
X898790Y226174D01*
X898915Y225924D01*
X899165Y225674D01*
X899456Y225507D01*
X899748Y225424D01*
X900040D01*
X900331Y225507D01*
X900581Y225632D01*
X900790Y225799D01*
G01X902848Y225424D02*
Y227924D01*
X902348Y227424D01*
G01Y225424D02*
X903348D01*
G01X905031Y225799D02*
X905281Y225591D01*
X905573Y225466D01*
X905948Y225424D01*
X906323Y225507D01*
X906615Y225674D01*
X906823Y225966D01*
X906865Y226299D01*
X906781Y226632D01*
X906573Y226841D01*
X906281Y227007D01*
X905990Y227049D01*
X905698Y227007D01*
X905323Y226841D01*
X905448Y227924D01*
X906573D01*
G01X908131Y225799D02*
X908381Y225591D01*
X908673Y225466D01*
X909048Y225424D01*
X909423Y225507D01*
X909715Y225674D01*
X909923Y225966D01*
X909965Y226299D01*
X909881Y226632D01*
X909673Y226841D01*
X909381Y227007D01*
X909090Y227049D01*
X908798Y227007D01*
X908423Y226841D01*
X908548Y227924D01*
X909673D01*
G01X869030Y213262D02*
Y217262D01*
X861630D01*
G01X866501Y274208D02*
X877701D01*
G01X866501Y292208D02*
Y274208D01*
G01X904901D02*
X893701D01*
G01X904901Y292208D02*
Y274208D01*
G01X908568Y280874D02*
X908443Y280624D01*
X908360Y280332D01*
Y279999D01*
X908485Y279624D01*
X908693Y279332D01*
X908943Y279124D01*
X909360Y278957D01*
X909735Y278915D01*
X910110Y278999D01*
X910360Y279124D01*
X910610Y279374D01*
X910777Y279665D01*
X910860Y279957D01*
Y280249D01*
X910777Y280540D01*
X910652Y280790D01*
X910485Y280999D01*
G01X909818Y282265D02*
X909527Y282557D01*
X909360Y282807D01*
X909277Y283140D01*
X909360Y283432D01*
X909527Y283640D01*
X909777Y283807D01*
X910068Y283849D01*
X910318Y283807D01*
X910568Y283640D01*
X910777Y283390D01*
X910860Y283099D01*
X910777Y282765D01*
X910527Y282474D01*
X910152Y282307D01*
X909735Y282265D01*
X909193Y282349D01*
X908902Y282474D01*
X908610Y282682D01*
X908402Y282974D01*
X908360Y283265D01*
X908443Y283557D01*
X908652Y283765D01*
G01X910485Y285240D02*
X910693Y285490D01*
X910818Y285782D01*
X910860Y286157D01*
X910777Y286532D01*
X910610Y286824D01*
X910318Y287032D01*
X909985Y287074D01*
X909652Y286990D01*
X909443Y286782D01*
X909277Y286490D01*
X909235Y286199D01*
X909277Y285907D01*
X909443Y285532D01*
X908360Y285657D01*
Y286782D01*
G01X910860Y289257D02*
X910818Y289549D01*
X910693Y289882D01*
X910485Y290090D01*
X910193Y290174D01*
X909902Y290090D01*
X909652Y289840D01*
X909527Y289465D01*
Y289049D01*
X909443Y288799D01*
X909235Y288590D01*
X908943Y288507D01*
X908652Y288632D01*
X908443Y288924D01*
X908360Y289257D01*
X908443Y289590D01*
X908652Y289882D01*
X908943Y290007D01*
X909235Y289924D01*
X909443Y289715D01*
X909527Y289465D01*
Y289049D01*
X909652Y288674D01*
X909902Y288424D01*
X910193Y288340D01*
X910485Y288424D01*
X910693Y288632D01*
X910818Y288965D01*
X910860Y289257D01*
G01X877701Y292208D02*
X866501D01*
G01X893701D02*
X904901D01*
G01X908293Y299416D02*
X908168Y299166D01*
X908085Y298874D01*
Y298541D01*
X908210Y298166D01*
X908418Y297874D01*
X908668Y297666D01*
X909085Y297499D01*
X909460Y297457D01*
X909835Y297541D01*
X910085Y297666D01*
X910335Y297916D01*
X910502Y298207D01*
X910585Y298499D01*
Y298791D01*
X910502Y299082D01*
X910377Y299332D01*
X910210Y299541D01*
G01X909543Y300807D02*
X909252Y301099D01*
X909085Y301349D01*
X909002Y301682D01*
X909085Y301974D01*
X909252Y302182D01*
X909502Y302349D01*
X909793Y302391D01*
X910043Y302349D01*
X910293Y302182D01*
X910502Y301932D01*
X910585Y301641D01*
X910502Y301307D01*
X910252Y301016D01*
X909877Y300849D01*
X909460Y300807D01*
X908918Y300891D01*
X908627Y301016D01*
X908335Y301224D01*
X908127Y301516D01*
X908085Y301807D01*
X908168Y302099D01*
X908377Y302307D01*
G01X910210Y303782D02*
X910418Y304032D01*
X910543Y304324D01*
X910585Y304699D01*
X910502Y305074D01*
X910335Y305366D01*
X910043Y305574D01*
X909710Y305616D01*
X909377Y305532D01*
X909168Y305324D01*
X909002Y305032D01*
X908960Y304741D01*
X909002Y304449D01*
X909168Y304074D01*
X908085Y304199D01*
Y305324D01*
G01X910585Y307716D02*
X910043Y307799D01*
X909585Y307924D01*
X909168Y308091D01*
X908710Y308299D01*
X908085Y308632D01*
Y306966D01*
G01X866501Y294708D02*
X877701D01*
G01X866501Y312708D02*
Y294708D01*
G01X877701Y312708D02*
X866501D01*
G01X904901Y294708D02*
X893701D01*
G01X904901Y312708D02*
Y294708D01*
G01X893701Y312708D02*
X904901D01*
G01X900599Y336382D02*
X903099D01*
Y338048D01*
G01X902599Y339398D02*
X902891Y339648D01*
X903057Y339982D01*
X903099Y340357D01*
X903057Y340690D01*
X902849Y341023D01*
X902599Y341232D01*
X902349Y341273D01*
X902057Y341190D01*
X901849Y340898D01*
X901766Y340607D01*
Y340232D01*
G01Y340607D02*
X901641Y340857D01*
X901432Y341065D01*
X901182Y341148D01*
X900932Y341065D01*
X900724Y340857D01*
X900599Y340482D01*
X900641Y340107D01*
X900807Y339732D01*
G01X903099Y343415D02*
X900599D01*
X901099Y342915D01*
G01X903099D02*
Y343915D01*
G01X905951Y362843D02*
X905826Y362593D01*
X905743Y362301D01*
Y361968D01*
X905868Y361593D01*
X906076Y361301D01*
X906326Y361093D01*
X906743Y360926D01*
X907118Y360884D01*
X907493Y360968D01*
X907743Y361093D01*
X907993Y361343D01*
X908160Y361634D01*
X908243Y361926D01*
Y362218D01*
X908160Y362509D01*
X908035Y362759D01*
X907868Y362968D01*
G01X907201Y364234D02*
X906910Y364526D01*
X906743Y364776D01*
X906660Y365109D01*
X906743Y365401D01*
X906910Y365609D01*
X907160Y365776D01*
X907451Y365818D01*
X907701Y365776D01*
X907951Y365609D01*
X908160Y365359D01*
X908243Y365068D01*
X908160Y364734D01*
X907910Y364443D01*
X907535Y364276D01*
X907118Y364234D01*
X906576Y364318D01*
X906285Y364443D01*
X905993Y364651D01*
X905785Y364943D01*
X905743Y365234D01*
X905826Y365526D01*
X906035Y365734D01*
G01X908243Y368626D02*
X905743D01*
X907535Y367084D01*
Y369168D01*
G01X907201Y370434D02*
X906910Y370726D01*
X906743Y370976D01*
X906660Y371309D01*
X906743Y371601D01*
X906910Y371809D01*
X907160Y371976D01*
X907451Y372018D01*
X907701Y371976D01*
X907951Y371809D01*
X908160Y371559D01*
X908243Y371268D01*
X908160Y370934D01*
X907910Y370643D01*
X907535Y370476D01*
X907118Y370434D01*
X906576Y370518D01*
X906285Y370643D01*
X905993Y370851D01*
X905785Y371143D01*
X905743Y371434D01*
X905826Y371726D01*
X906035Y371934D01*
G01X884414Y415952D02*
X884289Y415702D01*
X884206Y415410D01*
Y415077D01*
X884331Y414702D01*
X884539Y414410D01*
X884789Y414202D01*
X885206Y414035D01*
X885581Y413993D01*
X885956Y414077D01*
X886206Y414202D01*
X886456Y414452D01*
X886623Y414743D01*
X886706Y415035D01*
Y415327D01*
X886623Y415618D01*
X886498Y415868D01*
X886331Y416077D01*
G01X885664Y417343D02*
X885373Y417635D01*
X885206Y417885D01*
X885123Y418218D01*
X885206Y418510D01*
X885373Y418718D01*
X885623Y418885D01*
X885914Y418927D01*
X886164Y418885D01*
X886414Y418718D01*
X886623Y418468D01*
X886706Y418177D01*
X886623Y417843D01*
X886373Y417552D01*
X885998Y417385D01*
X885581Y417343D01*
X885039Y417427D01*
X884748Y417552D01*
X884456Y417760D01*
X884248Y418052D01*
X884206Y418343D01*
X884289Y418635D01*
X884498Y418843D01*
G01X886331Y420318D02*
X886539Y420568D01*
X886664Y420860D01*
X886706Y421235D01*
X886623Y421610D01*
X886456Y421902D01*
X886164Y422110D01*
X885831Y422152D01*
X885498Y422068D01*
X885289Y421860D01*
X885123Y421568D01*
X885081Y421277D01*
X885123Y420985D01*
X885289Y420610D01*
X884206Y420735D01*
Y421860D01*
G01X886414Y423627D02*
X886623Y423918D01*
X886706Y424252D01*
X886623Y424585D01*
X886373Y424877D01*
X885998Y425085D01*
X885623Y425168D01*
X885164D01*
X884789Y425085D01*
X884456Y424877D01*
X884289Y424627D01*
X884206Y424335D01*
X884289Y424002D01*
X884456Y423752D01*
X884706Y423585D01*
X885039Y423502D01*
X885331Y423585D01*
X885623Y423793D01*
X885789Y424043D01*
X885831Y424335D01*
X885748Y424668D01*
X885539Y424918D01*
X885164Y425168D01*
G01X896414Y415952D02*
X896289Y415702D01*
X896206Y415410D01*
Y415077D01*
X896331Y414702D01*
X896539Y414410D01*
X896789Y414202D01*
X897206Y414035D01*
X897581Y413993D01*
X897956Y414077D01*
X898206Y414202D01*
X898456Y414452D01*
X898623Y414743D01*
X898706Y415035D01*
Y415327D01*
X898623Y415618D01*
X898498Y415868D01*
X898331Y416077D01*
G01X897664Y417343D02*
X897373Y417635D01*
X897206Y417885D01*
X897123Y418218D01*
X897206Y418510D01*
X897373Y418718D01*
X897623Y418885D01*
X897914Y418927D01*
X898164Y418885D01*
X898414Y418718D01*
X898623Y418468D01*
X898706Y418177D01*
X898623Y417843D01*
X898373Y417552D01*
X897998Y417385D01*
X897581Y417343D01*
X897039Y417427D01*
X896748Y417552D01*
X896456Y417760D01*
X896248Y418052D01*
X896206Y418343D01*
X896289Y418635D01*
X896498Y418843D01*
G01X898206Y420318D02*
X898498Y420568D01*
X898664Y420902D01*
X898706Y421277D01*
X898664Y421610D01*
X898456Y421943D01*
X898206Y422152D01*
X897956Y422193D01*
X897664Y422110D01*
X897456Y421818D01*
X897373Y421527D01*
Y421152D01*
G01Y421527D02*
X897248Y421777D01*
X897039Y421985D01*
X896789Y422068D01*
X896539Y421985D01*
X896331Y421777D01*
X896206Y421402D01*
X896248Y421027D01*
X896414Y420652D01*
G01X897664Y423543D02*
X897373Y423835D01*
X897206Y424085D01*
X897123Y424418D01*
X897206Y424710D01*
X897373Y424918D01*
X897623Y425085D01*
X897914Y425127D01*
X898164Y425085D01*
X898414Y424918D01*
X898623Y424668D01*
X898706Y424377D01*
X898623Y424043D01*
X898373Y423752D01*
X897998Y423585D01*
X897581Y423543D01*
X897039Y423627D01*
X896748Y423752D01*
X896456Y423960D01*
X896248Y424252D01*
X896206Y424543D01*
X896289Y424835D01*
X896498Y425043D01*
G01X892414Y415952D02*
X892289Y415702D01*
X892206Y415410D01*
Y415077D01*
X892331Y414702D01*
X892539Y414410D01*
X892789Y414202D01*
X893206Y414035D01*
X893581Y413993D01*
X893956Y414077D01*
X894206Y414202D01*
X894456Y414452D01*
X894623Y414743D01*
X894706Y415035D01*
Y415327D01*
X894623Y415618D01*
X894498Y415868D01*
X894331Y416077D01*
G01X893664Y417343D02*
X893373Y417635D01*
X893206Y417885D01*
X893123Y418218D01*
X893206Y418510D01*
X893373Y418718D01*
X893623Y418885D01*
X893914Y418927D01*
X894164Y418885D01*
X894414Y418718D01*
X894623Y418468D01*
X894706Y418177D01*
X894623Y417843D01*
X894373Y417552D01*
X893998Y417385D01*
X893581Y417343D01*
X893039Y417427D01*
X892748Y417552D01*
X892456Y417760D01*
X892248Y418052D01*
X892206Y418343D01*
X892289Y418635D01*
X892498Y418843D01*
G01X894706Y421152D02*
X894164Y421235D01*
X893706Y421360D01*
X893289Y421527D01*
X892831Y421735D01*
X892206Y422068D01*
Y420402D01*
G01X892623Y423543D02*
X892373Y423793D01*
X892248Y424085D01*
X892206Y424418D01*
X892289Y424835D01*
X892498Y425127D01*
X892748Y425210D01*
X892998Y425168D01*
X893206Y425002D01*
X893623Y424168D01*
X893914Y423793D01*
X894331Y423543D01*
X894706Y423460D01*
Y425210D01*
G01X888414Y415952D02*
X888289Y415702D01*
X888206Y415410D01*
Y415077D01*
X888331Y414702D01*
X888539Y414410D01*
X888789Y414202D01*
X889206Y414035D01*
X889581Y413993D01*
X889956Y414077D01*
X890206Y414202D01*
X890456Y414452D01*
X890623Y414743D01*
X890706Y415035D01*
Y415327D01*
X890623Y415618D01*
X890498Y415868D01*
X890331Y416077D01*
G01X889664Y417343D02*
X889373Y417635D01*
X889206Y417885D01*
X889123Y418218D01*
X889206Y418510D01*
X889373Y418718D01*
X889623Y418885D01*
X889914Y418927D01*
X890164Y418885D01*
X890414Y418718D01*
X890623Y418468D01*
X890706Y418177D01*
X890623Y417843D01*
X890373Y417552D01*
X889998Y417385D01*
X889581Y417343D01*
X889039Y417427D01*
X888748Y417552D01*
X888456Y417760D01*
X888248Y418052D01*
X888206Y418343D01*
X888289Y418635D01*
X888498Y418843D01*
G01X890706Y421152D02*
X890164Y421235D01*
X889706Y421360D01*
X889289Y421527D01*
X888831Y421735D01*
X888206Y422068D01*
Y420402D01*
G01X890706Y424335D02*
X888206D01*
X888706Y423835D01*
G01X890706D02*
Y424835D01*
G01X860885Y412300D02*
X860635Y412425D01*
X860343Y412508D01*
X860010D01*
X859635Y412383D01*
X859343Y412175D01*
X859135Y411925D01*
X858968Y411508D01*
X858926Y411133D01*
X859010Y410758D01*
X859135Y410508D01*
X859385Y410258D01*
X859676Y410091D01*
X859968Y410008D01*
X860260D01*
X860551Y410091D01*
X860801Y410216D01*
X861010Y410383D01*
G01X862276Y411050D02*
X862568Y411341D01*
X862818Y411508D01*
X863151Y411591D01*
X863443Y411508D01*
X863651Y411341D01*
X863818Y411091D01*
X863860Y410800D01*
X863818Y410550D01*
X863651Y410300D01*
X863401Y410091D01*
X863110Y410008D01*
X862776Y410091D01*
X862485Y410341D01*
X862318Y410716D01*
X862276Y411133D01*
X862360Y411675D01*
X862485Y411966D01*
X862693Y412258D01*
X862985Y412466D01*
X863276Y412508D01*
X863568Y412425D01*
X863776Y412216D01*
G01X866668Y410008D02*
Y412508D01*
X865126Y410716D01*
X867210D01*
G01X868351Y410383D02*
X868601Y410175D01*
X868893Y410050D01*
X869268Y410008D01*
X869643Y410091D01*
X869935Y410258D01*
X870143Y410550D01*
X870185Y410883D01*
X870101Y411216D01*
X869893Y411425D01*
X869601Y411591D01*
X869310Y411633D01*
X869018Y411591D01*
X868643Y411425D01*
X868768Y412508D01*
X869893D01*
G01X905743Y383163D02*
X908243D01*
Y384829D01*
G01X907743Y386179D02*
X908035Y386429D01*
X908201Y386763D01*
X908243Y387138D01*
X908201Y387471D01*
X907993Y387804D01*
X907743Y388013D01*
X907493Y388054D01*
X907201Y387971D01*
X906993Y387679D01*
X906910Y387388D01*
Y387013D01*
G01Y387388D02*
X906785Y387638D01*
X906576Y387846D01*
X906326Y387929D01*
X906076Y387846D01*
X905868Y387638D01*
X905743Y387263D01*
X905785Y386888D01*
X905951Y386513D01*
G01X905743Y390196D02*
X905826Y389863D01*
X906035Y389613D01*
X906285Y389446D01*
X906618Y389321D01*
X906993Y389279D01*
X907368Y389321D01*
X907701Y389446D01*
X907951Y389613D01*
X908160Y389863D01*
X908243Y390196D01*
X908160Y390529D01*
X907951Y390779D01*
X907701Y390946D01*
X907368Y391071D01*
X906993Y391113D01*
X906618Y391071D01*
X906285Y390946D01*
X906035Y390779D01*
X905826Y390529D01*
X905743Y390196D01*
G01X895997Y394857D02*
Y381457D01*
G01X903197Y394857D02*
X895997D01*
G01X903197Y381457D02*
Y394857D01*
G01X895997Y381457D02*
X903197D01*
G01X912754Y372124D02*
X910254D01*
Y373165D01*
X910379Y373499D01*
X910546Y373707D01*
X910879Y373790D01*
X911212Y373707D01*
X911421Y373457D01*
X911546Y373165D01*
Y372124D01*
G01Y373165D02*
X912754Y373790D01*
G01Y376057D02*
X912712Y376349D01*
X912587Y376682D01*
X912379Y376890D01*
X912087Y376974D01*
X911796Y376890D01*
X911546Y376640D01*
X911421Y376265D01*
Y375849D01*
X911337Y375599D01*
X911129Y375390D01*
X910837Y375307D01*
X910546Y375432D01*
X910337Y375724D01*
X910254Y376057D01*
X910337Y376390D01*
X910546Y376682D01*
X910837Y376807D01*
X911129Y376724D01*
X911337Y376515D01*
X911421Y376265D01*
Y375849D01*
X911546Y375474D01*
X911796Y375224D01*
X912087Y375140D01*
X912379Y375224D01*
X912587Y375432D01*
X912712Y375765D01*
X912754Y376057D01*
G01X912254Y378240D02*
X912546Y378490D01*
X912712Y378824D01*
X912754Y379199D01*
X912712Y379532D01*
X912504Y379865D01*
X912254Y380074D01*
X912004Y380115D01*
X911712Y380032D01*
X911504Y379740D01*
X911421Y379449D01*
Y379074D01*
G01Y379449D02*
X911296Y379699D01*
X911087Y379907D01*
X910837Y379990D01*
X910587Y379907D01*
X910379Y379699D01*
X910254Y379324D01*
X910296Y378949D01*
X910462Y378574D01*
G01X912754Y382257D02*
X912712Y382549D01*
X912587Y382882D01*
X912379Y383090D01*
X912087Y383174D01*
X911796Y383090D01*
X911546Y382840D01*
X911421Y382465D01*
Y382049D01*
X911337Y381799D01*
X911129Y381590D01*
X910837Y381507D01*
X910546Y381632D01*
X910337Y381924D01*
X910254Y382257D01*
X910337Y382590D01*
X910546Y382882D01*
X910837Y383007D01*
X911129Y382924D01*
X911337Y382715D01*
X911421Y382465D01*
Y382049D01*
X911546Y381674D01*
X911796Y381424D01*
X912087Y381340D01*
X912379Y381424D01*
X912587Y381632D01*
X912712Y381965D01*
X912754Y382257D01*
G01X880666Y384816D02*
X885866D01*
G01X880666Y377816D02*
X888466D01*
G01X880666Y384816D02*
Y377816D01*
G01X894066Y384816D02*
X885366D01*
G01X894066Y377816D02*
Y384816D01*
G01X887666Y377816D02*
X894066D01*
G01X865792Y403021D02*
Y401229D01*
X865959Y400854D01*
X866292Y400604D01*
X866709Y400521D01*
X867126Y400604D01*
X867459Y400854D01*
X867626Y401229D01*
Y403021D01*
G01X869809Y400521D02*
X870101Y400563D01*
X870434Y400688D01*
X870642Y400896D01*
X870726Y401188D01*
X870642Y401479D01*
X870392Y401729D01*
X870017Y401854D01*
X869601D01*
X869351Y401938D01*
X869142Y402146D01*
X869059Y402438D01*
X869184Y402729D01*
X869476Y402938D01*
X869809Y403021D01*
X870142Y402938D01*
X870434Y402729D01*
X870559Y402438D01*
X870476Y402146D01*
X870267Y401938D01*
X870017Y401854D01*
X869601D01*
X869226Y401729D01*
X868976Y401479D01*
X868892Y401188D01*
X868976Y400896D01*
X869184Y400688D01*
X869517Y400563D01*
X869809Y400521D01*
G01X872909D02*
Y403021D01*
X872409Y402521D01*
G01Y400521D02*
X873409D01*
G01X880114Y392249D02*
Y397249D01*
X875114D01*
G01Y369549D02*
X880114D01*
Y374549D01*
G01X860208Y396242D02*
Y399242D01*
G01X870051Y396242D02*
Y398242D01*
G01X873988Y370556D02*
Y367556D01*
G01X864145Y370556D02*
Y368556D01*
M02*
